P  JOB   E:/<user>/brd/0417/9332_F0TG_MB_C_V02_0417_0820.brd                       
P  CODE  00                                                                     
P  UNITS CUST 0                                                                 
P  TITLE E:/<user>/brd/0417/9332_F0TG_MB_C_V02_0417_0820.brd                       
P  NUM   001                                                                    
P  REV   A                                                                      
P  VER IPC-D-356A                                                               
C                                                                               
C  IPC-D-356 Ouptut File from Allegro                                           
C  IPC File Date: Wed Apr 19 14:45:09 2023                                      
C                                                                               
C                                                                               
C  Board File:             9332_F0TG_MB_C_V02_0417_0820.brd                     
C  Design Rule Status:     OUT OF DATE                                          
C  Unit of Measure:        mils                                                 
C  Decimal Place Accuracy: 2                                                    
C  Number of etch Layers:  18                                                   
C  Board Thickness(mils):  95.000000                                            
C  Drawing Extents(mils):  -500000  -997638  7500000  7002362                   
C                                                                               
C                                                                               
C  BOARD LAYER INFORMATION                                                      
C                                                                               
C     Layer      Layer            Layer             Film  Layer                 
C     Name       Material         Type              Type  Number                
C  ---------------------------------------------------------                    
C  TOP           COPPER           CONDUCTOR         POS     1                   
C  GND           COPPER           PLANE             NEG     2                   
C  IN1           COPPER           CONDUCTOR         POS     3                   
C  GND1          COPPER           PLANE             NEG     4                   
C  IN2           COPPER           CONDUCTOR         POS     5                   
C  GND2          COPPER           PLANE             NEG     6                   
C  IN3           COPPER           CONDUCTOR         POS     7                   
C  GND3          COPPER           PLANE             NEG     8                   
C  VCC           COPPER           PLANE             NEG     9                   
C  VCC1          COPPER           PLANE             NEG    10                   
C  GND4          COPPER           PLANE             NEG    11                   
C  IN4           COPPER           CONDUCTOR         POS    12                   
C  GND5          COPPER           PLANE             NEG    13                   
C  IN5           COPPER           CONDUCTOR         POS    14                   
C  GND6          COPPER           PLANE             NEG    15                   
C  IN6           COPPER           CONDUCTOR         POS    16                   
C  GND7          COPPER           PLANE             NEG    17                   
C  BOTTOM        COPPER           CONDUCTOR         POS    18                   
C                                                                               
C                                                                               
C  PADSTACK INFORMATION                                                         
C                                                                               
C     Padstack          First     Last                                          
C     Name              Layer     Layer     Width     Height                    
C  ---------------------------------------------------------                    
C  SMD12X20_NPM         TOP       TOP            1600      2400                 
C  C41D41N              TOP       BOTTOM         7100      7100                 
C  SMD85X115            TOP       TOP            8900     11900                 
C  SMD85X152-8_CUT_NPM  TOP       TOP            8900     15680                 
C  SMD97X97_CUT         TOP       TOP           10046     10046                 
C  VIA16D8A24_BGA_GND3- TOP       BOTTOM         2400      2400                 
C  VIA16D8A24_BGA_GND3- TOP       BOTTOM         2400      2400                 
C  OB200X255D200X255N   TOP       BOTTOM        23000     28500                 
C  VIA16D8A24_BGA       TOP       BOTTOM         2400      2400                 
C  RE-R_0824-2          TOP       TOP            2384      2368                 
C  RE-L_0824-2          TOP       TOP            2384      2368                 
C  SMD7X10_M            TOP       TOP             700      1000                 
C  SMD26X54             TOP       TOP            3000      5800                 
C  SMD24X42_PM22X40     TOP       TOP            2800      4600                 
C  SMD24X42             TOP       TOP            2800      4600                 
C  SMD124X124           TOP       TOP           12800     12800                 
C  SMD16X54_PM12X50     TOP       TOP            2000      5800                 
C  SMD24X54_PM20X50     TOP       TOP            2800      5800                 
C  SMD138X138           TOP       TOP           14200     14200                 
C  SMD130X169-2         TOP       TOP           13400     17320                 
C  VIA18D10A28_BGA      TOP       BOTTOM         2800      2800                 
C  VIA16D8A26_BGA       TOP       BOTTOM         2600      2600                 
C  SMD63X138            TOP       TOP            6700     14200                 
C  SMD32X40             TOP       TOP            3600      4400                 
C  SMDC12_SM15          TOP       TOP            1500      1500                 
C  SMDC15               TOP       TOP            1900      1900                 
C  SMDOB10X13           TOP       TOP            1400      1700                 
C  SMDC12               TOP       TOP            1600      1600                 
C  SMD26X38             TOP       TOP            3000      4200                 
C  SMD18X52             TOP       TOP            2200      5600                 
C  C291D120N_V160_ANT29 TOP       BOTTOM        29500     29500                 
C  C65-74D40-15_FIT     TOP       BOTTOM         6974      6974                 
C  S65-74D40-15_FIT     TOP       BOTTOM         6974      6974                 
C  GHC36D22_NTH         TOP       BOTTOM         4200      4200                 
C  C315D166_NPB         TOP       BOTTOM        31900     31900                 
C  C122D122N            TOP       BOTTOM        15200     15200                 
C  C394D221_NPB         TOP       BOTTOM        39800     39800                 
C  SMD237X237_PM221X221 TOP       TOP           24022     24022                 
C  SMD0-24X0-6_CUT      TOP       TOP            1344      2762                 
C  SMD77X158            TOP       TOP            8100     16200                 
C  SMD48X56             TOP       TOP            5200      6000                 
C  SMD7X52              TOP       TOP            1100      5600                 
C  SMD205X205           TOP       TOP           20900     20900                 
C  SMD7X40              TOP       TOP            1100      4400                 
C  C30D30N_T3-14_0      TOP       BOTTOM         6000      6000                 
C  SMD56X231_PM35X231IX TOP       TOP            5912     23432                 
C  SMD56X231_PM35X231IX TOP       TOP            5912     23432                 
C  SMD24X65_PM20X60_IY2 TOP       TOP            2800      6900                 
C  SMD10X20             TOP       TOP            1400      2400                 
C  SMD126X270           TOP       TOP           13000     27400                 
C  SMD17X59             TOP       TOP            2100      6300                 
C  SMD103X103_PM99X99_C TOP       TOP           10636     10636                 
C  SMD10X24_CUT         TOP       TOP            1384      2762                 
C  SMD40X63             TOP       TOP            4400      6700                 
C  SMD16X44             TOP       TOP            2000      4800                 
C  SMD60X126_CUT        TOP       TOP           12998      6306                 
C  SMD16X36_PM14X34     TOP       TOP            2000      4000                 
C  C178D150B315I221_NPT TOP       BOTTOM        31900     31900                 
C  OB252X315D126X189B25 TOP       BOTTOM        25600     31900                 
C  R166X197D79B158_IX3- TOP       BOTTOM        17000     20100                 
C  C125D125N_T2-0       TOP       BOTTOM        15500     15500                 
C  C217D217N            TOP       BOTTOM        24700     24700                 
C  C125D125N            TOP       BOTTOM        15500     15500                 
C  C256D125N_V165_ANT25 TOP       BOTTOM        26000     26000                 
C  SMD15X63             TOP       TOP            1900      6700                 
C  SMD12X49             TOP       TOP            1600      5300                 
C  SMD24X28             TOP       TOP            2800      3200                 
C  C244D147I218_NPB     TOP       BOTTOM        24800     24800                 
C  SMD12X63_PM10X61     TOP       TOP            1600      6700                 
C  R40X15               TOP       TOP            4400      1900                 
C  C394D394N            TOP       BOTTOM        42400     42400                 
C  GHC30D22_NTH         TOP       BOTTOM         4200      4200                 
C  SMD36X40             TOP       TOP            4000      4400                 
C  SMD115X138           TOP       TOP           11900     14200                 
C  SMD48X126            TOP       TOP            5200     13000                 
C  SMD7X24_CUT_R        TOP       TOP            1100      2800                 
C  SMD7X24_CUT          TOP       TOP            1100      2800                 
C  SMD7X24_CUT_L        TOP       TOP            1100      2800                 
C  SH4-6X4-7_PM4-3X4-41 TOP       TOP           18904     18510                 
C  SMD28X46_PM24X42     TOP       TOP            3200      5000                 
C  SMD35X50             TOP       TOP            3900      5400                 
C  SMD14X56             TOP       TOP            1800      6000                 
C  SMD24X52             TOP       TOP            2800      5600                 
C  SMD67X67             TOP       TOP            7100      7100                 
C  SMD140X140           TOP       TOP           14400     14400                 
C  SMD10X29             TOP       TOP            1400      3300                 
C  VIA18D8A26_BGA       TOP       BOTTOM         2600      2600                 
C  VT18D10B18A26_BGA    TOP       BOTTOM         7502      7500                 
C  VIA18D10A26_BGA      TOP       BOTTOM         2600      2600                 
C  C85D67_SM85_NPM      TOP       BOTTOM         9700      9700                 
C  TC785CC25_O          TOP       BOTTOM         8700      8700                 
C  TC395CC25_O          TOP       BOTTOM         4800      4800                 
C  VT20D10B20           TOP       BOTTOM         7502      7500                 
C  VIA19-3D10           TOP       BOTTOM         3000      3000                 
C  TP_R16X4-1R16X8-1    TOP       TOP           12000     12000                 
C  TP_R16X4-1R16X8-1B   BOTTOM    BOTTOM        12000     12000                 
C  VIA19D10             TOP       BOTTOM         3000      3000                 
C  VIA19D10A26_BGA      TOP       BOTTOM         2600      2600                 
C  SMD12X15             TOP       TOP            1600      1900                 
C  SH10X28_CUT_R        TOP       TOP            1384      3156                 
C  SMD10X52             TOP       TOP            1400      5600                 
C  SMD10X36             TOP       TOP            1400      4000                 
C  SH10X28_CUT_L        TOP       TOP            1384      3156                 
C  SMD95X130            TOP       TOP            9900     13400                 
C  TP26T                TOP       TOP            7502      7500                 
C  SMD30X50             TOP       TOP            3400      5400                 
C  SMD186X189           TOP       TOP           19000     19300                 
C  SMD50X56             TOP       TOP            5400      6000                 
C  SMD14X63_PM12X61     TOP       TOP            1800      6700                 
C  SMD8X36_PM8X32_IY-1- TOP       TOP            1188      3944                 
C  SMD7X31              TOP       TOP            1100      3500                 
C  SMD14X52             TOP       TOP            1800      5600                 
C  SMD30X95             TOP       TOP            3400      9900                 
C  SMD49X110            TOP       TOP            5300     11400                 
C  C65D65N              TOP       BOTTOM         9500      9500                 
C  C46D46N              TOP       BOTTOM         7600      7600                 
C  SMD11X63             TOP       TOP            1500      6700                 
C  OB64X137D44X97_T1-96 TOP       BOTTOM         7400     14100                 
C  SMD15X50             TOP       TOP            1900      5400                 
C  OB68X137D48X97_T2    TOP       BOTTOM         7800     14100                 
C  SMD20-47X59          TOP       TOP            2447      6300                 
C  SMD34X96             TOP       TOP            3800     10000                 
C  SMD15X57             TOP       TOP            1900      6100                 
C  C44D44N_T1-96        TOP       BOTTOM         7400      7400                 
C  SMD24X32             TOP       TOP            2800      3600                 
C  SMD67X99             TOP       TOP            7100     10300                 
C  SMD7X24              TOP       TOP            1100      2800                 
C  SMD144X144           TOP       TOP           14800     14800                 
C  SMD7X26              TOP       TOP            1100      3000                 
C  SMD174X174           TOP       TOP           17800     17800                 
C  SMD48X59             TOP       TOP            5200      6300                 
C  SMD32X32             TOP       TOP            3600      3600                 
C  SMD130X166           TOP       TOP           13400     17000                 
C  SMD65X103            TOP       TOP            6900     10700                 
C  SMD130X130           TOP       TOP           13400     13400                 
C  SMD44X54             TOP       TOP            4800      5800                 
C  SMD84-8X130          TOP       TOP            8880     13400                 
C  SMD42X99             TOP       TOP            4600     10300                 
C  SMD128X197           TOP       TOP           13200     20100                 
C  SMD79X166            TOP       TOP            8300     17000                 
C  SMD95X178XA          TOP       TOP            9900     18200                 
C  SMD54X178            TOP       TOP            5800     18200                 
C  SMD128X135           TOP       TOP           13200     13900                 
C  SMD40X71             TOP       TOP            4400      7500                 
C  SMD40X50             TOP       TOP            4400      5400                 
C  SMD28X32             TOP       TOP            3200      3600                 
C  OC20X4R              TOP       TOP            1640      1640                 
C  SMD18X20             TOP       TOP            2200      2400                 
C  C60D40               TOP       BOTTOM         7000      7000                 
C  S60D40               TOP       BOTTOM         7000      7000                 
C  SMD63X119            TOP       TOP            6700     12300                 
C  SMD95X111            TOP       TOP            9900     11500                 
C  SMD7X28              TOP       TOP            1100      3200                 
C  SMD13X25             TOP       TOP            1700      2900                 
C  SMD10X21             TOP       TOP            1400      2500                 
C  SMD12X21             TOP       TOP            1600      2500                 
C  SMD24X46             TOP       TOP            2800      5000                 
C  SMD17X46             TOP       TOP            2100      5000                 
C  SMD28X36             TOP       TOP            3200      4000                 
C  SMD184X209_SM184X209 TOP       TOP           18406     20866                 
C  SMD12X20             TOP       TOP            1600      2400                 
C  SMD11X23             TOP       TOP            1500      2700                 
C  SMD11X24             TOP       TOP            1500      2800                 
C  SMD24X150_SM24X150_C TOP       TOP            2362     14960                 
C  SMD68X91_SM68X91_CUT TOP       TOP            6788      9054                 
C  SMD22X53             TOP       TOP            2600      5700                 
C  SMD14X44             TOP       TOP            1800      4800                 
C  SH32X124_SM32X124_CU TOP       TOP            3150     12402                 
C  SMD12X79             TOP       TOP            1600      8300                 
C  SH0-3X0-9_CUT        TOP       TOP            3944      1582                 
C  SMD12X32             TOP       TOP            1600      3600                 
C  SMD7X32              TOP       TOP            1100      3600                 
C  SMD10X15             TOP       TOP            1400      1900                 
C  SMD10X14             TOP       TOP            1400      1800                 
C  SMD46X63             TOP       TOP            5000      6700                 
C  SMD134X134           TOP       TOP           13800     13800                 
C  SMD9X15              TOP       TOP            1300      1900                 
C  SMD37X50_CUT         TOP       TOP            4042      5322                 
C  SMD10X50             TOP       TOP            1400      5400                 
C  SMD10X32             TOP       TOP            1400      3600                 
C  SMD10X34_CUT         TOP       TOP            1384      3746                 
C  SMD30X36_CUT         TOP       TOP            3352      3944                 
C  SMD30X36_CUT_R       TOP       TOP            3352      3944                 
C  SMD10X28             TOP       TOP            1400      3200                 
C  SMD40X56             TOP       TOP            4400      6000                 
C  SMD40X48             TOP       TOP            4400      5200                 
C  SMD32X36             TOP       TOP            3600      4000                 
C  SMD17X20             TOP       TOP            2100      2400                 
C  SMDC9_SM9            TOP       TOP             900       900                 
C  SMD25X48             TOP       TOP            2900      5200                 
C  SMDC16               TOP       TOP            2000      2000                 
C  SMD12X18             TOP       TOP            1600      2200                 
C  SMD24X170            TOP       TOP            2800     17400                 
C  SMD81X91             TOP       TOP            8500      9500                 
C  SMD69X77             TOP       TOP            7300      8100                 
C  SMD83X213_CUT        TOP       TOP            8668     21660                 
C  SMD9X24              TOP       TOP            1300      2800                 
C  SMD59X59_CUT         TOP       TOP            6306      6306                 
C  C158D158N            TOP       BOTTOM        18800     18800                 
C  SMDC0-45_SM0-55      TOP       TOP            2165      2165                 
C  SMD52X56             TOP       TOP            5600      6000                 
C  C66D46               TOP       BOTTOM         7600      7600                 
C  S66D46               TOP       BOTTOM         7600      7600                 
C  C64D44_T1-96         TOP       BOTTOM         7400      7400                 
C  C45D45N_T1-96        TOP       BOTTOM         7500      7500                 
C  C48D32_T3-93_0       TOP       BOTTOM         6200      6200                 
C  S48D32_T3-93_0       TOP       BOTTOM         6200      6200                 
C  C61D41               TOP       BOTTOM         7100      7100                 
C  S61D41               TOP       BOTTOM         7100      7100                 
C  C60D40_T1-96         TOP       BOTTOM         7000      7000                 
C  S64D44_T1-96         TOP       BOTTOM         7400      7400                 
C  S30-17D14-17_T1-96_F TOP       BOTTOM         3417      3417                 
C  C30-17D14-17_T1-96_F TOP       BOTTOM         3417      3417                 
C  C35-68D19-68_T1-96_F TOP       BOTTOM         3968      3968                 
C  SMD10X22             TOP       TOP            1400      2600                 
C  SMD16X20             TOP       TOP            2000      2400                 
C  SMD20X34             TOP       TOP            2400      3800                 
C  SMD16X34             TOP       TOP            2000      3800                 
C  SMD14X49             TOP       TOP            1800      5300                 
C  SMD17X24             TOP       TOP            2100      2800                 
C  SMD22X32             TOP       TOP            2600      3600                 
C  SMD22X32_PM18X28     TOP       TOP            2600      3600                 
C  SMD24X54             TOP       TOP            2800      5800                 
C  SMD16X54             TOP       TOP            2000      5800                 
C  SMD14X59             TOP       TOP            1800      6300                 
C  VT20D10T30           TOP       BOTTOM         7502      7500                 
C  VT20D10B26           TOP       BOTTOM         7502      7500                 
C  VIA20D10             TOP       BOTTOM         3000      3000                 
C  SPD_C125                                     12500     12500                 
C  SMDC39M118           TOP       TOP           11800     11800                 
C  TP26B                BOTTOM    BOTTOM         7500      7500                 
C  TP30T                TOP       TOP            7500      7500                 
C                                                                               
C                                                                               
C  ****************************************                                     
C     Name mapping for long Signal names                                        
C  ****************************************                                     
C                                                                               
P  NNAMEm0000 OCP_V3_2_P3V3_R3_PWRGD                                            
P  NNAMEm0001 OCP_V3_1_P3V3_R3_PWRGD                                            
P  NNAMEm0002 HP_LVC3_OCP_V3_2_PWRGD_R2                                         
P  NNAMEm0003 HP_LVC3_OCP_V3_2_P12V_PWRGD_R2                                    
P  NNAMEm0004 HP_LVC3_OCP_V3_1_PWRGD_R2                                         
P  NNAMEm0005 HP_LVC3_OCP_V3_1_P12V_R2_PWRGD                                    
P  NNAMEm0006 P3V3_AUX_DSC_VOL                                                  
P  NNAMEm0007 P3V3_AUX_DSC_S1                                                   
P  NNAMEm0008 P3V3_AUX_DSC_G2                                                   
P  NNAMEm0009 P3V3_AUX_DSC_G1                                                   
P  NNAMEm0010 P12V_AUX_DSC_VOL                                                  
P  NNAMEm0011 P12V_AUX_DSC_S1                                                   
P  NNAMEm0012 P12V_AUX_DSC_G2                                                   
P  NNAMEm0013 P12V_AUX_DSC_G1                                                   
P  NNAMEm0014 I3C_SPD_DDRL_CPU1_SDA                                             
P  NNAMEm0015 I3C_SPD_DDRL_CPU0_SDA                                             
P  NNAMEm0016 I3C_SPD_DDRK_CPU1_SDA                                             
P  NNAMEm0017 I3C_SPD_DDRK_CPU0_SDA                                             
P  NNAMEm0018 I3C_SPD_DDRJ_CPU1_SDA                                             
P  NNAMEm0019 I3C_SPD_DDRJ_CPU0_SDA                                             
P  NNAMEm0020 I3C_SPD_DDRI_CPU1_SDA                                             
P  NNAMEm0021 I3C_SPD_DDRI_CPU0_SDA                                             
P  NNAMEm0022 I3C_SPD_DDRH_CPU1_SDA                                             
P  NNAMEm0023 I3C_SPD_DDRH_CPU0_SDA                                             
P  NNAMEm0024 I3C_SPD_DDRG_CPU1_SDA                                             
P  NNAMEm0025 I3C_SPD_DDRG_CPU0_SDA                                             
P  NNAMEm0026 I3C_SPD_DDRF_CPU1_SDA                                             
P  NNAMEm0027 I3C_SPD_DDRF_CPU0_SDA                                             
P  NNAMEm0028 I3C_SPD_DDRE_CPU1_SDA                                             
P  NNAMEm0029 I3C_SPD_DDRE_CPU0_SDA                                             
P  NNAMEm0030 I3C_SPD_DDRD_CPU1_SDA                                             
P  NNAMEm0031 I3C_SPD_DDRD_CPU0_SDA                                             
P  NNAMEm0032 I3C_SPD_DDRC_CPU1_SDA                                             
P  NNAMEm0033 I3C_SPD_DDRC_CPU0_SDA                                             
P  NNAMEm0034 I3C_SPD_DDRB_CPU1_SDA                                             
P  NNAMEm0035 I3C_SPD_DDRB_CPU0_SDA                                             
P  NNAMEm0036 I3C_SPD_DDRA_CPU1_SDA                                             
P  NNAMEm0037 I3C_SPD_DDRA_CPU0_SDA                                             
P  NNAMEm0038 SMB_MUX_RT_R2_SDA                                                 
P  NNAMEm0039 SMB_MUX_RT_R2_SCL                                                 
P  NNAMEm0040 SMB_HOST_CLK_3V3AUX_SDA_R1                                        
P  NNAMEm0041 SMB_HOST_CLK_3V3AUX_SCL_R1                                        
P  NNAMEm0042 RXDET_BYP_RT_CPU1_P3                                              
P  NNAMEm0043 RXDET_BYP_RT_CPU1_P2                                              
P  NNAMEm0044 RXDET_BYP_RT_CPU1_P1                                              
P  NNAMEm0045 RXDET_BYP_RT_CPU1_P0                                              
P  NNAMEm0046 RXDET_BYP_RT_CPU0_P3                                              
P  NNAMEm0047 RXDET_BYP_RT_CPU0_P2                                              
P  NNAMEm0048 RXDET_BYP_RT_CPU0_P1                                              
P  NNAMEm0049 RXDET_BYP_RT_CPU0_P0                                              
P  NNAMEm0050 P3V3_ADC128_2_VCC                                                 
P  NNAMEm0051 JTAG_TRST_RT_CPU1_P3_N                                            
P  NNAMEm0052 JTAG_TRST_RT_CPU1_P2_N                                            
P  NNAMEm0053 JTAG_TRST_RT_CPU1_P1_N                                            
P  NNAMEm0054 JTAG_TRST_RT_CPU1_P0_N                                            
P  NNAMEm0055 JTAG_TRST_RT_CPU0_P3_N                                            
P  NNAMEm0056 JTAG_TRST_RT_CPU0_P2_N                                            
P  NNAMEm0057 JTAG_TRST_RT_CPU0_P1_N                                            
P  NNAMEm0058 JTAG_TRST_RT_CPU0_P0_N                                            
P  NNAMEm0059 JTAG_TMS_RT_CPU1_P3                                               
P  NNAMEm0060 JTAG_TMS_RT_CPU1_P2                                               
P  NNAMEm0061 JTAG_TMS_RT_CPU1_P1                                               
P  NNAMEm0062 JTAG_TMS_RT_CPU1_P0                                               
P  NNAMEm0063 JTAG_TMS_RT_CPU0_P3                                               
P  NNAMEm0064 JTAG_TMS_RT_CPU0_P2                                               
P  NNAMEm0065 JTAG_TMS_RT_CPU0_P1                                               
P  NNAMEm0066 JTAG_TMS_RT_CPU0_P0                                               
P  NNAMEm0067 JTAG_TDO_RT_CPU1_P3                                               
P  NNAMEm0068 JTAG_TDO_RT_CPU1_P2                                               
P  NNAMEm0069 JTAG_TDO_RT_CPU1_P1                                               
P  NNAMEm0070 JTAG_TDO_RT_CPU1_P0                                               
P  NNAMEm0071 JTAG_TDO_RT_CPU0_P3                                               
P  NNAMEm0072 JTAG_TDO_RT_CPU0_P2                                               
P  NNAMEm0073 JTAG_TDO_RT_CPU0_P1                                               
P  NNAMEm0074 JTAG_TDO_RT_CPU0_P0                                               
P  NNAMEm0075 JTAG_TDI_RT_CPU1_P3                                               
P  NNAMEm0076 JTAG_TDI_RT_CPU1_P2                                               
P  NNAMEm0077 JTAG_TDI_RT_CPU1_P1                                               
P  NNAMEm0078 JTAG_TDI_RT_CPU1_P0                                               
P  NNAMEm0079 JTAG_TDI_RT_CPU0_P3                                               
P  NNAMEm0080 JTAG_TDI_RT_CPU0_P2                                               
P  NNAMEm0081 JTAG_TDI_RT_CPU0_P1                                               
P  NNAMEm0082 JTAG_TDI_RT_CPU0_P0                                               
P  NNAMEm0083 JTAG_TCK_RT_CPU1_P3                                               
P  NNAMEm0084 JTAG_TCK_RT_CPU1_P2                                               
P  NNAMEm0085 JTAG_TCK_RT_CPU1_P1                                               
P  NNAMEm0086 JTAG_TCK_RT_CPU1_P0                                               
P  NNAMEm0087 JTAG_TCK_RT_CPU0_P3                                               
P  NNAMEm0088 JTAG_TCK_RT_CPU0_P2                                               
P  NNAMEm0089 JTAG_TCK_RT_CPU0_P1                                               
P  NNAMEm0090 JTAG_TCK_RT_CPU0_P0                                               
P  NNAMEm0091 CLKREQ_RT_CPU1_P3_N                                               
P  NNAMEm0092 CLKREQ_RT_CPU1_P2_N                                               
P  NNAMEm0093 CLKREQ_RT_CPU1_P1_N                                               
P  NNAMEm0094 CLKREQ_RT_CPU1_P0_N                                               
P  NNAMEm0095 CLKREQ_RT_CPU0_P3_N                                               
P  NNAMEm0096 CLKREQ_RT_CPU0_P2_N                                               
P  NNAMEm0097 CLKREQ_RT_CPU0_P1_N                                               
P  NNAMEm0098 CLKREQ_RT_CPU0_P0_N                                               
P  NNAMEm0099 OCP_V3_2_P3V3_P12V_ADC_R_ALERT                                    
P  NNAMEm0100 OCP_V3_2_P3V3_P12V_ADC_ALERT                                      
P  NNAMEm0101 OCP_SFF_P3V3_P12V_ADC_R_ALERT                                     
P  NNAMEm0102 OCP_SFF_P3V3_P12V_ADC_ALERT                                       
P  NNAMEm0103 E1S_0_P3V3_P12V_ADC_R_ALERT                                       
P  NNAMEm0104 E1S_0_P3V3_P12V_ADC_ALERT                                         
P  NNAMEm0105 VSENSE_P12V_INA230_8_INP                                          
P  NNAMEm0106 VSENSE_P12V_INA230_8_INN                                          
P  NNAMEm0107 VSENSE_P12V_INA230_7_INP                                          
P  NNAMEm0108 VSENSE_P12V_INA230_7_INN                                          
P  NNAMEm0109 VSENSE_P12V_INA230_6_INP                                          
P  NNAMEm0110 VSENSE_P12V_INA230_6_INN                                          
P  NNAMEm0111 TP_ADC128_2_INT                                                   
P  NNAMEm0112 SMB_SEN_TIC_2_3V3AUX_SDA                                          
P  NNAMEm0113 SMB_SEN_TIC_2_3V3AUX_SCL                                          
P  NNAMEm0114 SMB_SEN_MAM_2_3V3AUX_SDA                                          
P  NNAMEm0115 SMB_SEN_MAM_2_3V3AUX_SCL                                          
P  NNAMEm0116 SMB_RT_CPU1_P3_ROM_MUX_2D_SDA                                     
P  NNAMEm0117 SMB_RT_CPU1_P3_ROM_MUX_2D_SCL                                     
P  NNAMEm0118 SMB_RT_CPU1_P3_ROM_MUX_1D_SDA                                     
P  NNAMEm0119 SMB_RT_CPU1_P3_ROM_MUX_1D_SCL                                     
P  NNAMEm0120 SMB_RT_CPU1_P2_ROM_MUX_2D_SDA                                     
P  NNAMEm0121 SMB_RT_CPU1_P2_ROM_MUX_2D_SCL                                     
P  NNAMEm0122 SMB_RT_CPU1_P2_ROM_MUX_1D_SDA                                     
P  NNAMEm0123 SMB_RT_CPU1_P2_ROM_MUX_1D_SCL                                     
P  NNAMEm0124 SMB_RT_CPU1_P1_ROM_MUX_2D_SDA                                     
P  NNAMEm0125 SMB_RT_CPU1_P1_ROM_MUX_2D_SCL                                     
P  NNAMEm0126 SMB_RT_CPU1_P1_ROM_MUX_1D_SDA                                     
P  NNAMEm0127 SMB_RT_CPU1_P1_ROM_MUX_1D_SCL                                     
P  NNAMEm0128 SMB_RT_CPU1_P0_ROM_MUX_2D_SDA                                     
P  NNAMEm0129 SMB_RT_CPU1_P0_ROM_MUX_2D_SCL                                     
P  NNAMEm0130 SMB_RT_CPU1_P0_ROM_MUX_1D_SDA                                     
P  NNAMEm0131 SMB_RT_CPU1_P0_ROM_MUX_1D_SCL                                     
P  NNAMEm0132 SMB_RT_CPU0_P3_ROM_MUX_2D_SDA                                     
P  NNAMEm0133 SMB_RT_CPU0_P3_ROM_MUX_2D_SCL                                     
P  NNAMEm0134 SMB_RT_CPU0_P3_ROM_MUX_1D_SDA                                     
P  NNAMEm0135 SMB_RT_CPU0_P3_ROM_MUX_1D_SCL                                     
P  NNAMEm0136 SMB_RT_CPU0_P2_ROM_MUX_2D_SDA                                     
P  NNAMEm0137 SMB_RT_CPU0_P2_ROM_MUX_2D_SCL                                     
P  NNAMEm0138 SMB_RT_CPU0_P2_ROM_MUX_1D_SDA                                     
P  NNAMEm0139 SMB_RT_CPU0_P2_ROM_MUX_1D_SCL                                     
P  NNAMEm0140 SMB_RT_CPU0_P1_ROM_MUX_2D_SDA                                     
P  NNAMEm0141 SMB_RT_CPU0_P1_ROM_MUX_2D_SCL                                     
P  NNAMEm0142 SMB_RT_CPU0_P1_ROM_MUX_1D_SDA                                     
P  NNAMEm0143 SMB_RT_CPU0_P1_ROM_MUX_1D_SCL                                     
P  NNAMEm0144 SMB_RT_CPU0_P0_ROM_MUX_2D_SDA                                     
P  NNAMEm0145 SMB_RT_CPU0_P0_ROM_MUX_2D_SCL                                     
P  NNAMEm0146 SMB_RT_CPU0_P0_ROM_MUX_1D_SDA                                     
P  NNAMEm0147 SMB_RT_CPU0_P0_ROM_MUX_1D_SCL                                     
P  NNAMEm0148 SMB_INA230_8_3V3AUX_SDA_R1                                        
P  NNAMEm0149 SMB_INA230_8_3V3AUX_SDA_R                                         
P  NNAMEm0150 SMB_INA230_8_3V3AUX_SCL_R1                                        
P  NNAMEm0151 SMB_INA230_8_3V3AUX_SCL_R                                         
P  NNAMEm0152 SMB_INA230_7_3V3AUX_SDA_R1                                        
P  NNAMEm0153 SMB_INA230_7_3V3AUX_SDA_R                                         
P  NNAMEm0154 SMB_INA230_7_3V3AUX_SCL_R1                                        
P  NNAMEm0155 SMB_INA230_7_3V3AUX_SCL_R                                         
P  NNAMEm0156 SMB_INA230_6_3V3AUX_SDA_R1                                        
P  NNAMEm0157 SMB_INA230_6_3V3AUX_SDA_R                                         
P  NNAMEm0158 SMB_INA230_6_3V3AUX_SCL_R1                                        
P  NNAMEm0159 SMB_INA230_6_3V3AUX_SCL_R                                         
P  NNAMEm0160 RT_ROM_MUX8_OE_N                                                  
P  NNAMEm0161 RT_ROM_MUX7_OE_N                                                  
P  NNAMEm0162 RT_ROM_MUX6_OE_N                                                  
P  NNAMEm0163 RT_ROM_MUX5_OE_N                                                  
P  NNAMEm0164 RT_ROM_MUX4_OE_N                                                  
P  NNAMEm0165 RT_ROM_MUX3_OE_N                                                  
P  NNAMEm0166 RT_ROM_MUX2_OE_N                                                  
P  NNAMEm0167 RT_ROM_MUX1_OE_N                                                  
P  NNAMEm0168 RST_PERST_OCP_V3_2_R_N                                            
P  NNAMEm0169 RST_PERST_OCP_V3_2_BUF_R_N                                        
P  NNAMEm0170 RST_PERST_OCP_V3_2_BUF_N                                          
P  NNAMEm0171 RST_PERST_OCP_SFF_R_N                                             
P  NNAMEm0172 RST_PERST_OCP_SFF_BUF_R_N                                         
P  NNAMEm0173 RST_PERST_OCP_SFF_BUF_N                                           
P  NNAMEm0174 PVDD_33_S5_ADC_TIC                                                
P  NNAMEm0175 PVDD_33_S5_ADC_MAM                                                
P  NNAMEm0176 PVDD18_S5_P1_ADC_TIC                                              
P  NNAMEm0177 PVDD18_S5_P1_ADC_MAM                                              
P  NNAMEm0178 PVDD18_S5_P1_ADC                                                  
P  NNAMEm0179 PVDD18_S5_P0_ADC_TIC                                              
P  NNAMEm0180 PVDD18_S5_P0_ADC_MAM                                              
P  NNAMEm0181 PVDD18_S5_P0_ADC                                                  
P  NNAMEm0182 P5V_AUX_ADC_TIC                                                   
P  NNAMEm0183 P5V_AUX_ADC_MAM                                                   
P  NNAMEm0184 P3V3_MAX11617_2_VDD                                               
P  NNAMEm0185 P1V8_CPU1_RT_1D_ADC_TIC                                           
P  NNAMEm0186 P1V8_CPU1_RT_1D_ADC_MAM                                           
P  NNAMEm0187 P1V8_CPU1_RT_1D_ADC                                               
P  NNAMEm0188 P1V8_CPU0_RT_1D_ADC_TIC                                           
P  NNAMEm0189 P1V8_CPU0_RT_1D_ADC_MAM                                           
P  NNAMEm0190 P1V8_CPU0_RT_1D_ADC                                               
P  NNAMEm0191 P1V8_AUX_ADC_TIC                                                  
P  NNAMEm0192 P1V8_AUX_ADC_MAM                                                  
P  NNAMEm0193 P1V2_AUX_ADC_TIC                                                  
P  NNAMEm0194 P1V2_AUX_ADC_MAM                                                  
P  NNAMEm0195 P12V_OCP_V3_2_R                                                   
P  NNAMEm0196 P12V_OCP_V3_2_PLD_R_PWRGD                                         
P  NNAMEm0197 P12V_OCP_V3_2_PLD_PWRGD                                           
P  NNAMEm0198 P12V_OCP_V3_2_EN_R3                                               
P  NNAMEm0199 P12V_OCP_V3_2_BUF_EN_R                                            
P  NNAMEm0200 P12V_OCP_V3_2_BUF_EN                                              
P  NNAMEm0201 P12V_OCP_V3_2_ADC_ALERT_R                                         
P  NNAMEm0202 P12V_OCP_V3_1_PLD_R_PWRGD                                         
P  NNAMEm0203 P12V_OCP_V3_1_PLD_PWRGD                                           
P  NNAMEm0204 P12V_OCP_SFF_EN_R3                                                
P  NNAMEm0205 P12V_OCP_SFF_BUF_EN_R                                             
P  NNAMEm0206 P12V_OCP_SFF_BUF_EN                                               
P  NNAMEm0207 P12V_OCP_SFF_ADC_ALERT_R                                          
P  NNAMEm0208 P12V_E1S_0_ADC_ALERT_R                                            
P  NNAMEm0209 OCP_V3_2_P3V3_R2_PWRGD                                            
P  NNAMEm0210 OCP_V3_2_P3V3_PLD_R_PWRGD                                         
P  NNAMEm0211 OCP_V3_2_P3V3_PLD_PWRGD                                           
P  NNAMEm0212 OCP_V3_2_AUX_PWR_EN_R2                                            
P  NNAMEm0213 OCP_V3_1_P3V3_R2_PWRGD                                            
P  NNAMEm0214 OCP_V3_1_P3V3_PLD_R_PWRGD                                         
P  NNAMEm0215 OCP_V3_1_P3V3_PLD_PWRGD                                           
P  NNAMEm0216 OCP_SFF_AUX_PWR_EN_R3                                             
P  NNAMEm0217 NC_INA230_8_NC5                                                   
P  NNAMEm0218 NC_INA230_8_NC4                                                   
P  NNAMEm0219 NC_INA230_8_NC3                                                   
P  NNAMEm0220 NC_INA230_8_NC2                                                   
P  NNAMEm0221 NC_INA230_8_NC1                                                   
P  NNAMEm0222 NC_INA230_8_NC0                                                   
P  NNAMEm0223 NC_INA230_7_NC5                                                   
P  NNAMEm0224 NC_INA230_7_NC4                                                   
P  NNAMEm0225 NC_INA230_7_NC3                                                   
P  NNAMEm0226 NC_INA230_7_NC2                                                   
P  NNAMEm0227 NC_INA230_7_NC1                                                   
P  NNAMEm0228 NC_INA230_7_NC0                                                   
P  NNAMEm0229 NC_INA230_6_NC5                                                   
P  NNAMEm0230 NC_INA230_6_NC4                                                   
P  NNAMEm0231 NC_INA230_6_NC3                                                   
P  NNAMEm0232 NC_INA230_6_NC2                                                   
P  NNAMEm0233 NC_INA230_6_NC1                                                   
P  NNAMEm0234 NC_INA230_6_NC0                                                   
P  NNAMEm0235 MAX11617_2_VREF_R                                                 
P  NNAMEm0236 MAX11617_2_VREF                                                   
P  NNAMEm0237 HP_LVC3_OCP_V3_2_PWRGD_R1                                         
P  NNAMEm0238 HP_LVC3_OCP_V3_2_PWRGD                                            
P  NNAMEm0239 HP_LVC3_OCP_V3_2_PRSNT2_N                                         
P  NNAMEm0240 HP_LVC3_OCP_V3_2_PRSNT2                                           
P  NNAMEm0241 HP_LVC3_OCP_V3_2_P12V_R_PWRGD                                     
P  NNAMEm0242 HP_LVC3_OCP_V3_1_PWRGD_R1                                         
P  NNAMEm0243 HP_LVC3_OCP_V3_1_PWRGD                                            
P  NNAMEm0244 HP_LVC3_OCP_V3_1_P12V_R_PWRGD                                     
P  NNAMEm0245 HP_LVC3_OCP_SFF_PRSNT2_N                                          
P  NNAMEm0246 HP_LVC3_OCP_SFF_PRSNT2                                            
P  NNAMEm0247 FM_SMB_RT_ROM_MUX8_SEL                                            
P  NNAMEm0248 FM_SMB_RT_ROM_MUX7_SEL                                            
P  NNAMEm0249 FM_SMB_RT_ROM_MUX6_SEL                                            
P  NNAMEm0250 FM_SMB_RT_ROM_MUX5_SEL                                            
P  NNAMEm0251 FM_SMB_RT_ROM_MUX4_SEL                                            
P  NNAMEm0252 FM_SMB_RT_ROM_MUX3_SEL                                            
P  NNAMEm0253 FM_SMB_RT_ROM_MUX2_SEL                                            
P  NNAMEm0254 FM_SMB_RT_ROM_MUX1_SEL                                            
P  NNAMEm0255 FM_PLD_OCP_SFF_AUX_PWR_EN                                         
P  NNAMEm0256 FM_OCP_V3_2_AUX_PWR_R_EN                                          
P  NNAMEm0257 FM_OCP_V3_2_AUX_PWR_EN                                            
P  NNAMEm0258 IRQ_HSC_FAULT_BUF_N                                               
P  NNAMEm0259 GPU_WP_HW_CTRL_ISO_N                                              
P  NNAMEm0260 FM_PDB_BUF_EN_R_N                                                 
P  NNAMEm0261 FM_PDB_BUF_EN_R1_N                                                
P  NNAMEm0262 SMB_9ZXL045_P1_SDA                                                
P  NNAMEm0263 SMB_9ZXL045_P1_SCL                                                
P  NNAMEm0264 SMB_9ZXL045_P0_SDA                                                
P  NNAMEm0265 SMB_9ZXL045_P0_SCL                                                
P  NNAMEm0266 PWRGD_P0V9_RETIMER_CPU1_R2                                        
P  NNAMEm0267 PWRGD_P0V9_RETIMER_CPU0_R2                                        
P  NNAMEm0268 P1V8_RETIMER_CPU1_R_EN                                            
P  NNAMEm0269 P1V8_RETIMER_CPU0_R_EN                                            
P  NNAMEm0270 P0V9_RETIMER_CPU1_EN_R2                                           
P  NNAMEm0271 P0V9_RETIMER_CPU0_EN_R2                                           
P  NNAMEm0272 TEST2_RT_CPU0_P3                                                  
P  NNAMEm0273 TEST2_RT_CPU0_P2                                                  
P  NNAMEm0274 TEST2_RT_CPU0_P1                                                  
P  NNAMEm0275 TEST2_RT_CPU0_P0                                                  
P  NNAMEm0276 TEST1_RT_CPU0_P3                                                  
P  NNAMEm0277 TEST1_RT_CPU0_P2                                                  
P  NNAMEm0278 TEST1_RT_CPU0_P1                                                  
P  NNAMEm0279 TEST1_RT_CPU0_P0                                                  
P  NNAMEm0280 TEST0_RT_CPU0_P3                                                  
P  NNAMEm0281 TEST0_RT_CPU0_P2                                                  
P  NNAMEm0282 TEST0_RT_CPU0_P1                                                  
P  NNAMEm0283 TEST0_RT_CPU0_P0                                                  
P  NNAMEm0284 SMB_RT_CPU0_P3_R2_SDA                                             
P  NNAMEm0285 SMB_RT_CPU0_P3_R2_SCL                                             
P  NNAMEm0286 SMB_RT_CPU0_P2_R2_SDA                                             
P  NNAMEm0287 SMB_RT_CPU0_P2_R2_SCL                                             
P  NNAMEm0288 SMB_RT_CPU0_P1_R2_SDA                                             
P  NNAMEm0289 SMB_RT_CPU0_P1_R2_SCL                                             
P  NNAMEm0290 SMB_RT_CPU0_P0_R2_SDA                                             
P  NNAMEm0291 SMB_RT_CPU0_P0_R2_SCL                                             
P  NNAMEm0292 RT_CPU0_P3_VQPS                                                   
P  NNAMEm0293 RT_CPU0_P3_SCAN_MODE                                              
P  NNAMEm0294 RT_CPU0_P3_ADDR3                                                  
P  NNAMEm0295 RT_CPU0_P3_ADDR2                                                  
P  NNAMEm0296 RT_CPU0_P3_ADDR1                                                  
P  NNAMEm0297 RT_CPU0_P2_VQPS                                                   
P  NNAMEm0298 RT_CPU0_P2_SCAN_MODE                                              
P  NNAMEm0299 RT_CPU0_P2_ADDR3                                                  
P  NNAMEm0300 RT_CPU0_P2_ADDR2                                                  
P  NNAMEm0301 RT_CPU0_P2_ADDR1                                                  
P  NNAMEm0302 RT_CPU0_P1_VQPS                                                   
P  NNAMEm0303 RT_CPU0_P1_SCAN_MODE                                              
P  NNAMEm0304 RT_CPU0_P1_ADDR3                                                  
P  NNAMEm0305 RT_CPU0_P1_ADDR2                                                  
P  NNAMEm0306 RT_CPU0_P1_ADDR1                                                  
P  NNAMEm0307 RT_CPU0_P0_VQPS                                                   
P  NNAMEm0308 RT_CPU0_P0_SCAN_MODE                                              
P  NNAMEm0309 RT_CPU0_P0_ADDR3                                                  
P  NNAMEm0310 RT_CPU0_P0_ADDR2                                                  
P  NNAMEm0311 RT_CPU0_P0_ADDR1                                                  
P  NNAMEm0312 RST_RT_CPU0_P3_RESET_R_N                                          
P  NNAMEm0313 RST_RT_CPU0_P3_RESET_R2_N                                         
P  NNAMEm0314 RST_RT_CPU0_P3_RESET_N                                            
P  NNAMEm0315 RST_RT_CPU0_P3_PERST_R_N                                          
P  NNAMEm0316 RST_RT_CPU0_P3_PERST_R2_N                                         
P  NNAMEm0317 RST_RT_CPU0_P3_PERST_N                                            
P  NNAMEm0318 RST_RT_CPU0_P2_RESET_R_N                                          
P  NNAMEm0319 RST_RT_CPU0_P2_RESET_R2_N                                         
P  NNAMEm0320 RST_RT_CPU0_P2_RESET_N                                            
P  NNAMEm0321 RST_RT_CPU0_P2_PERST_R_N                                          
P  NNAMEm0322 RST_RT_CPU0_P2_PERST_R2_N                                         
P  NNAMEm0323 RST_RT_CPU0_P2_PERST_N                                            
P  NNAMEm0324 RST_RT_CPU0_P1_RESET_R_N                                          
P  NNAMEm0325 RST_RT_CPU0_P1_RESET_R2_N                                         
P  NNAMEm0326 RST_RT_CPU0_P1_RESET_N                                            
P  NNAMEm0327 RST_RT_CPU0_P1_PERST_R_N                                          
P  NNAMEm0328 RST_RT_CPU0_P1_PERST_R2_N                                         
P  NNAMEm0329 RST_RT_CPU0_P1_PERST_N                                            
P  NNAMEm0330 RST_RT_CPU0_P0_RESET_R_N                                          
P  NNAMEm0331 RST_RT_CPU0_P0_RESET_R2_N                                         
P  NNAMEm0332 RST_RT_CPU0_P0_RESET_N                                            
P  NNAMEm0333 RST_RT_CPU0_P0_PERST_R_N                                          
P  NNAMEm0334 RST_RT_CPU0_P0_PERST_R2_N                                         
P  NNAMEm0335 RST_RT_CPU0_P0_PERST_N                                            
P  NNAMEm0336 P1V8_CPU0_RT3_1A_1D                                               
P  NNAMEm0337 P1V8_CPU0_RT3_1A                                                  
P  NNAMEm0338 P1V8_CPU0_RT2_1A_1D                                               
P  NNAMEm0339 P1V8_CPU0_RT2_1A                                                  
P  NNAMEm0340 P1V8_CPU0_RT1_1A_1D                                               
P  NNAMEm0341 P1V8_CPU0_RT1_1A                                                  
P  NNAMEm0342 P1V8_CPU0_RT0_1A_1D                                               
P  NNAMEm0343 P1V8_CPU0_RT0_1A                                                  
P  NNAMEm0344 P0V9_CPU0_RT3_2A_2D                                               
P  NNAMEm0345 P0V9_CPU0_RT3_2A                                                  
P  NNAMEm0346 P0V9_CPU0_RT2_2A_2D                                               
P  NNAMEm0347 P0V9_CPU0_RT2_2A                                                  
P  NNAMEm0348 P0V9_CPU0_RT1_2A_2D                                               
P  NNAMEm0349 P0V9_CPU0_RT1_2A                                                  
P  NNAMEm0350 P0V9_CPU0_RT0_2A_2D                                               
P  NNAMEm0351 P0V9_CPU0_RT0_2A                                                  
P  NNAMEm0352 NCF_CPU0_P3_GND                                                   
P  NNAMEm0353 NCF_CPU0_P2_GND                                                   
P  NNAMEm0354 NCF_CPU0_P1_GND                                                   
P  NNAMEm0355 NCF_CPU0_P0_GND                                                   
P  NNAMEm0356 NCF_A1_CPU0_P3_GND                                                
P  NNAMEm0357 NCF_A1_CPU0_P2_GND                                                
P  NNAMEm0358 NCF_A1_CPU0_P1_GND                                                
P  NNAMEm0359 NCF_A1_CPU0_P0_GND                                                
P  NNAMEm0360 MODE_RT_CPU0_P3                                                   
P  NNAMEm0361 MODE_RT_CPU0_P2                                                   
P  NNAMEm0362 MODE_RT_CPU0_P1                                                   
P  NNAMEm0363 MODE_RT_CPU0_P0                                                   
P  NNAMEm0364 JTAG_TEST_MODE_RT_CPU0_P3                                         
P  NNAMEm0365 JTAG_TEST_MODE_RT_CPU0_P2                                         
P  NNAMEm0366 JTAG_TEST_MODE_RT_CPU0_P1                                         
P  NNAMEm0367 JTAG_TEST_MODE_RT_CPU0_P0                                         
P  NNAMEm0368 GPIO3_RT_CPU0_P3                                                  
P  NNAMEm0369 GPIO3_RT_CPU0_P2                                                  
P  NNAMEm0370 GPIO3_RT_CPU0_P1                                                  
P  NNAMEm0371 GPIO3_RT_CPU0_P0                                                  
P  NNAMEm0372 GPIO2_RT_CPU0_P3                                                  
P  NNAMEm0373 GPIO2_RT_CPU0_P2                                                  
P  NNAMEm0374 GPIO2_RT_CPU0_P1                                                  
P  NNAMEm0375 GPIO2_RT_CPU0_P0                                                  
P  NNAMEm0376 TEST2_RT_CPU1_P3                                                  
P  NNAMEm0377 TEST2_RT_CPU1_P2                                                  
P  NNAMEm0378 TEST1_RT_CPU1_P3                                                  
P  NNAMEm0379 TEST1_RT_CPU1_P2                                                  
P  NNAMEm0380 TEST0_RT_CPU1_P3                                                  
P  NNAMEm0381 TEST0_RT_CPU1_P2                                                  
P  NNAMEm0382 SMB_SEN_MAM_3V3AUX_SDA                                            
P  NNAMEm0383 SMB_SEN_MAM_3V3AUX_SCL                                            
P  NNAMEm0384 SMB_RT_CPU1_P3_SDA                                                
P  NNAMEm0385 SMB_RT_CPU1_P3_SCL                                                
P  NNAMEm0386 SMB_RT_CPU1_P3_R_SDA                                              
P  NNAMEm0387 SMB_RT_CPU1_P3_R_SCL                                              
P  NNAMEm0388 SMB_RT_CPU1_P3_ROM_MUX_2D_R_SDA                                   
P  NNAMEm0389 SMB_RT_CPU1_P3_ROM_MUX_2D_R_SCL                                   
P  NNAMEm0390 SMB_RT_CPU1_P3_R2_SDA                                             
P  NNAMEm0391 SMB_RT_CPU1_P3_R2_SCL                                             
P  NNAMEm0392 SMB_RT_CPU1_P2_SDA                                                
P  NNAMEm0393 SMB_RT_CPU1_P2_SCL                                                
P  NNAMEm0394 SMB_RT_CPU1_P2_R_SDA                                              
P  NNAMEm0395 SMB_RT_CPU1_P2_R_SCL                                              
P  NNAMEm0396 SMB_RT_CPU1_P2_ROM_MUX_2D_R_SDA                                   
P  NNAMEm0397 SMB_RT_CPU1_P2_ROM_MUX_2D_R_SCL                                   
P  NNAMEm0398 SMB_RT_CPU1_P2_R2_SDA                                             
P  NNAMEm0399 SMB_RT_CPU1_P2_R2_SCL                                             
P  NNAMEm0400 SMB_RT_CPU1_P1_ROM_MUX_2D_R_SDA                                   
P  NNAMEm0401 SMB_RT_CPU1_P1_ROM_MUX_2D_R_SCL                                   
P  NNAMEm0402 SMB_RT_CPU1_P0_ROM_MUX_2D_R_SDA                                   
P  NNAMEm0403 SMB_RT_CPU1_P0_ROM_MUX_2D_R_SCL                                   
P  NNAMEm0404 SMB_RT_CPU0_P3_SDA                                                
P  NNAMEm0405 SMB_RT_CPU0_P3_SCL                                                
P  NNAMEm0406 SMB_RT_CPU0_P3_R_SDA                                              
P  NNAMEm0407 SMB_RT_CPU0_P3_R_SCL                                              
P  NNAMEm0408 SMB_RT_CPU0_P3_ROM_MUX_2D_R_SDA                                   
P  NNAMEm0409 SMB_RT_CPU0_P3_ROM_MUX_2D_R_SCL                                   
P  NNAMEm0410 SMB_RT_CPU0_P2_SDA                                                
P  NNAMEm0411 SMB_RT_CPU0_P2_SCL                                                
P  NNAMEm0412 SMB_RT_CPU0_P2_R_SDA                                              
P  NNAMEm0413 SMB_RT_CPU0_P2_R_SCL                                              
P  NNAMEm0414 SMB_RT_CPU0_P2_ROM_MUX_2D_R_SDA                                   
P  NNAMEm0415 SMB_RT_CPU0_P2_ROM_MUX_2D_R_SCL                                   
P  NNAMEm0416 SMB_RT_CPU0_P1_SDA                                                
P  NNAMEm0417 SMB_RT_CPU0_P1_SCL                                                
P  NNAMEm0418 SMB_RT_CPU0_P1_R_SDA                                              
P  NNAMEm0419 SMB_RT_CPU0_P1_R_SCL                                              
P  NNAMEm0420 SMB_RT_CPU0_P1_ROM_MUX_2D_R_SDA                                   
P  NNAMEm0421 SMB_RT_CPU0_P1_ROM_MUX_2D_R_SCL                                   
P  NNAMEm0422 SMB_RT_CPU0_P0_SDA                                                
P  NNAMEm0423 SMB_RT_CPU0_P0_SCL                                                
P  NNAMEm0424 SMB_RT_CPU0_P0_R_SDA                                              
P  NNAMEm0425 SMB_RT_CPU0_P0_R_SCL                                              
P  NNAMEm0426 SMB_RT_CPU0_P0_ROM_MUX_2D_R_SDA                                   
P  NNAMEm0427 SMB_RT_CPU0_P0_ROM_MUX_2D_R_SCL                                   
P  NNAMEm0428 SMB_MUX_RT_ROM_SDA                                                
P  NNAMEm0429 SMB_MUX_RT_ROM_SCL                                                
P  NNAMEm0430 SMB_MUX_RT_ROM_R1_SDA                                             
P  NNAMEm0431 SMB_MUX_RT_ROM_R1_SCL                                             
P  NNAMEm0432 SMB_MUX_RT_R1_SDA                                                 
P  NNAMEm0433 SMB_MUX_RT_R1_SCL                                                 
P  NNAMEm0434 RT_SMB_MUX_ADDR2                                                  
P  NNAMEm0435 RT_SMB_MUX_ADDR1                                                  
P  NNAMEm0436 RT_SMB_MUX_ADDR0                                                  
P  NNAMEm0437 RT_ROM_SMB_MUX_ADDR2                                              
P  NNAMEm0438 RT_ROM_SMB_MUX_ADDR1                                              
P  NNAMEm0439 RT_ROM_SMB_MUX_ADDR0                                              
P  NNAMEm0440 RT_CPU1_P3_VQPS                                                   
P  NNAMEm0441 RT_CPU1_P3_SCAN_MODE                                              
P  NNAMEm0442 RT_CPU1_P3_ADDR3                                                  
P  NNAMEm0443 RT_CPU1_P3_ADDR2                                                  
P  NNAMEm0444 RT_CPU1_P3_ADDR1                                                  
P  NNAMEm0445 RT_CPU1_P2_VQPS                                                   
P  NNAMEm0446 RT_CPU1_P2_SCAN_MODE                                              
P  NNAMEm0447 RT_CPU1_P2_ADDR3                                                  
P  NNAMEm0448 RT_CPU1_P2_ADDR2                                                  
P  NNAMEm0449 RT_CPU1_P2_ADDR1                                                  
P  NNAMEm0450 RT_BOARD_ID_ID1                                                   
P  NNAMEm0451 RT_BOARD_ID_ID0                                                   
P  NNAMEm0452 RST_SMB_RT_ROM_R2_N                                               
P  NNAMEm0453 RST_SMB_RT_ROM_R1_N                                               
P  NNAMEm0454 RST_SMB_RT_ROM_N                                                  
P  NNAMEm0455 RST_SMB_RT_R2_N                                                   
P  NNAMEm0456 RST_SMB_RT_R1_N                                                   
P  NNAMEm0457 RST_RT_CPU1_P3_RESET_R_N                                          
P  NNAMEm0458 RST_RT_CPU1_P3_RESET_R2_N                                         
P  NNAMEm0459 RST_RT_CPU1_P3_RESET_N                                            
P  NNAMEm0460 RST_RT_CPU1_P3_PERST_R_N                                          
P  NNAMEm0461 RST_RT_CPU1_P3_PERST_R2_N                                         
P  NNAMEm0462 RST_RT_CPU1_P3_PERST_N                                            
P  NNAMEm0463 RST_RT_CPU1_P2_RESET_R_N                                          
P  NNAMEm0464 RST_RT_CPU1_P2_RESET_R2_N                                         
P  NNAMEm0465 RST_RT_CPU1_P2_RESET_N                                            
P  NNAMEm0466 RST_RT_CPU1_P2_PERST_R_N                                          
P  NNAMEm0467 RST_RT_CPU1_P2_PERST_R2_N                                         
P  NNAMEm0468 RST_RT_CPU1_P2_PERST_N                                            
P  NNAMEm0469 PRSNT_CABLE_SWB_B2_N                                              
P  NNAMEm0470 PRSNT_CABLE_SWB_B2_ISO_R_N                                        
P  NNAMEm0471 PRSNT_CABLE_SWB_B2_ISO_N                                          
P  NNAMEm0472 PRSNT_CABLE_SWB_B2                                                
P  NNAMEm0473 PRSNT_CABLE_SWB_B1_N                                              
P  NNAMEm0474 PRSNT_CABLE_SWB_B1_ISO_R_N                                        
P  NNAMEm0475 PRSNT_CABLE_SWB_B1_ISO_N                                          
P  NNAMEm0476 PRSNT_CABLE_SWB_B1                                                
P  NNAMEm0477 PRSNT_CABLE_GPU_B3_ISO_R1_N                                       
P  NNAMEm0478 PRSNT_CABLE_GPU_B3_ISO_N                                          
P  NNAMEm0479 PRSNT_CABLE_GPU_A3_N                                              
P  NNAMEm0480 PRSNT_CABLE_GPU_A3_ISO_R_N                                        
P  NNAMEm0481 PRSNT_CABLE_GPU_A3_ISO_N                                          
P  NNAMEm0482 PRSNT_CABLE_GPU_A3                                                
P  NNAMEm0483 PRSNT_CABLE_GPU_A2_ISO_R1_N                                       
P  NNAMEm0484 PRSNT_CABLE_GPU_A2_ISO_N                                          
P  NNAMEm0485 PRSNT_CABLE_GPU_A1_ISO_R1_N                                       
P  NNAMEm0486 PRSNT_CABLE_GPU_A1_ISO_N                                          
P  NNAMEm0487 P1V8_CPU1_RT3_1A_1D                                               
P  NNAMEm0488 P1V8_CPU1_RT3_1A                                                  
P  NNAMEm0489 P1V8_CPU1_RT2_1A_1D                                               
P  NNAMEm0490 P1V8_CPU1_RT2_1A                                                  
P  NNAMEm0491 P0V9_CPU1_RT3_2A_2D                                               
P  NNAMEm0492 P0V9_CPU1_RT3_2A                                                  
P  NNAMEm0493 P0V9_CPU1_RT2_2A_2D                                               
P  NNAMEm0494 P0V9_CPU1_RT2_2A                                                  
P  NNAMEm0495 NCF_CPU1_P3_GND                                                   
P  NNAMEm0496 NCF_CPU1_P2_GND                                                   
P  NNAMEm0497 NCF_A1_CPU1_P3_GND                                                
P  NNAMEm0498 NCF_A1_CPU1_P2_GND                                                
P  NNAMEm0499 MODE_RT_CPU1_P3                                                   
P  NNAMEm0500 MODE_RT_CPU1_P2                                                   
P  NNAMEm0501 JTAG_TEST_MODE_RT_CPU1_P3                                         
P  NNAMEm0502 JTAG_TEST_MODE_RT_CPU1_P2                                         
P  NNAMEm0503 GPU_PRSNT_N_ISO_R1                                                
P  NNAMEm0504 GPIO3_RT_CPU1_P3                                                  
P  NNAMEm0505 GPIO3_RT_CPU1_P2                                                  
P  NNAMEm0506 GPIO2_RT_CPU1_P3                                                  
P  NNAMEm0507 GPIO2_RT_CPU1_P2                                                  
P  NNAMEm0508 TEST2_RT_CPU1_P1                                                  
P  NNAMEm0509 TEST1_RT_CPU1_P1                                                  
P  NNAMEm0510 TEST0_RT_CPU1_P1                                                  
P  NNAMEm0511 SMB_RT_CPU1_P1_SDA                                                
P  NNAMEm0512 SMB_RT_CPU1_P1_SCL                                                
P  NNAMEm0513 SMB_RT_CPU1_P1_R_SDA                                              
P  NNAMEm0514 SMB_RT_CPU1_P1_R_SCL                                              
P  NNAMEm0515 SMB_RT_CPU1_P1_R2_SDA                                             
P  NNAMEm0516 SMB_RT_CPU1_P1_R2_SCL                                             
P  NNAMEm0517 RT_CPU1_P1_VQPS                                                   
P  NNAMEm0518 RT_CPU1_P1_SCAN_MODE                                              
P  NNAMEm0519 RT_CPU1_P1_ADDR3                                                  
P  NNAMEm0520 RT_CPU1_P1_ADDR2                                                  
P  NNAMEm0521 RT_CPU1_P1_ADDR1                                                  
P  NNAMEm0522 RT_CPU1_P0_SCAN_MODE                                              
P  NNAMEm0523 RT_CPU1_P0_ADDR3                                                  
P  NNAMEm0524 RT_CPU1_P0_ADDR2                                                  
P  NNAMEm0525 RT_CPU1_P0_ADDR1                                                  
P  NNAMEm0526 RST_RT_CPU1_P1_RESET_R_N                                          
P  NNAMEm0527 RST_RT_CPU1_P1_RESET_R2_N                                         
P  NNAMEm0528 RST_RT_CPU1_P1_RESET_N                                            
P  NNAMEm0529 RST_RT_CPU1_P1_PERST_R_N                                          
P  NNAMEm0530 RST_RT_CPU1_P1_PERST_R2_N                                         
P  NNAMEm0531 RST_RT_CPU1_P1_PERST_N                                            
P  NNAMEm0532 RST_RT_CPU1_P0_RESET_R_N                                          
P  NNAMEm0533 RST_RT_CPU1_P0_RESET_R2_N                                         
P  NNAMEm0534 RST_RT_CPU1_P0_RESET_N                                            
P  NNAMEm0535 RST_RT_CPU1_P0_PERST_R_N                                          
P  NNAMEm0536 RST_RT_CPU1_P0_PERST_R2_N                                         
P  NNAMEm0537 RST_RT_CPU1_P0_PERST_N                                            
P  NNAMEm0538 P1V8_CPU1_RT_1D                                                   
P  NNAMEm0539 P1V8_CPU1_RT1_1A_1D                                               
P  NNAMEm0540 P1V8_CPU1_RT1_1A                                                  
P  NNAMEm0541 P1V8_CPU1_RT0_1A_1D                                               
P  NNAMEm0542 P1V8_CPU1_RT0_1A                                                  
P  NNAMEm0543 P0V9_CPU1_RT_2D                                                   
P  NNAMEm0544 P0V9_CPU1_RT1_2A_2D                                               
P  NNAMEm0545 P0V9_CPU1_RT1_2A                                                  
P  NNAMEm0546 P0V9_CPU1_RT0_2A_2D                                               
P  NNAMEm0547 P0V9_CPU1_RT0_2A                                                  
P  NNAMEm0548 NCF_CPU1_P1_GND                                                   
P  NNAMEm0549 NCF_A1_CPU1_P1_GND                                                
P  NNAMEm0550 MODE_RT_CPU1_P1                                                   
P  NNAMEm0551 JTAG_TEST_MODE_RT_CPU1_P1                                         
P  NNAMEm0552 GPIO3_RT_CPU1_P1                                                  
P  NNAMEm0553 GPIO2_RT_CPU1_P1                                                  
P  NNAMEm0554 TEST2_RT_CPU1_P0                                                  
P  NNAMEm0555 TEST1_RT_CPU1_P0                                                  
P  NNAMEm0556 TEST0_RT_CPU1_P0                                                  
P  NNAMEm0557 MODE_RT_CPU1_P0                                                   
P  NNAMEm0558 JTAG_TEST_MODE_RT_CPU1_P0                                         
P  NNAMEm0559 GPIO3_RT_CPU1_P0                                                  
P  NNAMEm0560 GPIO2_RT_CPU1_P0                                                  
P  NNAMEm0561 TP_P0V9_RETIMER_CPU1_VRHOT                                        
P  NNAMEm0562 TP_P0V9_RETIMER_CPU1_SVID_ALERT_N                                 
P  NNAMEm0563 TP_P0V9_RETIMER_CPU0_VRHOT                                        
P  NNAMEm0564 TP_P0V9_RETIMER_CPU0_SVID_ALERT_N                                 
P  NNAMEm0565 SW_P1V8_RETIMER_CPU1_BST_R                                        
P  NNAMEm0566 SW_P1V8_RETIMER_CPU0_BST_R                                        
P  NNAMEm0567 SW_P0V9_RETIMER_CPU1_SW2_RC                                       
P  NNAMEm0568 SW_P0V9_RETIMER_CPU1_SW1_RC                                       
P  NNAMEm0569 SMB_RT_CPU1_P0_SDA                                                
P  NNAMEm0570 SMB_RT_CPU1_P0_SCL                                                
P  NNAMEm0571 SMB_RT_CPU1_P0_R_SDA                                              
P  NNAMEm0572 SMB_RT_CPU1_P0_R_SCL                                              
P  NNAMEm0573 SMB_RT_CPU1_P0_R2_SDA                                             
P  NNAMEm0574 SMB_RT_CPU1_P0_R2_SCL                                             
P  NNAMEm0575 PV09_RETIMER_CPU1_VCCS                                            
P  NNAMEm0576 PV09_RETIMER_CPU0_VCCS                                            
P  NNAMEm0577 P0V9_RETIMER_CPU1_VRHOT                                           
P  NNAMEm0578 P0V9_RETIMER_CPU1_TEMP1_R                                         
P  NNAMEm0579 P0V9_RETIMER_CPU1_SVID_SDA                                        
P  NNAMEm0580 P0V9_RETIMER_CPU1_SVID_CLK                                        
P  NNAMEm0581 P0V9_RETIMER_CPU1_SENSE_SH_P                                      
P  NNAMEm0582 P0V9_RETIMER_CPU1_SENSE_SH_N                                      
P  NNAMEm0583 P0V9_RETIMER_CPU1_EN1_R                                           
P  NNAMEm0584 P0V9_RETIMER_CPU1_EN0_R                                           
P  NNAMEm0585 P0V9_RETIMER_CPU1_CFP                                             
P  NNAMEm0586 P0V9_RETIMER_CPU1_ADDR                                            
P  NNAMEm0587 P0V9_RETIMER_CPU0_VRHOT                                           
P  NNAMEm0588 P0V9_RETIMER_CPU0_TEMP1_R                                         
P  NNAMEm0589 P0V9_RETIMER_CPU0_SVID_SDA                                        
P  NNAMEm0590 P0V9_RETIMER_CPU0_SVID_CLK                                        
P  NNAMEm0591 P0V9_RETIMER_CPU0_SENSE_SH_P                                      
P  NNAMEm0592 P0V9_RETIMER_CPU0_SENSE_SH_N                                      
P  NNAMEm0593 P0V9_RETIMER_CPU0_EN1_R                                           
P  NNAMEm0594 P0V9_RETIMER_CPU0_EN0_R                                           
P  NNAMEm0595 P0V9_RETIMER_CPU0_CFP                                             
P  NNAMEm0596 P0V9_RETIMER_CPU0_ADDR                                            
P  NNAMEm0597 RT_CPU1_P0_VQPS                                                   
P  NNAMEm0598 NCF_CPU1_P0_GND                                                   
P  NNAMEm0599 NCF_A1_CPU1_P0_GND                                                
P  NNAMEm0600 P0V9_RETIMER_CPU1_SENSE_R_P                                       
P  NNAMEm0601 P0V9_RETIMER_CPU0_SENSE_R_P                                       
P  NNAMEm0602 UV_ADR_P2V5_COMP                                                  
P  NNAMEm0603 P0V9_RETIMER_CPU1_PMSCL                                           
P  NNAMEm0604 P0V9_RETIMER_CPU1_PMSDA                                           
P  NNAMEm0605 P0V9_RETIMER_CPU0_PMSCL                                           
P  NNAMEm0606 P0V9_RETIMER_CPU0_PMSDA                                           
P  NNAMEm0607 SW_PVDD_33_S5_BST_R                                               
P  NNAMEm0608 SW_PVDD18_S5_P1_BST_R                                             
P  NNAMEm0609 SW_PVDD18_S5_P0_BST_R                                             
P  NNAMEm0610 SW_P1V8_RETIMER_CPU1_SW                                           
P  NNAMEm0611 SW_P1V8_RETIMER_CPU1_BST                                          
P  NNAMEm0612 SW_P1V8_AUX_BT_R                                                  
P  NNAMEm0613 SW_P1V2_AUX_BT_R                                                  
P  NNAMEm0614 SW_P12V_AUX_P1V8_RETIMER_CPU1_FLT                                 
P  NNAMEm0615 SW_P12V_AUX_P0V9_RETIMER_CPU1_FLT                                 
P  NNAMEm0616 SW_P12V_AUX_P0V9_RETIMER_CPU0_FLT                                 
P  NNAMEm0617 SW_P0V9_RETIMER_CPU1_SW2                                          
P  NNAMEm0618 SW_P0V9_RETIMER_CPU1_SW1                                          
P  NNAMEm0619 SW_P0V9_RETIMER_CPU1_PH2                                          
P  NNAMEm0620 SW_P0V9_RETIMER_CPU1_PH1                                          
P  NNAMEm0621 SW_P0V9_RETIMER_CPU1_BOOT2_RC                                     
P  NNAMEm0622 SW_P0V9_RETIMER_CPU1_BOOT2                                        
P  NNAMEm0623 SW_P0V9_RETIMER_CPU1_BOOT1_RC                                     
P  NNAMEm0624 SW_P0V9_RETIMER_CPU1_BOOT1                                        
P  NNAMEm0625 SW_P0V9_RETIMER_CPU0_SW2_RC                                       
P  NNAMEm0626 SW_P0V9_RETIMER_CPU0_SW2                                          
P  NNAMEm0627 SW_P0V9_RETIMER_CPU0_SW1_RC                                       
P  NNAMEm0628 SW_P0V9_RETIMER_CPU0_SW1                                          
P  NNAMEm0629 SW_P0V9_RETIMER_CPU0_PH2                                          
P  NNAMEm0630 SW_P0V9_RETIMER_CPU0_PH1                                          
P  NNAMEm0631 SW_P0V9_RETIMER_CPU0_BOOT2_RC                                     
P  NNAMEm0632 SW_P0V9_RETIMER_CPU0_BOOT2                                        
P  NNAMEm0633 SW_P0V9_RETIMER_CPU0_BOOT1_RC                                     
P  NNAMEm0634 SW_P0V9_RETIMER_CPU0_BOOT1                                        
P  NNAMEm0635 SVID_PVDDCR_CPU1_P1_SVD_R1                                        
P  NNAMEm0636 SVID_PVDDCR_CPU1_P1_SVC_R1                                        
P  NNAMEm0637 SVID_PVDDCR_CPU1_P0_SVD_R1                                        
P  NNAMEm0638 SVID_PVDDCR_CPU1_P0_SVC_R1                                        
P  NNAMEm0639 SVID_PVDDCR_CPU0_P1_SVD_R1                                        
P  NNAMEm0640 SVID_PVDDCR_CPU0_P1_SVC_R1                                        
P  NNAMEm0641 SVID_PVDDCR_CPU0_P0_SVD_R1                                        
P  NNAMEm0642 SVID_PVDDCR_CPU0_P0_SVC_R1                                        
P  NNAMEm0643 SMB_RT_CPU1_P3_ROM_R_SDA                                          
P  NNAMEm0644 SMB_RT_CPU1_P3_ROM_R_SCL                                          
P  NNAMEm0645 SMB_RT_CPU1_P3_ROM_MUX_1D_R_SDA                                   
P  NNAMEm0646 SMB_RT_CPU1_P3_ROM_MUX_1D_R_SCL                                   
P  NNAMEm0647 SMB_RT_CPU1_P3_ROM_SDA                                            
P  NNAMEm0648 SMB_RT_CPU1_P3_ROM_SCL                                            
P  NNAMEm0649 SMB_RT_CPU1_P2_ROM_R_SDA                                          
P  NNAMEm0650 SMB_RT_CPU1_P2_ROM_R_SCL                                          
P  NNAMEm0651 SMB_RT_CPU1_P2_ROM_MUX_1D_R_SDA                                   
P  NNAMEm0652 SMB_RT_CPU1_P2_ROM_MUX_1D_R_SCL                                   
P  NNAMEm0653 SMB_RT_CPU1_P2_ROM_SDA                                            
P  NNAMEm0654 SMB_RT_CPU1_P2_ROM_SCL                                            
P  NNAMEm0655 SMB_RT_CPU1_P1_ROM_R_SDA                                          
P  NNAMEm0656 SMB_RT_CPU1_P1_ROM_R_SCL                                          
P  NNAMEm0657 SMB_RT_CPU1_P1_ROM_MUX_1D_R_SDA                                   
P  NNAMEm0658 SMB_RT_CPU1_P1_ROM_MUX_1D_R_SCL                                   
P  NNAMEm0659 SMB_RT_CPU1_P1_ROM_SDA                                            
P  NNAMEm0660 SMB_RT_CPU1_P1_ROM_SCL                                            
P  NNAMEm0661 SMB_RT_CPU1_P0_ROM_R_SDA                                          
P  NNAMEm0662 SMB_RT_CPU1_P0_ROM_R_SCL                                          
P  NNAMEm0663 SMB_RT_CPU1_P0_ROM_MUX_1D_R_SDA                                   
P  NNAMEm0664 SMB_RT_CPU1_P0_ROM_MUX_1D_R_SCL                                   
P  NNAMEm0665 SMB_RT_CPU1_P0_ROM_SDA                                            
P  NNAMEm0666 SMB_RT_CPU1_P0_ROM_SCL                                            
P  NNAMEm0667 SMB_RT_CPU0_P3_ROM_R_SDA                                          
P  NNAMEm0668 SMB_RT_CPU0_P3_ROM_R_SCL                                          
P  NNAMEm0669 SMB_RT_CPU0_P3_ROM_MUX_1D_R_SDA                                   
P  NNAMEm0670 SMB_RT_CPU0_P3_ROM_MUX_1D_R_SCL                                   
P  NNAMEm0671 SMB_RT_CPU0_P3_ROM_SDA                                            
P  NNAMEm0672 SMB_RT_CPU0_P3_ROM_SCL                                            
P  NNAMEm0673 SMB_RT_CPU0_P2_ROM_R_SDA                                          
P  NNAMEm0674 SMB_RT_CPU0_P2_ROM_R_SCL                                          
P  NNAMEm0675 SMB_RT_CPU0_P2_ROM_MUX_1D_R_SDA                                   
P  NNAMEm0676 SMB_RT_CPU0_P2_ROM_MUX_1D_R_SCL                                   
P  NNAMEm0677 SMB_RT_CPU0_P2_ROM_SDA                                            
P  NNAMEm0678 SMB_RT_CPU0_P2_ROM_SCL                                            
P  NNAMEm0679 SMB_RT_CPU0_P1_ROM_R_SDA                                          
P  NNAMEm0680 SMB_RT_CPU0_P1_ROM_R_SCL                                          
P  NNAMEm0681 SMB_RT_CPU0_P1_ROM_MUX_1D_R_SDA                                   
P  NNAMEm0682 SMB_RT_CPU0_P1_ROM_MUX_1D_R_SCL                                   
P  NNAMEm0683 SMB_RT_CPU0_P1_ROM_SDA                                            
P  NNAMEm0684 SMB_RT_CPU0_P1_ROM_SCL                                            
P  NNAMEm0685 SMB_RT_CPU0_P0_ROM_R_SDA                                          
P  NNAMEm0686 SMB_RT_CPU0_P0_ROM_R_SCL                                          
P  NNAMEm0687 SMB_RT_CPU0_P0_ROM_MUX_1D_R_SDA                                   
P  NNAMEm0688 SMB_RT_CPU0_P0_ROM_MUX_1D_R_SCL                                   
P  NNAMEm0689 SMB_RT_CPU0_P0_ROM_SDA                                            
P  NNAMEm0690 SMB_RT_CPU0_P0_ROM_SCL                                            
P  NNAMEm0691 PWRGD_P1V8_RETIMER_CPU1                                           
P  NNAMEm0692 PWRGD_P0V9_RETIMER_CPU1_R                                         
P  NNAMEm0693 PWRGD_P0V9_RETIMER_CPU1                                           
P  NNAMEm0694 PWRGD_P0V9_RETIMER_CPU0_R                                         
P  NNAMEm0695 PWRGD_P0V9_RETIMER_CPU0                                           
P  NNAMEm0696 PWRGD_CHGL_CPU1_R2                                                
P  NNAMEm0697 PWRGD_CHGL_CPU1_R1                                                
P  NNAMEm0698 PWRGD_CHGL_CPU0_R2                                                
P  NNAMEm0699 PWRGD_CHGL_CPU0_R1                                                
P  NNAMEm0700 PWRGD_CHAF_CPU1_R2                                                
P  NNAMEm0701 PWRGD_CHAF_CPU1_R1                                                
P  NNAMEm0702 PWRGD_CHAF_CPU0_R2                                                
P  NNAMEm0703 PWRGD_CHAF_CPU0_R1                                                
P  NNAMEm0704 PRSNT_SWB_ISO_R_N                                                 
P  NNAMEm0705 PRSNT_SWB_ISO_R1_N                                                
P  NNAMEm0706 PRSNT_SWB_ISO_N                                                   
P  NNAMEm0707 P3V3_E1S_PWRGD_0_R1                                               
P  NNAMEm0708 P3V3_9ZXL045_P1_VDDR                                              
P  NNAMEm0709 P3V3_9ZXL045_P1_VDDA                                              
P  NNAMEm0710 P3V3_9ZXL045_P1_VDD                                               
P  NNAMEm0711 P3V3_9ZXL045_P1                                                   
P  NNAMEm0712 P3V3_9ZXL045_P0_VDDR                                              
P  NNAMEm0713 P3V3_9ZXL045_P0_VDDA                                              
P  NNAMEm0714 P3V3_9ZXL045_P0_VDD                                               
P  NNAMEm0715 P3V3_9ZXL045_P0                                                   
P  NNAMEm0716 P1V8_RETIMER_CPU1_VCC                                             
P  NNAMEm0717 P1V8_RETIMER_CPU1_REF                                             
P  NNAMEm0718 P1V8_RETIMER_CPU1_MODE                                            
P  NNAMEm0719 P1V8_RETIMER_CPU1_FB                                              
P  NNAMEm0720 P1V8_RETIMER_CPU1_EN                                              
P  NNAMEm0721 P1V8_RETIMER_CPU1_CS                                              
P  NNAMEm0722 P12V_SCM_FLTB_N                                                   
P  NNAMEm0723 P12V_SCM_FAULT_R_N                                                
P  NNAMEm0724 P12V_SCM_FAULT_N                                                  
P  NNAMEm0725 P12V_AUX_UV_TRIGGER                                               
P  NNAMEm0726 P12V_AUX_UV_ADR_TRIGGER                                           
P  NNAMEm0727 P0V9_RETIMER_CPU1_VOS2                                            
P  NNAMEm0728 P0V9_RETIMER_CPU1_VOS1                                            
P  NNAMEm0729 P0V9_RETIMER_CPU1_VMON                                            
P  NNAMEm0730 P0V9_RETIMER_CPU1_VINSEN                                          
P  NNAMEm0731 P0V9_RETIMER_CPU1_INALERT                                         
P  NNAMEm0732 P0V9_RETIMER_CPU1_VCC2                                            
P  NNAMEm0733 P0V9_RETIMER_CPU1_VCC1                                            
P  NNAMEm0734 P0V9_RETIMER_CPU1_VCC                                             
P  NNAMEm0735 P0V9_RETIMER_CPU1_TEMP0                                           
P  NNAMEm0736 P0V9_RETIMER_CPU1_PWM2                                            
P  NNAMEm0737 P0V9_RETIMER_CPU1_PWM1                                            
P  NNAMEm0738 P0V9_RETIMER_CPU1_PVCC                                            
P  NNAMEm0739 P0V9_RETIMER_CPU1_PMSDA_R                                         
P  NNAMEm0740 P0V9_RETIMER_CPU1_PMSCL_R                                         
P  NNAMEm0741 TP_P0V9_RETIMER_CPU1_PMALERT                                      
P  NNAMEm0742 P0V9_RETIMER_CPU1_LSET2                                           
P  NNAMEm0743 P0V9_RETIMER_CPU1_LSET1                                           
P  NNAMEm0744 P0V9_RETIMER_CPU1_IMON2                                           
P  NNAMEm0745 P0V9_RETIMER_CPU1_IMON1                                           
P  NNAMEm0746 P0V9_RETIMER_CPU1_EN                                              
P  NNAMEm0747 P0V9_RETIMER_CPU0_VOS2                                            
P  NNAMEm0748 P0V9_RETIMER_CPU0_VOS1                                            
P  NNAMEm0749 P0V9_RETIMER_CPU0_VMON                                            
P  NNAMEm0750 P0V9_RETIMER_CPU0_VINSEN                                          
P  NNAMEm0751 P0V9_RETIMER_CPU0_INALERT                                         
P  NNAMEm0752 P0V9_RETIMER_CPU0_VCC2                                            
P  NNAMEm0753 P0V9_RETIMER_CPU0_VCC1                                            
P  NNAMEm0754 P0V9_RETIMER_CPU0_VCC                                             
P  NNAMEm0755 P0V9_RETIMER_CPU0_TEMP0                                           
P  NNAMEm0756 P0V9_RETIMER_CPU0_PWM2                                            
P  NNAMEm0757 P0V9_RETIMER_CPU0_PWM1                                            
P  NNAMEm0758 P0V9_RETIMER_CPU0_PVCC                                            
P  NNAMEm0759 P0V9_RETIMER_CPU0_PMSDA_R                                         
P  NNAMEm0760 P0V9_RETIMER_CPU0_PMSCL_R                                         
P  NNAMEm0761 TP_P0V9_RETIMER_CPU0_PMALERT                                      
P  NNAMEm0762 P0V9_RETIMER_CPU0_LSET2                                           
P  NNAMEm0763 P0V9_RETIMER_CPU0_LSET1                                           
P  NNAMEm0764 P0V9_RETIMER_CPU0_IMON2                                           
P  NNAMEm0765 P0V9_RETIMER_CPU0_IMON1                                           
P  NNAMEm0766 P0V9_RETIMER_CPU0_EN                                              
P  NNAMEm0767 P0V9_CPU0_RT_2D                                                   
P  NNAMEm0768 OCP_V3_2_PRSNT23_R1_N                                             
P  NNAMEm0769 OCP_V3_2_PRSNT01_R1_N                                             
P  NNAMEm0770 OCP_V3_2_P3V3_R1_PWRGD                                            
P  NNAMEm0771 OCP_V3_1_P3V3_R1_PWRGD                                            
P  NNAMEm0772 OCP_SFF_PRSNT23_R1_N                                              
P  NNAMEm0773 OCP_SFF_PRSNT01_R1_N                                              
P  NNAMEm0774 NC_U314_FBOUT_N                                                   
P  NNAMEm0775 NC_P0V9_RETIMER_CPU1_PWM8                                         
P  NNAMEm0776 NC_P0V9_RETIMER_CPU1_PWM7                                         
P  NNAMEm0777 NC_P0V9_RETIMER_CPU1_PWM6                                         
P  NNAMEm0778 NC_P0V9_RETIMER_CPU1_PWM5                                         
P  NNAMEm0779 NC_P0V9_RETIMER_CPU1_PWM4                                         
P  NNAMEm0780 NC_P0V9_RETIMER_CPU1_PWM3                                         
P  NNAMEm0781 NC_P0V9_RETIMER_CPU1_PG1                                          
P  NNAMEm0782 NC_P0V9_RETIMER_CPU1_IMON8                                        
P  NNAMEm0783 NC_P0V9_RETIMER_CPU1_IMON7                                        
P  NNAMEm0784 NC_P0V9_RETIMER_CPU1_IMON6                                        
P  NNAMEm0785 NC_P0V9_RETIMER_CPU1_IMON5                                        
P  NNAMEm0786 NC_P0V9_RETIMER_CPU1_IMON4                                        
P  NNAMEm0787 NC_P0V9_RETIMER_CPU1_IMON3                                        
P  NNAMEm0788 NC_PV09_RETIMER_CPU1_GL2_2                                        
P  NNAMEm0789 NC_PV09_RETIMER_CPU1_GL2_1                                        
P  NNAMEm0790 NC_PV09_RETIMER_CPU1_GL1_2                                        
P  NNAMEm0791 NC_PV09_RETIMER_CPU1_GL1_1                                        
P  NNAMEm0792 NC_PV09_RETIMER_CPU1_DNC2                                         
P  NNAMEm0793 NC_PV09_RETIMER_CPU1_DNC1                                         
P  NNAMEm0794 NC_P0V9_RETIMER_CPU0_PWM8                                         
P  NNAMEm0795 NC_P0V9_RETIMER_CPU0_PWM7                                         
P  NNAMEm0796 NC_P0V9_RETIMER_CPU0_PWM6                                         
P  NNAMEm0797 NC_P0V9_RETIMER_CPU0_PWM5                                         
P  NNAMEm0798 NC_P0V9_RETIMER_CPU0_PWM4                                         
P  NNAMEm0799 NC_P0V9_RETIMER_CPU0_PWM3                                         
P  NNAMEm0800 NC_P0V9_RETIMER_CPU0_PG1                                          
P  NNAMEm0801 NC_P0V9_RETIMER_CPU0_IMON8                                        
P  NNAMEm0802 NC_P0V9_RETIMER_CPU0_IMON7                                        
P  NNAMEm0803 NC_P0V9_RETIMER_CPU0_IMON6                                        
P  NNAMEm0804 NC_P0V9_RETIMER_CPU0_IMON5                                        
P  NNAMEm0805 NC_P0V9_RETIMER_CPU0_IMON4                                        
P  NNAMEm0806 NC_P0V9_RETIMER_CPU0_IMON3                                        
P  NNAMEm0807 NC_PV09_RETIMER_CPU0_GL2_2                                        
P  NNAMEm0808 NC_PV09_RETIMER_CPU0_GL2_1                                        
P  NNAMEm0809 NC_PV09_RETIMER_CPU0_GL1_2                                        
P  NNAMEm0810 NC_PV09_RETIMER_CPU0_GL1_1                                        
P  NNAMEm0811 NC_PV09_RETIMER_CPU0_DNC2                                         
P  NNAMEm0812 NC_PV09_RETIMER_CPU0_DNC1                                         
P  NNAMEm0813 LED_P12V_SCM_FAULT_D2                                             
P  NNAMEm0814 LED_P12V_SCM_FAULT_D1                                             
P  NNAMEm0815 LED_P12V_SCM_FAULT                                                
P  NNAMEm0816 LED_P12V_PSU_R3                                                   
P  NNAMEm0817 LED_P12V_PSU_R2                                                   
P  NNAMEm0818 LED_P12V_PSU_R1                                                   
P  NNAMEm0819 LED_P12V_AUX_R3                                                   
P  NNAMEm0820 LED_P12V_AUX_R2                                                   
P  NNAMEm0821 LED_P12V_AUX_R1                                                   
P  NNAMEm0822 IRQ_UV_DETECT_R2_N                                                
P  NNAMEm0823 HP_LVC3_SCM_HSC_PWRGD_R                                           
P  NNAMEm0824 FM_UV_ADR_TRIGGER_N_R2                                            
P  NNAMEm0825 FM_PWRGD_P1V8_RETIMER_CPU1                                        
P  NNAMEm0826 FM_JTAG_BMC_R_OE                                                  
P  NNAMEm0827 FM_ESPI_CPU0_ALERT_SEL                                            
P  NNAMEm0828 FM_ESPI_CPU0_ALERT_R_SEL                                          
P  NNAMEm0829 FM_AC_PWR_BTN_R_N                                                 
P  NNAMEm0830 FM_AC_PWR_BTN_PLD_N                                               
P  NNAMEm0831 FM_AC_PWR_BTN_PLD_ISO_R_N                                         
P  NNAMEm0832 FM_AC_PWR_BTN_PLD_ISO_N                                           
P  NNAMEm0833 FM_AC_PWR_BTN_PDB_N                                               
P  NNAMEm0834 FM_AC_PWR_BTN_N                                                   
P  NNAMEm0835 FM_9ZXL045_P1_DEV_EN                                              
P  NNAMEm0836 FM_9ZXL045_P1_3_OE_N                                              
P  NNAMEm0837 FM_9ZXL045_P1_2_OE_N                                              
P  NNAMEm0838 FM_9ZXL045_P1_1_OE_N                                              
P  NNAMEm0839 FM_9ZXL045_P1_0_OE_N                                              
P  NNAMEm0840 FM_9ZXL045_P0_DEV_EN                                              
P  NNAMEm0841 FM_9ZXL045_P0_3_OE_N                                              
P  NNAMEm0842 FM_9ZXL045_P0_2_OE_N                                              
P  NNAMEm0843 FM_9ZXL045_P0_1_OE_N                                              
P  NNAMEm0844 FM_9ZXL045_P0_0_OE_N                                              
P  NNAMEm0845 ESPI_CPU0_ALERT_R1_N                                              
P  NNAMEm0846 ESPI_CPU0_ALERT_PLD_N                                             
P  NNAMEm0847 ESPI_CPU0_ALERT_P0_N                                              
P  NNAMEm0848 CLK_9ZXL045_P1_SADR0                                              
P  NNAMEm0849 CLK_9ZXL045_P1_HIBW                                               
P  NNAMEm0850 CLK_9ZXL045_P0_SADR0                                              
P  NNAMEm0851 CLK_9ZXL045_P0_HIBW                                               
P  NNAMEm0852 CLK_100M_RETIMER_CPU1_P3_R_DP                                     
P  NNAMEm0853 CLK_100M_RETIMER_CPU1_P3_R_DN                                     
P  NNAMEm0854 CLK_100M_RETIMER_CPU1_P3_DP                                       
P  NNAMEm0855 CLK_100M_RETIMER_CPU1_P3_DN                                       
P  NNAMEm0856 CLK_100M_RETIMER_CPU1_P2_R_DP                                     
P  NNAMEm0857 CLK_100M_RETIMER_CPU1_P2_R_DN                                     
P  NNAMEm0858 CLK_100M_RETIMER_CPU1_P2_DP                                       
P  NNAMEm0859 CLK_100M_RETIMER_CPU1_P2_DN                                       
P  NNAMEm0860 CLK_100M_RETIMER_CPU1_P1_R_DP                                     
P  NNAMEm0861 CLK_100M_RETIMER_CPU1_P1_R_DN                                     
P  NNAMEm0862 CLK_100M_RETIMER_CPU1_P1_DP                                       
P  NNAMEm0863 CLK_100M_RETIMER_CPU1_P1_DN                                       
P  NNAMEm0864 CLK_100M_RETIMER_CPU1_P0_R_DP                                     
P  NNAMEm0865 CLK_100M_RETIMER_CPU1_P0_R_DN                                     
P  NNAMEm0866 CLK_100M_RETIMER_CPU1_P0_DP                                       
P  NNAMEm0867 CLK_100M_RETIMER_CPU1_P0_DN                                       
P  NNAMEm0868 CLK_100M_RETIMER_CPU0_P3_R_DP                                     
P  NNAMEm0869 CLK_100M_RETIMER_CPU0_P3_R_DN                                     
P  NNAMEm0870 CLK_100M_RETIMER_CPU0_P3_DP                                       
P  NNAMEm0871 CLK_100M_RETIMER_CPU0_P3_DN                                       
P  NNAMEm0872 CLK_100M_RETIMER_CPU0_P2_R_DP                                     
P  NNAMEm0873 CLK_100M_RETIMER_CPU0_P2_R_DN                                     
P  NNAMEm0874 CLK_100M_RETIMER_CPU0_P2_DP                                       
P  NNAMEm0875 CLK_100M_RETIMER_CPU0_P2_DN                                       
P  NNAMEm0876 CLK_100M_RETIMER_CPU0_P1_R_DP                                     
P  NNAMEm0877 CLK_100M_RETIMER_CPU0_P1_R_DN                                     
P  NNAMEm0878 CLK_100M_RETIMER_CPU0_P1_DP                                       
P  NNAMEm0879 CLK_100M_RETIMER_CPU0_P1_DN                                       
P  NNAMEm0880 CLK_100M_RETIMER_CPU0_P0_R_DP                                     
P  NNAMEm0881 CLK_100M_RETIMER_CPU0_P0_R_DN                                     
P  NNAMEm0882 CLK_100M_RETIMER_CPU0_P0_DP                                       
P  NNAMEm0883 CLK_100M_RETIMER_CPU0_P0_DN                                       
P  NNAMEm0884 CLK_100M_CPU1_CLK13_R_DP                                          
P  NNAMEm0885 CLK_100M_CPU1_CLK13_R_DN                                          
P  NNAMEm0886 CLK_100M_CPU1_CLK13_DP                                            
P  NNAMEm0887 CLK_100M_CPU1_CLK13_DN                                            
P  NNAMEm0888 CLK_100M_CPU0_CLK13_R_DP                                          
P  NNAMEm0889 CLK_100M_CPU0_CLK13_R_DN                                          
P  NNAMEm0890 CLK_100M_CPU0_CLK13_DP                                            
P  NNAMEm0891 CLK_100M_CPU0_CLK13_DN                                            
P  NNAMEm0892 SW_P1V8_RETIMER_CPU0_SW                                           
P  NNAMEm0893 SW_P1V8_RETIMER_CPU0_BST                                          
P  NNAMEm0894 SW_P12V_AUX_P1V8_RETIMER_CPU0_FLT                                 
P  NNAMEm0895 PWRGD_P1V8_RETIMER_CPU0                                           
P  NNAMEm0896 P1V8_RETIMER_CPU0_VCC                                             
P  NNAMEm0897 P1V8_RETIMER_CPU0_REF                                             
P  NNAMEm0898 P1V8_RETIMER_CPU0_MODE                                            
P  NNAMEm0899 P1V8_RETIMER_CPU0_FB                                              
P  NNAMEm0900 P1V8_RETIMER_CPU0_EN                                              
P  NNAMEm0901 P1V8_RETIMER_CPU0_CS                                              
P  NNAMEm0902 P1V8_CPU0_RT_1D                                                   
P  NNAMEm0903 FM_PWRGD_P1V8_RETIMER_CPU0                                        
P  NNAMEm0904 USB_HUB2_TI_TEST                                                  
P  NNAMEm0905 SW_P3V3_EN_ISO_R                                                  
P  NNAMEm0906 PWRGD_P3V3_EN_R                                                   
P  NNAMEm0907 P5E_CPU1_P3_TX_BUF_DP<9>                                          
P  NNAMEm0908 P5E_CPU1_P3_TX_BUF_DP<8>                                          
P  NNAMEm0909 P5E_CPU1_P3_TX_BUF_DP<7>                                          
P  NNAMEm0910 P5E_CPU1_P3_TX_BUF_DP<6>                                          
P  NNAMEm0911 P5E_CPU1_P3_TX_BUF_DP<5>                                          
P  NNAMEm0912 P5E_CPU1_P3_TX_BUF_DP<4>                                          
P  NNAMEm0913 P5E_CPU1_P3_TX_BUF_DP<3>                                          
P  NNAMEm0914 P5E_CPU1_P3_TX_BUF_DP<2>                                          
P  NNAMEm0915 P5E_CPU1_P3_TX_BUF_DP<1>                                          
P  NNAMEm0916 P5E_CPU1_P3_TX_BUF_DP<15>                                         
P  NNAMEm0917 P5E_CPU1_P3_TX_BUF_DP<14>                                         
P  NNAMEm0918 P5E_CPU1_P3_TX_BUF_DP<13>                                         
P  NNAMEm0919 P5E_CPU1_P3_TX_BUF_DP<12>                                         
P  NNAMEm0920 P5E_CPU1_P3_TX_BUF_DP<11>                                         
P  NNAMEm0921 P5E_CPU1_P3_TX_BUF_DP<10>                                         
P  NNAMEm0922 P5E_CPU1_P3_TX_BUF_DP<0>                                          
P  NNAMEm0923 P5E_CPU1_P3_TX_BUF_DN<9>                                          
P  NNAMEm0924 P5E_CPU1_P3_TX_BUF_DN<8>                                          
P  NNAMEm0925 P5E_CPU1_P3_TX_BUF_DN<7>                                          
P  NNAMEm0926 P5E_CPU1_P3_TX_BUF_DN<6>                                          
P  NNAMEm0927 P5E_CPU1_P3_TX_BUF_DN<5>                                          
P  NNAMEm0928 P5E_CPU1_P3_TX_BUF_DN<4>                                          
P  NNAMEm0929 P5E_CPU1_P3_TX_BUF_DN<3>                                          
P  NNAMEm0930 P5E_CPU1_P3_TX_BUF_DN<2>                                          
P  NNAMEm0931 P5E_CPU1_P3_TX_BUF_DN<1>                                          
P  NNAMEm0932 P5E_CPU1_P3_TX_BUF_DN<15>                                         
P  NNAMEm0933 P5E_CPU1_P3_TX_BUF_DN<14>                                         
P  NNAMEm0934 P5E_CPU1_P3_TX_BUF_DN<13>                                         
P  NNAMEm0935 P5E_CPU1_P3_TX_BUF_DN<12>                                         
P  NNAMEm0936 P5E_CPU1_P3_TX_BUF_DN<11>                                         
P  NNAMEm0937 P5E_CPU1_P3_TX_BUF_DN<10>                                         
P  NNAMEm0938 P5E_CPU1_P3_TX_BUF_DN<0>                                          
P  NNAMEm0939 P5E_CPU1_P3_TX_BUF_C_DP<9>                                        
P  NNAMEm0940 P5E_CPU1_P3_TX_BUF_C_DP<8>                                        
P  NNAMEm0941 P5E_CPU1_P3_TX_BUF_C_DP<7>                                        
P  NNAMEm0942 P5E_CPU1_P3_TX_BUF_C_DP<6>                                        
P  NNAMEm0943 P5E_CPU1_P3_TX_BUF_C_DP<5>                                        
P  NNAMEm0944 P5E_CPU1_P3_TX_BUF_C_DP<4>                                        
P  NNAMEm0945 P5E_CPU1_P3_TX_BUF_C_DP<3>                                        
P  NNAMEm0946 P5E_CPU1_P3_TX_BUF_C_DP<2>                                        
P  NNAMEm0947 P5E_CPU1_P3_TX_BUF_C_DP<1>                                        
P  NNAMEm0948 P5E_CPU1_P3_TX_BUF_C_DP<15>                                       
P  NNAMEm0949 P5E_CPU1_P3_TX_BUF_C_DP<14>                                       
P  NNAMEm0950 P5E_CPU1_P3_TX_BUF_C_DP<13>                                       
P  NNAMEm0951 P5E_CPU1_P3_TX_BUF_C_DP<12>                                       
P  NNAMEm0952 P5E_CPU1_P3_TX_BUF_C_DP<11>                                       
P  NNAMEm0953 P5E_CPU1_P3_TX_BUF_C_DP<10>                                       
P  NNAMEm0954 P5E_CPU1_P3_TX_BUF_C_DP<0>                                        
P  NNAMEm0955 P5E_CPU1_P3_TX_BUF_C_DN<9>                                        
P  NNAMEm0956 P5E_CPU1_P3_TX_BUF_C_DN<8>                                        
P  NNAMEm0957 P5E_CPU1_P3_TX_BUF_C_DN<7>                                        
P  NNAMEm0958 P5E_CPU1_P3_TX_BUF_C_DN<6>                                        
P  NNAMEm0959 P5E_CPU1_P3_TX_BUF_C_DN<5>                                        
P  NNAMEm0960 P5E_CPU1_P3_TX_BUF_C_DN<4>                                        
P  NNAMEm0961 P5E_CPU1_P3_TX_BUF_C_DN<3>                                        
P  NNAMEm0962 P5E_CPU1_P3_TX_BUF_C_DN<2>                                        
P  NNAMEm0963 P5E_CPU1_P3_TX_BUF_C_DN<1>                                        
P  NNAMEm0964 P5E_CPU1_P3_TX_BUF_C_DN<15>                                       
P  NNAMEm0965 P5E_CPU1_P3_TX_BUF_C_DN<14>                                       
P  NNAMEm0966 P5E_CPU1_P3_TX_BUF_C_DN<13>                                       
P  NNAMEm0967 P5E_CPU1_P3_TX_BUF_C_DN<12>                                       
P  NNAMEm0968 P5E_CPU1_P3_TX_BUF_C_DN<11>                                       
P  NNAMEm0969 P5E_CPU1_P3_TX_BUF_C_DN<10>                                       
P  NNAMEm0970 P5E_CPU1_P3_TX_BUF_C_DN<0>                                        
P  NNAMEm0971 P5E_CPU1_P3_RX_BUF_DP<9>                                          
P  NNAMEm0972 P5E_CPU1_P3_RX_BUF_DP<8>                                          
P  NNAMEm0973 P5E_CPU1_P3_RX_BUF_DP<7>                                          
P  NNAMEm0974 P5E_CPU1_P3_RX_BUF_DP<6>                                          
P  NNAMEm0975 P5E_CPU1_P3_RX_BUF_DP<5>                                          
P  NNAMEm0976 P5E_CPU1_P3_RX_BUF_DP<4>                                          
P  NNAMEm0977 P5E_CPU1_P3_RX_BUF_DP<3>                                          
P  NNAMEm0978 P5E_CPU1_P3_RX_BUF_DP<2>                                          
P  NNAMEm0979 P5E_CPU1_P3_RX_BUF_DP<1>                                          
P  NNAMEm0980 P5E_CPU1_P3_RX_BUF_DP<15>                                         
P  NNAMEm0981 P5E_CPU1_P3_RX_BUF_DP<14>                                         
P  NNAMEm0982 P5E_CPU1_P3_RX_BUF_DP<13>                                         
P  NNAMEm0983 P5E_CPU1_P3_RX_BUF_DP<12>                                         
P  NNAMEm0984 P5E_CPU1_P3_RX_BUF_DP<11>                                         
P  NNAMEm0985 P5E_CPU1_P3_RX_BUF_DP<10>                                         
P  NNAMEm0986 P5E_CPU1_P3_RX_BUF_DP<0>                                          
P  NNAMEm0987 P5E_CPU1_P3_RX_BUF_DN<9>                                          
P  NNAMEm0988 P5E_CPU1_P3_RX_BUF_DN<8>                                          
P  NNAMEm0989 P5E_CPU1_P3_RX_BUF_DN<7>                                          
P  NNAMEm0990 P5E_CPU1_P3_RX_BUF_DN<6>                                          
P  NNAMEm0991 P5E_CPU1_P3_RX_BUF_DN<5>                                          
P  NNAMEm0992 P5E_CPU1_P3_RX_BUF_DN<4>                                          
P  NNAMEm0993 P5E_CPU1_P3_RX_BUF_DN<3>                                          
P  NNAMEm0994 P5E_CPU1_P3_RX_BUF_DN<2>                                          
P  NNAMEm0995 P5E_CPU1_P3_RX_BUF_DN<1>                                          
P  NNAMEm0996 P5E_CPU1_P3_RX_BUF_DN<15>                                         
P  NNAMEm0997 P5E_CPU1_P3_RX_BUF_DN<14>                                         
P  NNAMEm0998 P5E_CPU1_P3_RX_BUF_DN<13>                                         
P  NNAMEm0999 P5E_CPU1_P3_RX_BUF_DN<12>                                         
P  NNAMEm1000 P5E_CPU1_P3_RX_BUF_DN<11>                                         
P  NNAMEm1001 P5E_CPU1_P3_RX_BUF_DN<10>                                         
P  NNAMEm1002 P5E_CPU1_P3_RX_BUF_DN<0>                                          
P  NNAMEm1003 P5E_CPU1_P2_TX_BUF_DP<9>                                          
P  NNAMEm1004 P5E_CPU1_P2_TX_BUF_DP<8>                                          
P  NNAMEm1005 P5E_CPU1_P2_TX_BUF_DP<7>                                          
P  NNAMEm1006 P5E_CPU1_P2_TX_BUF_DP<6>                                          
P  NNAMEm1007 P5E_CPU1_P2_TX_BUF_DP<5>                                          
P  NNAMEm1008 P5E_CPU1_P2_TX_BUF_DP<4>                                          
P  NNAMEm1009 P5E_CPU1_P2_TX_BUF_DP<3>                                          
P  NNAMEm1010 P5E_CPU1_P2_TX_BUF_DP<2>                                          
P  NNAMEm1011 P5E_CPU1_P2_TX_BUF_DP<1>                                          
P  NNAMEm1012 P5E_CPU1_P2_TX_BUF_DP<15>                                         
P  NNAMEm1013 P5E_CPU1_P2_TX_BUF_DP<14>                                         
P  NNAMEm1014 P5E_CPU1_P2_TX_BUF_DP<13>                                         
P  NNAMEm1015 P5E_CPU1_P2_TX_BUF_DP<12>                                         
P  NNAMEm1016 P5E_CPU1_P2_TX_BUF_DP<11>                                         
P  NNAMEm1017 P5E_CPU1_P2_TX_BUF_DP<10>                                         
P  NNAMEm1018 P5E_CPU1_P2_TX_BUF_DP<0>                                          
P  NNAMEm1019 P5E_CPU1_P2_TX_BUF_DN<9>                                          
P  NNAMEm1020 P5E_CPU1_P2_TX_BUF_DN<8>                                          
P  NNAMEm1021 P5E_CPU1_P2_TX_BUF_DN<7>                                          
P  NNAMEm1022 P5E_CPU1_P2_TX_BUF_DN<6>                                          
P  NNAMEm1023 P5E_CPU1_P2_TX_BUF_DN<5>                                          
P  NNAMEm1024 P5E_CPU1_P2_TX_BUF_DN<4>                                          
P  NNAMEm1025 P5E_CPU1_P2_TX_BUF_DN<3>                                          
P  NNAMEm1026 P5E_CPU1_P2_TX_BUF_DN<2>                                          
P  NNAMEm1027 P5E_CPU1_P2_TX_BUF_DN<1>                                          
P  NNAMEm1028 P5E_CPU1_P2_TX_BUF_DN<15>                                         
P  NNAMEm1029 P5E_CPU1_P2_TX_BUF_DN<14>                                         
P  NNAMEm1030 P5E_CPU1_P2_TX_BUF_DN<13>                                         
P  NNAMEm1031 P5E_CPU1_P2_TX_BUF_DN<12>                                         
P  NNAMEm1032 P5E_CPU1_P2_TX_BUF_DN<11>                                         
P  NNAMEm1033 P5E_CPU1_P2_TX_BUF_DN<10>                                         
P  NNAMEm1034 P5E_CPU1_P2_TX_BUF_DN<0>                                          
P  NNAMEm1035 P5E_CPU1_P2_TX_BUF_C_DP<9>                                        
P  NNAMEm1036 P5E_CPU1_P2_TX_BUF_C_DP<8>                                        
P  NNAMEm1037 P5E_CPU1_P2_TX_BUF_C_DP<7>                                        
P  NNAMEm1038 P5E_CPU1_P2_TX_BUF_C_DP<6>                                        
P  NNAMEm1039 P5E_CPU1_P2_TX_BUF_C_DP<5>                                        
P  NNAMEm1040 P5E_CPU1_P2_TX_BUF_C_DP<4>                                        
P  NNAMEm1041 P5E_CPU1_P2_TX_BUF_C_DP<3>                                        
P  NNAMEm1042 P5E_CPU1_P2_TX_BUF_C_DP<2>                                        
P  NNAMEm1043 P5E_CPU1_P2_TX_BUF_C_DP<1>                                        
P  NNAMEm1044 P5E_CPU1_P2_TX_BUF_C_DP<15>                                       
P  NNAMEm1045 P5E_CPU1_P2_TX_BUF_C_DP<14>                                       
P  NNAMEm1046 P5E_CPU1_P2_TX_BUF_C_DP<13>                                       
P  NNAMEm1047 P5E_CPU1_P2_TX_BUF_C_DP<12>                                       
P  NNAMEm1048 P5E_CPU1_P2_TX_BUF_C_DP<11>                                       
P  NNAMEm1049 P5E_CPU1_P2_TX_BUF_C_DP<10>                                       
P  NNAMEm1050 P5E_CPU1_P2_TX_BUF_C_DP<0>                                        
P  NNAMEm1051 P5E_CPU1_P2_TX_BUF_C_DN<9>                                        
P  NNAMEm1052 P5E_CPU1_P2_TX_BUF_C_DN<8>                                        
P  NNAMEm1053 P5E_CPU1_P2_TX_BUF_C_DN<7>                                        
P  NNAMEm1054 P5E_CPU1_P2_TX_BUF_C_DN<6>                                        
P  NNAMEm1055 P5E_CPU1_P2_TX_BUF_C_DN<5>                                        
P  NNAMEm1056 P5E_CPU1_P2_TX_BUF_C_DN<4>                                        
P  NNAMEm1057 P5E_CPU1_P2_TX_BUF_C_DN<3>                                        
P  NNAMEm1058 P5E_CPU1_P2_TX_BUF_C_DN<2>                                        
P  NNAMEm1059 P5E_CPU1_P2_TX_BUF_C_DN<1>                                        
P  NNAMEm1060 P5E_CPU1_P2_TX_BUF_C_DN<15>                                       
P  NNAMEm1061 P5E_CPU1_P2_TX_BUF_C_DN<14>                                       
P  NNAMEm1062 P5E_CPU1_P2_TX_BUF_C_DN<13>                                       
P  NNAMEm1063 P5E_CPU1_P2_TX_BUF_C_DN<12>                                       
P  NNAMEm1064 P5E_CPU1_P2_TX_BUF_C_DN<11>                                       
P  NNAMEm1065 P5E_CPU1_P2_TX_BUF_C_DN<10>                                       
P  NNAMEm1066 P5E_CPU1_P2_TX_BUF_C_DN<0>                                        
P  NNAMEm1067 P5E_CPU1_P2_RX_BUF_DP<9>                                          
P  NNAMEm1068 P5E_CPU1_P2_RX_BUF_DP<8>                                          
P  NNAMEm1069 P5E_CPU1_P2_RX_BUF_DP<7>                                          
P  NNAMEm1070 P5E_CPU1_P2_RX_BUF_DP<6>                                          
P  NNAMEm1071 P5E_CPU1_P2_RX_BUF_DP<5>                                          
P  NNAMEm1072 P5E_CPU1_P2_RX_BUF_DP<4>                                          
P  NNAMEm1073 P5E_CPU1_P2_RX_BUF_DP<3>                                          
P  NNAMEm1074 P5E_CPU1_P2_RX_BUF_DP<2>                                          
P  NNAMEm1075 P5E_CPU1_P2_RX_BUF_DP<1>                                          
P  NNAMEm1076 P5E_CPU1_P2_RX_BUF_DP<15>                                         
P  NNAMEm1077 P5E_CPU1_P2_RX_BUF_DP<14>                                         
P  NNAMEm1078 P5E_CPU1_P2_RX_BUF_DP<13>                                         
P  NNAMEm1079 P5E_CPU1_P2_RX_BUF_DP<12>                                         
P  NNAMEm1080 P5E_CPU1_P2_RX_BUF_DP<11>                                         
P  NNAMEm1081 P5E_CPU1_P2_RX_BUF_DP<10>                                         
P  NNAMEm1082 P5E_CPU1_P2_RX_BUF_DP<0>                                          
P  NNAMEm1083 P5E_CPU1_P2_RX_BUF_DN<9>                                          
P  NNAMEm1084 P5E_CPU1_P2_RX_BUF_DN<8>                                          
P  NNAMEm1085 P5E_CPU1_P2_RX_BUF_DN<7>                                          
P  NNAMEm1086 P5E_CPU1_P2_RX_BUF_DN<6>                                          
P  NNAMEm1087 P5E_CPU1_P2_RX_BUF_DN<5>                                          
P  NNAMEm1088 P5E_CPU1_P2_RX_BUF_DN<4>                                          
P  NNAMEm1089 P5E_CPU1_P2_RX_BUF_DN<3>                                          
P  NNAMEm1090 P5E_CPU1_P2_RX_BUF_DN<2>                                          
P  NNAMEm1091 P5E_CPU1_P2_RX_BUF_DN<1>                                          
P  NNAMEm1092 P5E_CPU1_P2_RX_BUF_DN<15>                                         
P  NNAMEm1093 P5E_CPU1_P2_RX_BUF_DN<14>                                         
P  NNAMEm1094 P5E_CPU1_P2_RX_BUF_DN<13>                                         
P  NNAMEm1095 P5E_CPU1_P2_RX_BUF_DN<12>                                         
P  NNAMEm1096 P5E_CPU1_P2_RX_BUF_DN<11>                                         
P  NNAMEm1097 P5E_CPU1_P2_RX_BUF_DN<10>                                         
P  NNAMEm1098 P5E_CPU1_P2_RX_BUF_DN<0>                                          
P  NNAMEm1099 P5E_CPU1_P1_TX_BUF_DP<9>                                          
P  NNAMEm1100 P5E_CPU1_P1_TX_BUF_DP<8>                                          
P  NNAMEm1101 P5E_CPU1_P1_TX_BUF_DP<7>                                          
P  NNAMEm1102 P5E_CPU1_P1_TX_BUF_DP<6>                                          
P  NNAMEm1103 P5E_CPU1_P1_TX_BUF_DP<5>                                          
P  NNAMEm1104 P5E_CPU1_P1_TX_BUF_DP<4>                                          
P  NNAMEm1105 P5E_CPU1_P1_TX_BUF_DP<3>                                          
P  NNAMEm1106 P5E_CPU1_P1_TX_BUF_DP<2>                                          
P  NNAMEm1107 P5E_CPU1_P1_TX_BUF_DP<1>                                          
P  NNAMEm1108 P5E_CPU1_P1_TX_BUF_DP<15>                                         
P  NNAMEm1109 P5E_CPU1_P1_TX_BUF_DP<14>                                         
P  NNAMEm1110 P5E_CPU1_P1_TX_BUF_DP<13>                                         
P  NNAMEm1111 P5E_CPU1_P1_TX_BUF_DP<12>                                         
P  NNAMEm1112 P5E_CPU1_P1_TX_BUF_DP<11>                                         
P  NNAMEm1113 P5E_CPU1_P1_TX_BUF_DP<10>                                         
P  NNAMEm1114 P5E_CPU1_P1_TX_BUF_DP<0>                                          
P  NNAMEm1115 P5E_CPU1_P1_TX_BUF_DN<9>                                          
P  NNAMEm1116 P5E_CPU1_P1_TX_BUF_DN<8>                                          
P  NNAMEm1117 P5E_CPU1_P1_TX_BUF_DN<7>                                          
P  NNAMEm1118 P5E_CPU1_P1_TX_BUF_DN<6>                                          
P  NNAMEm1119 P5E_CPU1_P1_TX_BUF_DN<5>                                          
P  NNAMEm1120 P5E_CPU1_P1_TX_BUF_DN<4>                                          
P  NNAMEm1121 P5E_CPU1_P1_TX_BUF_DN<3>                                          
P  NNAMEm1122 P5E_CPU1_P1_TX_BUF_DN<2>                                          
P  NNAMEm1123 P5E_CPU1_P1_TX_BUF_DN<1>                                          
P  NNAMEm1124 P5E_CPU1_P1_TX_BUF_DN<15>                                         
P  NNAMEm1125 P5E_CPU1_P1_TX_BUF_DN<14>                                         
P  NNAMEm1126 P5E_CPU1_P1_TX_BUF_DN<13>                                         
P  NNAMEm1127 P5E_CPU1_P1_TX_BUF_DN<12>                                         
P  NNAMEm1128 P5E_CPU1_P1_TX_BUF_DN<11>                                         
P  NNAMEm1129 P5E_CPU1_P1_TX_BUF_DN<10>                                         
P  NNAMEm1130 P5E_CPU1_P1_TX_BUF_DN<0>                                          
P  NNAMEm1131 P5E_CPU1_P1_TX_BUF_C_DP<9>                                        
P  NNAMEm1132 P5E_CPU1_P1_TX_BUF_C_DP<8>                                        
P  NNAMEm1133 P5E_CPU1_P1_TX_BUF_C_DP<7>                                        
P  NNAMEm1134 P5E_CPU1_P1_TX_BUF_C_DP<6>                                        
P  NNAMEm1135 P5E_CPU1_P1_TX_BUF_C_DP<5>                                        
P  NNAMEm1136 P5E_CPU1_P1_TX_BUF_C_DP<4>                                        
P  NNAMEm1137 P5E_CPU1_P1_TX_BUF_C_DP<3>                                        
P  NNAMEm1138 P5E_CPU1_P1_TX_BUF_C_DP<2>                                        
P  NNAMEm1139 P5E_CPU1_P1_TX_BUF_C_DP<1>                                        
P  NNAMEm1140 P5E_CPU1_P1_TX_BUF_C_DP<15>                                       
P  NNAMEm1141 P5E_CPU1_P1_TX_BUF_C_DP<14>                                       
P  NNAMEm1142 P5E_CPU1_P1_TX_BUF_C_DP<13>                                       
P  NNAMEm1143 P5E_CPU1_P1_TX_BUF_C_DP<12>                                       
P  NNAMEm1144 P5E_CPU1_P1_TX_BUF_C_DP<11>                                       
P  NNAMEm1145 P5E_CPU1_P1_TX_BUF_C_DP<10>                                       
P  NNAMEm1146 P5E_CPU1_P1_TX_BUF_C_DP<0>                                        
P  NNAMEm1147 P5E_CPU1_P1_TX_BUF_C_DN<9>                                        
P  NNAMEm1148 P5E_CPU1_P1_TX_BUF_C_DN<8>                                        
P  NNAMEm1149 P5E_CPU1_P1_TX_BUF_C_DN<7>                                        
P  NNAMEm1150 P5E_CPU1_P1_TX_BUF_C_DN<6>                                        
P  NNAMEm1151 P5E_CPU1_P1_TX_BUF_C_DN<5>                                        
P  NNAMEm1152 P5E_CPU1_P1_TX_BUF_C_DN<4>                                        
P  NNAMEm1153 P5E_CPU1_P1_TX_BUF_C_DN<3>                                        
P  NNAMEm1154 P5E_CPU1_P1_TX_BUF_C_DN<2>                                        
P  NNAMEm1155 P5E_CPU1_P1_TX_BUF_C_DN<1>                                        
P  NNAMEm1156 P5E_CPU1_P1_TX_BUF_C_DN<15>                                       
P  NNAMEm1157 P5E_CPU1_P1_TX_BUF_C_DN<14>                                       
P  NNAMEm1158 P5E_CPU1_P1_TX_BUF_C_DN<13>                                       
P  NNAMEm1159 P5E_CPU1_P1_TX_BUF_C_DN<12>                                       
P  NNAMEm1160 P5E_CPU1_P1_TX_BUF_C_DN<11>                                       
P  NNAMEm1161 P5E_CPU1_P1_TX_BUF_C_DN<10>                                       
P  NNAMEm1162 P5E_CPU1_P1_TX_BUF_C_DN<0>                                        
P  NNAMEm1163 P5E_CPU1_P1_RX_BUF_DP<9>                                          
P  NNAMEm1164 P5E_CPU1_P1_RX_BUF_DP<8>                                          
P  NNAMEm1165 P5E_CPU1_P1_RX_BUF_DP<7>                                          
P  NNAMEm1166 P5E_CPU1_P1_RX_BUF_DP<6>                                          
P  NNAMEm1167 P5E_CPU1_P1_RX_BUF_DP<5>                                          
P  NNAMEm1168 P5E_CPU1_P1_RX_BUF_DP<4>                                          
P  NNAMEm1169 P5E_CPU1_P1_RX_BUF_DP<3>                                          
P  NNAMEm1170 P5E_CPU1_P1_RX_BUF_DP<2>                                          
P  NNAMEm1171 P5E_CPU1_P1_RX_BUF_DP<1>                                          
P  NNAMEm1172 P5E_CPU1_P1_RX_BUF_DP<15>                                         
P  NNAMEm1173 P5E_CPU1_P1_RX_BUF_DP<14>                                         
P  NNAMEm1174 P5E_CPU1_P1_RX_BUF_DP<13>                                         
P  NNAMEm1175 P5E_CPU1_P1_RX_BUF_DP<12>                                         
P  NNAMEm1176 P5E_CPU1_P1_RX_BUF_DP<11>                                         
P  NNAMEm1177 P5E_CPU1_P1_RX_BUF_DP<10>                                         
P  NNAMEm1178 P5E_CPU1_P1_RX_BUF_DP<0>                                          
P  NNAMEm1179 P5E_CPU1_P1_RX_BUF_DN<9>                                          
P  NNAMEm1180 P5E_CPU1_P1_RX_BUF_DN<8>                                          
P  NNAMEm1181 P5E_CPU1_P1_RX_BUF_DN<7>                                          
P  NNAMEm1182 P5E_CPU1_P1_RX_BUF_DN<6>                                          
P  NNAMEm1183 P5E_CPU1_P1_RX_BUF_DN<5>                                          
P  NNAMEm1184 P5E_CPU1_P1_RX_BUF_DN<4>                                          
P  NNAMEm1185 P5E_CPU1_P1_RX_BUF_DN<3>                                          
P  NNAMEm1186 P5E_CPU1_P1_RX_BUF_DN<2>                                          
P  NNAMEm1187 P5E_CPU1_P1_RX_BUF_DN<1>                                          
P  NNAMEm1188 P5E_CPU1_P1_RX_BUF_DN<15>                                         
P  NNAMEm1189 P5E_CPU1_P1_RX_BUF_DN<14>                                         
P  NNAMEm1190 P5E_CPU1_P1_RX_BUF_DN<13>                                         
P  NNAMEm1191 P5E_CPU1_P1_RX_BUF_DN<12>                                         
P  NNAMEm1192 P5E_CPU1_P1_RX_BUF_DN<11>                                         
P  NNAMEm1193 P5E_CPU1_P1_RX_BUF_DN<10>                                         
P  NNAMEm1194 P5E_CPU1_P1_RX_BUF_DN<0>                                          
P  NNAMEm1195 P5E_CPU1_P0_TX_BUF_DP<9>                                          
P  NNAMEm1196 P5E_CPU1_P0_TX_BUF_DP<8>                                          
P  NNAMEm1197 P5E_CPU1_P0_TX_BUF_DP<7>                                          
P  NNAMEm1198 P5E_CPU1_P0_TX_BUF_DP<6>                                          
P  NNAMEm1199 P5E_CPU1_P0_TX_BUF_DP<5>                                          
P  NNAMEm1200 P5E_CPU1_P0_TX_BUF_DP<4>                                          
P  NNAMEm1201 P5E_CPU1_P0_TX_BUF_DP<3>                                          
P  NNAMEm1202 P5E_CPU1_P0_TX_BUF_DP<2>                                          
P  NNAMEm1203 P5E_CPU1_P0_TX_BUF_DP<1>                                          
P  NNAMEm1204 P5E_CPU1_P0_TX_BUF_DP<15>                                         
P  NNAMEm1205 P5E_CPU1_P0_TX_BUF_DP<14>                                         
P  NNAMEm1206 P5E_CPU1_P0_TX_BUF_DP<13>                                         
P  NNAMEm1207 P5E_CPU1_P0_TX_BUF_DP<12>                                         
P  NNAMEm1208 P5E_CPU1_P0_TX_BUF_DP<11>                                         
P  NNAMEm1209 P5E_CPU1_P0_TX_BUF_DP<10>                                         
P  NNAMEm1210 P5E_CPU1_P0_TX_BUF_DP<0>                                          
P  NNAMEm1211 P5E_CPU1_P0_TX_BUF_DN<9>                                          
P  NNAMEm1212 P5E_CPU1_P0_TX_BUF_DN<8>                                          
P  NNAMEm1213 P5E_CPU1_P0_TX_BUF_DN<7>                                          
P  NNAMEm1214 P5E_CPU1_P0_TX_BUF_DN<6>                                          
P  NNAMEm1215 P5E_CPU1_P0_TX_BUF_DN<5>                                          
P  NNAMEm1216 P5E_CPU1_P0_TX_BUF_DN<4>                                          
P  NNAMEm1217 P5E_CPU1_P0_TX_BUF_DN<3>                                          
P  NNAMEm1218 P5E_CPU1_P0_TX_BUF_DN<2>                                          
P  NNAMEm1219 P5E_CPU1_P0_TX_BUF_DN<1>                                          
P  NNAMEm1220 P5E_CPU1_P0_TX_BUF_DN<15>                                         
P  NNAMEm1221 P5E_CPU1_P0_TX_BUF_DN<14>                                         
P  NNAMEm1222 P5E_CPU1_P0_TX_BUF_DN<13>                                         
P  NNAMEm1223 P5E_CPU1_P0_TX_BUF_DN<12>                                         
P  NNAMEm1224 P5E_CPU1_P0_TX_BUF_DN<11>                                         
P  NNAMEm1225 P5E_CPU1_P0_TX_BUF_DN<10>                                         
P  NNAMEm1226 P5E_CPU1_P0_TX_BUF_DN<0>                                          
P  NNAMEm1227 P5E_CPU1_P0_TX_BUF_C_DP<9>                                        
P  NNAMEm1228 P5E_CPU1_P0_TX_BUF_C_DP<8>                                        
P  NNAMEm1229 P5E_CPU1_P0_TX_BUF_C_DP<7>                                        
P  NNAMEm1230 P5E_CPU1_P0_TX_BUF_C_DP<6>                                        
P  NNAMEm1231 P5E_CPU1_P0_TX_BUF_C_DP<5>                                        
P  NNAMEm1232 P5E_CPU1_P0_TX_BUF_C_DP<4>                                        
P  NNAMEm1233 P5E_CPU1_P0_TX_BUF_C_DP<3>                                        
P  NNAMEm1234 P5E_CPU1_P0_TX_BUF_C_DP<2>                                        
P  NNAMEm1235 P5E_CPU1_P0_TX_BUF_C_DP<1>                                        
P  NNAMEm1236 P5E_CPU1_P0_TX_BUF_C_DP<15>                                       
P  NNAMEm1237 P5E_CPU1_P0_TX_BUF_C_DP<14>                                       
P  NNAMEm1238 P5E_CPU1_P0_TX_BUF_C_DP<13>                                       
P  NNAMEm1239 P5E_CPU1_P0_TX_BUF_C_DP<12>                                       
P  NNAMEm1240 P5E_CPU1_P0_TX_BUF_C_DP<11>                                       
P  NNAMEm1241 P5E_CPU1_P0_TX_BUF_C_DP<10>                                       
P  NNAMEm1242 P5E_CPU1_P0_TX_BUF_C_DP<0>                                        
P  NNAMEm1243 P5E_CPU1_P0_TX_BUF_C_DN<9>                                        
P  NNAMEm1244 P5E_CPU1_P0_TX_BUF_C_DN<8>                                        
P  NNAMEm1245 P5E_CPU1_P0_TX_BUF_C_DN<7>                                        
P  NNAMEm1246 P5E_CPU1_P0_TX_BUF_C_DN<6>                                        
P  NNAMEm1247 P5E_CPU1_P0_TX_BUF_C_DN<5>                                        
P  NNAMEm1248 P5E_CPU1_P0_TX_BUF_C_DN<4>                                        
P  NNAMEm1249 P5E_CPU1_P0_TX_BUF_C_DN<3>                                        
P  NNAMEm1250 P5E_CPU1_P0_TX_BUF_C_DN<2>                                        
P  NNAMEm1251 P5E_CPU1_P0_TX_BUF_C_DN<1>                                        
P  NNAMEm1252 P5E_CPU1_P0_TX_BUF_C_DN<15>                                       
P  NNAMEm1253 P5E_CPU1_P0_TX_BUF_C_DN<14>                                       
P  NNAMEm1254 P5E_CPU1_P0_TX_BUF_C_DN<13>                                       
P  NNAMEm1255 P5E_CPU1_P0_TX_BUF_C_DN<12>                                       
P  NNAMEm1256 P5E_CPU1_P0_TX_BUF_C_DN<11>                                       
P  NNAMEm1257 P5E_CPU1_P0_TX_BUF_C_DN<10>                                       
P  NNAMEm1258 P5E_CPU1_P0_TX_BUF_C_DN<0>                                        
P  NNAMEm1259 P5E_CPU1_P0_RX_BUF_DP<9>                                          
P  NNAMEm1260 P5E_CPU1_P0_RX_BUF_DP<8>                                          
P  NNAMEm1261 P5E_CPU1_P0_RX_BUF_DP<7>                                          
P  NNAMEm1262 P5E_CPU1_P0_RX_BUF_DP<6>                                          
P  NNAMEm1263 P5E_CPU1_P0_RX_BUF_DP<5>                                          
P  NNAMEm1264 P5E_CPU1_P0_RX_BUF_DP<4>                                          
P  NNAMEm1265 P5E_CPU1_P0_RX_BUF_DP<3>                                          
P  NNAMEm1266 P5E_CPU1_P0_RX_BUF_DP<2>                                          
P  NNAMEm1267 P5E_CPU1_P0_RX_BUF_DP<1>                                          
P  NNAMEm1268 P5E_CPU1_P0_RX_BUF_DP<15>                                         
P  NNAMEm1269 P5E_CPU1_P0_RX_BUF_DP<14>                                         
P  NNAMEm1270 P5E_CPU1_P0_RX_BUF_DP<13>                                         
P  NNAMEm1271 P5E_CPU1_P0_RX_BUF_DP<12>                                         
P  NNAMEm1272 P5E_CPU1_P0_RX_BUF_DP<11>                                         
P  NNAMEm1273 P5E_CPU1_P0_RX_BUF_DP<10>                                         
P  NNAMEm1274 P5E_CPU1_P0_RX_BUF_DP<0>                                          
P  NNAMEm1275 P5E_CPU1_P0_RX_BUF_DN<9>                                          
P  NNAMEm1276 P5E_CPU1_P0_RX_BUF_DN<8>                                          
P  NNAMEm1277 P5E_CPU1_P0_RX_BUF_DN<7>                                          
P  NNAMEm1278 P5E_CPU1_P0_RX_BUF_DN<6>                                          
P  NNAMEm1279 P5E_CPU1_P0_RX_BUF_DN<5>                                          
P  NNAMEm1280 P5E_CPU1_P0_RX_BUF_DN<4>                                          
P  NNAMEm1281 P5E_CPU1_P0_RX_BUF_DN<3>                                          
P  NNAMEm1282 P5E_CPU1_P0_RX_BUF_DN<2>                                          
P  NNAMEm1283 P5E_CPU1_P0_RX_BUF_DN<1>                                          
P  NNAMEm1284 P5E_CPU1_P0_RX_BUF_DN<15>                                         
P  NNAMEm1285 P5E_CPU1_P0_RX_BUF_DN<14>                                         
P  NNAMEm1286 P5E_CPU1_P0_RX_BUF_DN<13>                                         
P  NNAMEm1287 P5E_CPU1_P0_RX_BUF_DN<12>                                         
P  NNAMEm1288 P5E_CPU1_P0_RX_BUF_DN<11>                                         
P  NNAMEm1289 P5E_CPU1_P0_RX_BUF_DN<10>                                         
P  NNAMEm1290 P5E_CPU1_P0_RX_BUF_DN<0>                                          
P  NNAMEm1291 P5E_CPU0_P3_TX_BUF_DP<9>                                          
P  NNAMEm1292 P5E_CPU0_P3_TX_BUF_DP<8>                                          
P  NNAMEm1293 P5E_CPU0_P3_TX_BUF_DP<7>                                          
P  NNAMEm1294 P5E_CPU0_P3_TX_BUF_DP<6>                                          
P  NNAMEm1295 P5E_CPU0_P3_TX_BUF_DP<5>                                          
P  NNAMEm1296 P5E_CPU0_P3_TX_BUF_DP<4>                                          
P  NNAMEm1297 P5E_CPU0_P3_TX_BUF_DP<3>                                          
P  NNAMEm1298 P5E_CPU0_P3_TX_BUF_DP<2>                                          
P  NNAMEm1299 P5E_CPU0_P3_TX_BUF_DP<1>                                          
P  NNAMEm1300 P5E_CPU0_P3_TX_BUF_DP<15>                                         
P  NNAMEm1301 P5E_CPU0_P3_TX_BUF_DP<14>                                         
P  NNAMEm1302 P5E_CPU0_P3_TX_BUF_DP<13>                                         
P  NNAMEm1303 P5E_CPU0_P3_TX_BUF_DP<12>                                         
P  NNAMEm1304 P5E_CPU0_P3_TX_BUF_DP<11>                                         
P  NNAMEm1305 P5E_CPU0_P3_TX_BUF_DP<10>                                         
P  NNAMEm1306 P5E_CPU0_P3_TX_BUF_DP<0>                                          
P  NNAMEm1307 P5E_CPU0_P3_TX_BUF_DN<9>                                          
P  NNAMEm1308 P5E_CPU0_P3_TX_BUF_DN<8>                                          
P  NNAMEm1309 P5E_CPU0_P3_TX_BUF_DN<7>                                          
P  NNAMEm1310 P5E_CPU0_P3_TX_BUF_DN<6>                                          
P  NNAMEm1311 P5E_CPU0_P3_TX_BUF_DN<5>                                          
P  NNAMEm1312 P5E_CPU0_P3_TX_BUF_DN<4>                                          
P  NNAMEm1313 P5E_CPU0_P3_TX_BUF_DN<3>                                          
P  NNAMEm1314 P5E_CPU0_P3_TX_BUF_DN<2>                                          
P  NNAMEm1315 P5E_CPU0_P3_TX_BUF_DN<1>                                          
P  NNAMEm1316 P5E_CPU0_P3_TX_BUF_DN<15>                                         
P  NNAMEm1317 P5E_CPU0_P3_TX_BUF_DN<14>                                         
P  NNAMEm1318 P5E_CPU0_P3_TX_BUF_DN<13>                                         
P  NNAMEm1319 P5E_CPU0_P3_TX_BUF_DN<12>                                         
P  NNAMEm1320 P5E_CPU0_P3_TX_BUF_DN<11>                                         
P  NNAMEm1321 P5E_CPU0_P3_TX_BUF_DN<10>                                         
P  NNAMEm1322 P5E_CPU0_P3_TX_BUF_DN<0>                                          
P  NNAMEm1323 P5E_CPU0_P3_TX_BUF_C_DP<9>                                        
P  NNAMEm1324 P5E_CPU0_P3_TX_BUF_C_DP<8>                                        
P  NNAMEm1325 P5E_CPU0_P3_TX_BUF_C_DP<7>                                        
P  NNAMEm1326 P5E_CPU0_P3_TX_BUF_C_DP<6>                                        
P  NNAMEm1327 P5E_CPU0_P3_TX_BUF_C_DP<5>                                        
P  NNAMEm1328 P5E_CPU0_P3_TX_BUF_C_DP<4>                                        
P  NNAMEm1329 P5E_CPU0_P3_TX_BUF_C_DP<3>                                        
P  NNAMEm1330 P5E_CPU0_P3_TX_BUF_C_DP<2>                                        
P  NNAMEm1331 P5E_CPU0_P3_TX_BUF_C_DP<1>                                        
P  NNAMEm1332 P5E_CPU0_P3_TX_BUF_C_DP<15>                                       
P  NNAMEm1333 P5E_CPU0_P3_TX_BUF_C_DP<14>                                       
P  NNAMEm1334 P5E_CPU0_P3_TX_BUF_C_DP<13>                                       
P  NNAMEm1335 P5E_CPU0_P3_TX_BUF_C_DP<12>                                       
P  NNAMEm1336 P5E_CPU0_P3_TX_BUF_C_DP<11>                                       
P  NNAMEm1337 P5E_CPU0_P3_TX_BUF_C_DP<10>                                       
P  NNAMEm1338 P5E_CPU0_P3_TX_BUF_C_DP<0>                                        
P  NNAMEm1339 P5E_CPU0_P3_TX_BUF_C_DN<9>                                        
P  NNAMEm1340 P5E_CPU0_P3_TX_BUF_C_DN<8>                                        
P  NNAMEm1341 P5E_CPU0_P3_TX_BUF_C_DN<7>                                        
P  NNAMEm1342 P5E_CPU0_P3_TX_BUF_C_DN<6>                                        
P  NNAMEm1343 P5E_CPU0_P3_TX_BUF_C_DN<5>                                        
P  NNAMEm1344 P5E_CPU0_P3_TX_BUF_C_DN<4>                                        
P  NNAMEm1345 P5E_CPU0_P3_TX_BUF_C_DN<3>                                        
P  NNAMEm1346 P5E_CPU0_P3_TX_BUF_C_DN<2>                                        
P  NNAMEm1347 P5E_CPU0_P3_TX_BUF_C_DN<1>                                        
P  NNAMEm1348 P5E_CPU0_P3_TX_BUF_C_DN<15>                                       
P  NNAMEm1349 P5E_CPU0_P3_TX_BUF_C_DN<14>                                       
P  NNAMEm1350 P5E_CPU0_P3_TX_BUF_C_DN<13>                                       
P  NNAMEm1351 P5E_CPU0_P3_TX_BUF_C_DN<12>                                       
P  NNAMEm1352 P5E_CPU0_P3_TX_BUF_C_DN<11>                                       
P  NNAMEm1353 P5E_CPU0_P3_TX_BUF_C_DN<10>                                       
P  NNAMEm1354 P5E_CPU0_P3_TX_BUF_C_DN<0>                                        
P  NNAMEm1355 P5E_CPU0_P3_RX_BUF_DP<9>                                          
P  NNAMEm1356 P5E_CPU0_P3_RX_BUF_DP<8>                                          
P  NNAMEm1357 P5E_CPU0_P3_RX_BUF_DP<7>                                          
P  NNAMEm1358 P5E_CPU0_P3_RX_BUF_DP<6>                                          
P  NNAMEm1359 P5E_CPU0_P3_RX_BUF_DP<5>                                          
P  NNAMEm1360 P5E_CPU0_P3_RX_BUF_DP<4>                                          
P  NNAMEm1361 P5E_CPU0_P3_RX_BUF_DP<3>                                          
P  NNAMEm1362 P5E_CPU0_P3_RX_BUF_DP<2>                                          
P  NNAMEm1363 P5E_CPU0_P3_RX_BUF_DP<1>                                          
P  NNAMEm1364 P5E_CPU0_P3_RX_BUF_DP<15>                                         
P  NNAMEm1365 P5E_CPU0_P3_RX_BUF_DP<14>                                         
P  NNAMEm1366 P5E_CPU0_P3_RX_BUF_DP<13>                                         
P  NNAMEm1367 P5E_CPU0_P3_RX_BUF_DP<12>                                         
P  NNAMEm1368 P5E_CPU0_P3_RX_BUF_DP<11>                                         
P  NNAMEm1369 P5E_CPU0_P3_RX_BUF_DP<10>                                         
P  NNAMEm1370 P5E_CPU0_P3_RX_BUF_DP<0>                                          
P  NNAMEm1371 P5E_CPU0_P3_RX_BUF_DN<9>                                          
P  NNAMEm1372 P5E_CPU0_P3_RX_BUF_DN<8>                                          
P  NNAMEm1373 P5E_CPU0_P3_RX_BUF_DN<7>                                          
P  NNAMEm1374 P5E_CPU0_P3_RX_BUF_DN<6>                                          
P  NNAMEm1375 P5E_CPU0_P3_RX_BUF_DN<5>                                          
P  NNAMEm1376 P5E_CPU0_P3_RX_BUF_DN<4>                                          
P  NNAMEm1377 P5E_CPU0_P3_RX_BUF_DN<3>                                          
P  NNAMEm1378 P5E_CPU0_P3_RX_BUF_DN<2>                                          
P  NNAMEm1379 P5E_CPU0_P3_RX_BUF_DN<1>                                          
P  NNAMEm1380 P5E_CPU0_P3_RX_BUF_DN<15>                                         
P  NNAMEm1381 P5E_CPU0_P3_RX_BUF_DN<14>                                         
P  NNAMEm1382 P5E_CPU0_P3_RX_BUF_DN<13>                                         
P  NNAMEm1383 P5E_CPU0_P3_RX_BUF_DN<12>                                         
P  NNAMEm1384 P5E_CPU0_P3_RX_BUF_DN<11>                                         
P  NNAMEm1385 P5E_CPU0_P3_RX_BUF_DN<10>                                         
P  NNAMEm1386 P5E_CPU0_P3_RX_BUF_DN<0>                                          
P  NNAMEm1387 P5E_CPU0_P2_TX_BUF_DP<9>                                          
P  NNAMEm1388 P5E_CPU0_P2_TX_BUF_DP<8>                                          
P  NNAMEm1389 P5E_CPU0_P2_TX_BUF_DP<7>                                          
P  NNAMEm1390 P5E_CPU0_P2_TX_BUF_DP<6>                                          
P  NNAMEm1391 P5E_CPU0_P2_TX_BUF_DP<5>                                          
P  NNAMEm1392 P5E_CPU0_P2_TX_BUF_DP<4>                                          
P  NNAMEm1393 P5E_CPU0_P2_TX_BUF_DP<3>                                          
P  NNAMEm1394 P5E_CPU0_P2_TX_BUF_DP<2>                                          
P  NNAMEm1395 P5E_CPU0_P2_TX_BUF_DP<1>                                          
P  NNAMEm1396 P5E_CPU0_P2_TX_BUF_DP<15>                                         
P  NNAMEm1397 P5E_CPU0_P2_TX_BUF_DP<14>                                         
P  NNAMEm1398 P5E_CPU0_P2_TX_BUF_DP<13>                                         
P  NNAMEm1399 P5E_CPU0_P2_TX_BUF_DP<12>                                         
P  NNAMEm1400 P5E_CPU0_P2_TX_BUF_DP<11>                                         
P  NNAMEm1401 P5E_CPU0_P2_TX_BUF_DP<10>                                         
P  NNAMEm1402 P5E_CPU0_P2_TX_BUF_DP<0>                                          
P  NNAMEm1403 P5E_CPU0_P2_TX_BUF_DN<9>                                          
P  NNAMEm1404 P5E_CPU0_P2_TX_BUF_DN<8>                                          
P  NNAMEm1405 P5E_CPU0_P2_TX_BUF_DN<7>                                          
P  NNAMEm1406 P5E_CPU0_P2_TX_BUF_DN<6>                                          
P  NNAMEm1407 P5E_CPU0_P2_TX_BUF_DN<5>                                          
P  NNAMEm1408 P5E_CPU0_P2_TX_BUF_DN<4>                                          
P  NNAMEm1409 P5E_CPU0_P2_TX_BUF_DN<3>                                          
P  NNAMEm1410 P5E_CPU0_P2_TX_BUF_DN<2>                                          
P  NNAMEm1411 P5E_CPU0_P2_TX_BUF_DN<1>                                          
P  NNAMEm1412 P5E_CPU0_P2_TX_BUF_DN<15>                                         
P  NNAMEm1413 P5E_CPU0_P2_TX_BUF_DN<14>                                         
P  NNAMEm1414 P5E_CPU0_P2_TX_BUF_DN<13>                                         
P  NNAMEm1415 P5E_CPU0_P2_TX_BUF_DN<12>                                         
P  NNAMEm1416 P5E_CPU0_P2_TX_BUF_DN<11>                                         
P  NNAMEm1417 P5E_CPU0_P2_TX_BUF_DN<10>                                         
P  NNAMEm1418 P5E_CPU0_P2_TX_BUF_DN<0>                                          
P  NNAMEm1419 P5E_CPU0_P2_TX_BUF_C_DP<9>                                        
P  NNAMEm1420 P5E_CPU0_P2_TX_BUF_C_DP<8>                                        
P  NNAMEm1421 P5E_CPU0_P2_TX_BUF_C_DP<7>                                        
P  NNAMEm1422 P5E_CPU0_P2_TX_BUF_C_DP<6>                                        
P  NNAMEm1423 P5E_CPU0_P2_TX_BUF_C_DP<5>                                        
P  NNAMEm1424 P5E_CPU0_P2_TX_BUF_C_DP<4>                                        
P  NNAMEm1425 P5E_CPU0_P2_TX_BUF_C_DP<3>                                        
P  NNAMEm1426 P5E_CPU0_P2_TX_BUF_C_DP<2>                                        
P  NNAMEm1427 P5E_CPU0_P2_TX_BUF_C_DP<1>                                        
P  NNAMEm1428 P5E_CPU0_P2_TX_BUF_C_DP<15>                                       
P  NNAMEm1429 P5E_CPU0_P2_TX_BUF_C_DP<14>                                       
P  NNAMEm1430 P5E_CPU0_P2_TX_BUF_C_DP<13>                                       
P  NNAMEm1431 P5E_CPU0_P2_TX_BUF_C_DP<12>                                       
P  NNAMEm1432 P5E_CPU0_P2_TX_BUF_C_DP<11>                                       
P  NNAMEm1433 P5E_CPU0_P2_TX_BUF_C_DP<10>                                       
P  NNAMEm1434 P5E_CPU0_P2_TX_BUF_C_DP<0>                                        
P  NNAMEm1435 P5E_CPU0_P2_TX_BUF_C_DN<9>                                        
P  NNAMEm1436 P5E_CPU0_P2_TX_BUF_C_DN<8>                                        
P  NNAMEm1437 P5E_CPU0_P2_TX_BUF_C_DN<7>                                        
P  NNAMEm1438 P5E_CPU0_P2_TX_BUF_C_DN<6>                                        
P  NNAMEm1439 P5E_CPU0_P2_TX_BUF_C_DN<5>                                        
P  NNAMEm1440 P5E_CPU0_P2_TX_BUF_C_DN<4>                                        
P  NNAMEm1441 P5E_CPU0_P2_TX_BUF_C_DN<3>                                        
P  NNAMEm1442 P5E_CPU0_P2_TX_BUF_C_DN<2>                                        
P  NNAMEm1443 P5E_CPU0_P2_TX_BUF_C_DN<1>                                        
P  NNAMEm1444 P5E_CPU0_P2_TX_BUF_C_DN<15>                                       
P  NNAMEm1445 P5E_CPU0_P2_TX_BUF_C_DN<14>                                       
P  NNAMEm1446 P5E_CPU0_P2_TX_BUF_C_DN<13>                                       
P  NNAMEm1447 P5E_CPU0_P2_TX_BUF_C_DN<12>                                       
P  NNAMEm1448 P5E_CPU0_P2_TX_BUF_C_DN<11>                                       
P  NNAMEm1449 P5E_CPU0_P2_TX_BUF_C_DN<10>                                       
P  NNAMEm1450 P5E_CPU0_P2_TX_BUF_C_DN<0>                                        
P  NNAMEm1451 P5E_CPU0_P2_RX_BUF_DP<9>                                          
P  NNAMEm1452 P5E_CPU0_P2_RX_BUF_DP<8>                                          
P  NNAMEm1453 P5E_CPU0_P2_RX_BUF_DP<7>                                          
P  NNAMEm1454 P5E_CPU0_P2_RX_BUF_DP<6>                                          
P  NNAMEm1455 P5E_CPU0_P2_RX_BUF_DP<5>                                          
P  NNAMEm1456 P5E_CPU0_P2_RX_BUF_DP<4>                                          
P  NNAMEm1457 P5E_CPU0_P2_RX_BUF_DP<3>                                          
P  NNAMEm1458 P5E_CPU0_P2_RX_BUF_DP<2>                                          
P  NNAMEm1459 P5E_CPU0_P2_RX_BUF_DP<1>                                          
P  NNAMEm1460 P5E_CPU0_P2_RX_BUF_DP<15>                                         
P  NNAMEm1461 P5E_CPU0_P2_RX_BUF_DP<14>                                         
P  NNAMEm1462 P5E_CPU0_P2_RX_BUF_DP<13>                                         
P  NNAMEm1463 P5E_CPU0_P2_RX_BUF_DP<12>                                         
P  NNAMEm1464 P5E_CPU0_P2_RX_BUF_DP<11>                                         
P  NNAMEm1465 P5E_CPU0_P2_RX_BUF_DP<10>                                         
P  NNAMEm1466 P5E_CPU0_P2_RX_BUF_DP<0>                                          
P  NNAMEm1467 P5E_CPU0_P2_RX_BUF_DN<9>                                          
P  NNAMEm1468 P5E_CPU0_P2_RX_BUF_DN<8>                                          
P  NNAMEm1469 P5E_CPU0_P2_RX_BUF_DN<7>                                          
P  NNAMEm1470 P5E_CPU0_P2_RX_BUF_DN<6>                                          
P  NNAMEm1471 P5E_CPU0_P2_RX_BUF_DN<5>                                          
P  NNAMEm1472 P5E_CPU0_P2_RX_BUF_DN<4>                                          
P  NNAMEm1473 P5E_CPU0_P2_RX_BUF_DN<3>                                          
P  NNAMEm1474 P5E_CPU0_P2_RX_BUF_DN<2>                                          
P  NNAMEm1475 P5E_CPU0_P2_RX_BUF_DN<1>                                          
P  NNAMEm1476 P5E_CPU0_P2_RX_BUF_DN<15>                                         
P  NNAMEm1477 P5E_CPU0_P2_RX_BUF_DN<14>                                         
P  NNAMEm1478 P5E_CPU0_P2_RX_BUF_DN<13>                                         
P  NNAMEm1479 P5E_CPU0_P2_RX_BUF_DN<12>                                         
P  NNAMEm1480 P5E_CPU0_P2_RX_BUF_DN<11>                                         
P  NNAMEm1481 P5E_CPU0_P2_RX_BUF_DN<10>                                         
P  NNAMEm1482 P5E_CPU0_P2_RX_BUF_DN<0>                                          
P  NNAMEm1483 P5E_CPU0_P1_TX_BUF_DP<9>                                          
P  NNAMEm1484 P5E_CPU0_P1_TX_BUF_DP<8>                                          
P  NNAMEm1485 P5E_CPU0_P1_TX_BUF_DP<7>                                          
P  NNAMEm1486 P5E_CPU0_P1_TX_BUF_DP<6>                                          
P  NNAMEm1487 P5E_CPU0_P1_TX_BUF_DP<5>                                          
P  NNAMEm1488 P5E_CPU0_P1_TX_BUF_DP<4>                                          
P  NNAMEm1489 P5E_CPU0_P1_TX_BUF_DP<3>                                          
P  NNAMEm1490 P5E_CPU0_P1_TX_BUF_DP<2>                                          
P  NNAMEm1491 P5E_CPU0_P1_TX_BUF_DP<1>                                          
P  NNAMEm1492 P5E_CPU0_P1_TX_BUF_DP<15>                                         
P  NNAMEm1493 P5E_CPU0_P1_TX_BUF_DP<14>                                         
P  NNAMEm1494 P5E_CPU0_P1_TX_BUF_DP<13>                                         
P  NNAMEm1495 P5E_CPU0_P1_TX_BUF_DP<12>                                         
P  NNAMEm1496 P5E_CPU0_P1_TX_BUF_DP<11>                                         
P  NNAMEm1497 P5E_CPU0_P1_TX_BUF_DP<10>                                         
P  NNAMEm1498 P5E_CPU0_P1_TX_BUF_DP<0>                                          
P  NNAMEm1499 P5E_CPU0_P1_TX_BUF_DN<9>                                          
P  NNAMEm1500 P5E_CPU0_P1_TX_BUF_DN<8>                                          
P  NNAMEm1501 P5E_CPU0_P1_TX_BUF_DN<7>                                          
P  NNAMEm1502 P5E_CPU0_P1_TX_BUF_DN<6>                                          
P  NNAMEm1503 P5E_CPU0_P1_TX_BUF_DN<5>                                          
P  NNAMEm1504 P5E_CPU0_P1_TX_BUF_DN<4>                                          
P  NNAMEm1505 P5E_CPU0_P1_TX_BUF_DN<3>                                          
P  NNAMEm1506 P5E_CPU0_P1_TX_BUF_DN<2>                                          
P  NNAMEm1507 P5E_CPU0_P1_TX_BUF_DN<1>                                          
P  NNAMEm1508 P5E_CPU0_P1_TX_BUF_DN<15>                                         
P  NNAMEm1509 P5E_CPU0_P1_TX_BUF_DN<14>                                         
P  NNAMEm1510 P5E_CPU0_P1_TX_BUF_DN<13>                                         
P  NNAMEm1511 P5E_CPU0_P1_TX_BUF_DN<12>                                         
P  NNAMEm1512 P5E_CPU0_P1_TX_BUF_DN<11>                                         
P  NNAMEm1513 P5E_CPU0_P1_TX_BUF_DN<10>                                         
P  NNAMEm1514 P5E_CPU0_P1_TX_BUF_DN<0>                                          
P  NNAMEm1515 P5E_CPU0_P1_TX_BUF_C_DP<9>                                        
P  NNAMEm1516 P5E_CPU0_P1_TX_BUF_C_DP<8>                                        
P  NNAMEm1517 P5E_CPU0_P1_TX_BUF_C_DP<7>                                        
P  NNAMEm1518 P5E_CPU0_P1_TX_BUF_C_DP<6>                                        
P  NNAMEm1519 P5E_CPU0_P1_TX_BUF_C_DP<5>                                        
P  NNAMEm1520 P5E_CPU0_P1_TX_BUF_C_DP<4>                                        
P  NNAMEm1521 P5E_CPU0_P1_TX_BUF_C_DP<3>                                        
P  NNAMEm1522 P5E_CPU0_P1_TX_BUF_C_DP<2>                                        
P  NNAMEm1523 P5E_CPU0_P1_TX_BUF_C_DP<1>                                        
P  NNAMEm1524 P5E_CPU0_P1_TX_BUF_C_DP<15>                                       
P  NNAMEm1525 P5E_CPU0_P1_TX_BUF_C_DP<14>                                       
P  NNAMEm1526 P5E_CPU0_P1_TX_BUF_C_DP<13>                                       
P  NNAMEm1527 P5E_CPU0_P1_TX_BUF_C_DP<12>                                       
P  NNAMEm1528 P5E_CPU0_P1_TX_BUF_C_DP<11>                                       
P  NNAMEm1529 P5E_CPU0_P1_TX_BUF_C_DP<10>                                       
P  NNAMEm1530 P5E_CPU0_P1_TX_BUF_C_DP<0>                                        
P  NNAMEm1531 P5E_CPU0_P1_TX_BUF_C_DN<9>                                        
P  NNAMEm1532 P5E_CPU0_P1_TX_BUF_C_DN<8>                                        
P  NNAMEm1533 P5E_CPU0_P1_TX_BUF_C_DN<7>                                        
P  NNAMEm1534 P5E_CPU0_P1_TX_BUF_C_DN<6>                                        
P  NNAMEm1535 P5E_CPU0_P1_TX_BUF_C_DN<5>                                        
P  NNAMEm1536 P5E_CPU0_P1_TX_BUF_C_DN<4>                                        
P  NNAMEm1537 P5E_CPU0_P1_TX_BUF_C_DN<3>                                        
P  NNAMEm1538 P5E_CPU0_P1_TX_BUF_C_DN<2>                                        
P  NNAMEm1539 P5E_CPU0_P1_TX_BUF_C_DN<1>                                        
P  NNAMEm1540 P5E_CPU0_P1_TX_BUF_C_DN<15>                                       
P  NNAMEm1541 P5E_CPU0_P1_TX_BUF_C_DN<14>                                       
P  NNAMEm1542 P5E_CPU0_P1_TX_BUF_C_DN<13>                                       
P  NNAMEm1543 P5E_CPU0_P1_TX_BUF_C_DN<12>                                       
P  NNAMEm1544 P5E_CPU0_P1_TX_BUF_C_DN<11>                                       
P  NNAMEm1545 P5E_CPU0_P1_TX_BUF_C_DN<10>                                       
P  NNAMEm1546 P5E_CPU0_P1_TX_BUF_C_DN<0>                                        
P  NNAMEm1547 P5E_CPU0_P1_RX_BUF_DP<9>                                          
P  NNAMEm1548 P5E_CPU0_P1_RX_BUF_DP<8>                                          
P  NNAMEm1549 P5E_CPU0_P1_RX_BUF_DP<7>                                          
P  NNAMEm1550 P5E_CPU0_P1_RX_BUF_DP<6>                                          
P  NNAMEm1551 P5E_CPU0_P1_RX_BUF_DP<5>                                          
P  NNAMEm1552 P5E_CPU0_P1_RX_BUF_DP<4>                                          
P  NNAMEm1553 P5E_CPU0_P1_RX_BUF_DP<3>                                          
P  NNAMEm1554 P5E_CPU0_P1_RX_BUF_DP<2>                                          
P  NNAMEm1555 P5E_CPU0_P1_RX_BUF_DP<1>                                          
P  NNAMEm1556 P5E_CPU0_P1_RX_BUF_DP<15>                                         
P  NNAMEm1557 P5E_CPU0_P1_RX_BUF_DP<14>                                         
P  NNAMEm1558 P5E_CPU0_P1_RX_BUF_DP<13>                                         
P  NNAMEm1559 P5E_CPU0_P1_RX_BUF_DP<12>                                         
P  NNAMEm1560 P5E_CPU0_P1_RX_BUF_DP<11>                                         
P  NNAMEm1561 P5E_CPU0_P1_RX_BUF_DP<10>                                         
P  NNAMEm1562 P5E_CPU0_P1_RX_BUF_DP<0>                                          
P  NNAMEm1563 P5E_CPU0_P1_RX_BUF_DN<9>                                          
P  NNAMEm1564 P5E_CPU0_P1_RX_BUF_DN<8>                                          
P  NNAMEm1565 P5E_CPU0_P1_RX_BUF_DN<7>                                          
P  NNAMEm1566 P5E_CPU0_P1_RX_BUF_DN<6>                                          
P  NNAMEm1567 P5E_CPU0_P1_RX_BUF_DN<5>                                          
P  NNAMEm1568 P5E_CPU0_P1_RX_BUF_DN<4>                                          
P  NNAMEm1569 P5E_CPU0_P1_RX_BUF_DN<3>                                          
P  NNAMEm1570 P5E_CPU0_P1_RX_BUF_DN<2>                                          
P  NNAMEm1571 P5E_CPU0_P1_RX_BUF_DN<1>                                          
P  NNAMEm1572 P5E_CPU0_P1_RX_BUF_DN<15>                                         
P  NNAMEm1573 P5E_CPU0_P1_RX_BUF_DN<14>                                         
P  NNAMEm1574 P5E_CPU0_P1_RX_BUF_DN<13>                                         
P  NNAMEm1575 P5E_CPU0_P1_RX_BUF_DN<12>                                         
P  NNAMEm1576 P5E_CPU0_P1_RX_BUF_DN<11>                                         
P  NNAMEm1577 P5E_CPU0_P1_RX_BUF_DN<10>                                         
P  NNAMEm1578 P5E_CPU0_P1_RX_BUF_DN<0>                                          
P  NNAMEm1579 P5E_CPU0_P0_TX_BUF_DP<9>                                          
P  NNAMEm1580 P5E_CPU0_P0_TX_BUF_DP<8>                                          
P  NNAMEm1581 P5E_CPU0_P0_TX_BUF_DP<7>                                          
P  NNAMEm1582 P5E_CPU0_P0_TX_BUF_DP<6>                                          
P  NNAMEm1583 P5E_CPU0_P0_TX_BUF_DP<5>                                          
P  NNAMEm1584 P5E_CPU0_P0_TX_BUF_DP<4>                                          
P  NNAMEm1585 P5E_CPU0_P0_TX_BUF_DP<3>                                          
P  NNAMEm1586 P5E_CPU0_P0_TX_BUF_DP<2>                                          
P  NNAMEm1587 P5E_CPU0_P0_TX_BUF_DP<1>                                          
P  NNAMEm1588 P5E_CPU0_P0_TX_BUF_DP<15>                                         
P  NNAMEm1589 P5E_CPU0_P0_TX_BUF_DP<14>                                         
P  NNAMEm1590 P5E_CPU0_P0_TX_BUF_DP<13>                                         
P  NNAMEm1591 P5E_CPU0_P0_TX_BUF_DP<12>                                         
P  NNAMEm1592 P5E_CPU0_P0_TX_BUF_DP<11>                                         
P  NNAMEm1593 P5E_CPU0_P0_TX_BUF_DP<10>                                         
P  NNAMEm1594 P5E_CPU0_P0_TX_BUF_DP<0>                                          
P  NNAMEm1595 P5E_CPU0_P0_TX_BUF_DN<9>                                          
P  NNAMEm1596 P5E_CPU0_P0_TX_BUF_DN<8>                                          
P  NNAMEm1597 P5E_CPU0_P0_TX_BUF_DN<7>                                          
P  NNAMEm1598 P5E_CPU0_P0_TX_BUF_DN<6>                                          
P  NNAMEm1599 P5E_CPU0_P0_TX_BUF_DN<5>                                          
P  NNAMEm1600 P5E_CPU0_P0_TX_BUF_DN<4>                                          
P  NNAMEm1601 P5E_CPU0_P0_TX_BUF_DN<3>                                          
P  NNAMEm1602 P5E_CPU0_P0_TX_BUF_DN<2>                                          
P  NNAMEm1603 P5E_CPU0_P0_TX_BUF_DN<1>                                          
P  NNAMEm1604 P5E_CPU0_P0_TX_BUF_DN<15>                                         
P  NNAMEm1605 P5E_CPU0_P0_TX_BUF_DN<14>                                         
P  NNAMEm1606 P5E_CPU0_P0_TX_BUF_DN<13>                                         
P  NNAMEm1607 P5E_CPU0_P0_TX_BUF_DN<12>                                         
P  NNAMEm1608 P5E_CPU0_P0_TX_BUF_DN<11>                                         
P  NNAMEm1609 P5E_CPU0_P0_TX_BUF_DN<10>                                         
P  NNAMEm1610 P5E_CPU0_P0_TX_BUF_DN<0>                                          
P  NNAMEm1611 P5E_CPU0_P0_TX_BUF_C_DP<9>                                        
P  NNAMEm1612 P5E_CPU0_P0_TX_BUF_C_DP<8>                                        
P  NNAMEm1613 P5E_CPU0_P0_TX_BUF_C_DP<7>                                        
P  NNAMEm1614 P5E_CPU0_P0_TX_BUF_C_DP<6>                                        
P  NNAMEm1615 P5E_CPU0_P0_TX_BUF_C_DP<5>                                        
P  NNAMEm1616 P5E_CPU0_P0_TX_BUF_C_DP<4>                                        
P  NNAMEm1617 P5E_CPU0_P0_TX_BUF_C_DP<3>                                        
P  NNAMEm1618 P5E_CPU0_P0_TX_BUF_C_DP<2>                                        
P  NNAMEm1619 P5E_CPU0_P0_TX_BUF_C_DP<1>                                        
P  NNAMEm1620 P5E_CPU0_P0_TX_BUF_C_DP<15>                                       
P  NNAMEm1621 P5E_CPU0_P0_TX_BUF_C_DP<14>                                       
P  NNAMEm1622 P5E_CPU0_P0_TX_BUF_C_DP<13>                                       
P  NNAMEm1623 P5E_CPU0_P0_TX_BUF_C_DP<12>                                       
P  NNAMEm1624 P5E_CPU0_P0_TX_BUF_C_DP<11>                                       
P  NNAMEm1625 P5E_CPU0_P0_TX_BUF_C_DP<10>                                       
P  NNAMEm1626 P5E_CPU0_P0_TX_BUF_C_DP<0>                                        
P  NNAMEm1627 P5E_CPU0_P0_TX_BUF_C_DN<9>                                        
P  NNAMEm1628 P5E_CPU0_P0_TX_BUF_C_DN<8>                                        
P  NNAMEm1629 P5E_CPU0_P0_TX_BUF_C_DN<7>                                        
P  NNAMEm1630 P5E_CPU0_P0_TX_BUF_C_DN<6>                                        
P  NNAMEm1631 P5E_CPU0_P0_TX_BUF_C_DN<5>                                        
P  NNAMEm1632 P5E_CPU0_P0_TX_BUF_C_DN<4>                                        
P  NNAMEm1633 P5E_CPU0_P0_TX_BUF_C_DN<3>                                        
P  NNAMEm1634 P5E_CPU0_P0_TX_BUF_C_DN<2>                                        
P  NNAMEm1635 P5E_CPU0_P0_TX_BUF_C_DN<1>                                        
P  NNAMEm1636 P5E_CPU0_P0_TX_BUF_C_DN<15>                                       
P  NNAMEm1637 P5E_CPU0_P0_TX_BUF_C_DN<14>                                       
P  NNAMEm1638 P5E_CPU0_P0_TX_BUF_C_DN<13>                                       
P  NNAMEm1639 P5E_CPU0_P0_TX_BUF_C_DN<12>                                       
P  NNAMEm1640 P5E_CPU0_P0_TX_BUF_C_DN<11>                                       
P  NNAMEm1641 P5E_CPU0_P0_TX_BUF_C_DN<10>                                       
P  NNAMEm1642 P5E_CPU0_P0_TX_BUF_C_DN<0>                                        
P  NNAMEm1643 P5E_CPU0_P0_RX_BUF_DP<9>                                          
P  NNAMEm1644 P5E_CPU0_P0_RX_BUF_DP<8>                                          
P  NNAMEm1645 P5E_CPU0_P0_RX_BUF_DP<7>                                          
P  NNAMEm1646 P5E_CPU0_P0_RX_BUF_DP<6>                                          
P  NNAMEm1647 P5E_CPU0_P0_RX_BUF_DP<5>                                          
P  NNAMEm1648 P5E_CPU0_P0_RX_BUF_DP<4>                                          
P  NNAMEm1649 P5E_CPU0_P0_RX_BUF_DP<3>                                          
P  NNAMEm1650 P5E_CPU0_P0_RX_BUF_DP<2>                                          
P  NNAMEm1651 P5E_CPU0_P0_RX_BUF_DP<1>                                          
P  NNAMEm1652 P5E_CPU0_P0_RX_BUF_DP<15>                                         
P  NNAMEm1653 P5E_CPU0_P0_RX_BUF_DP<14>                                         
P  NNAMEm1654 P5E_CPU0_P0_RX_BUF_DP<13>                                         
P  NNAMEm1655 P5E_CPU0_P0_RX_BUF_DP<12>                                         
P  NNAMEm1656 P5E_CPU0_P0_RX_BUF_DP<11>                                         
P  NNAMEm1657 P5E_CPU0_P0_RX_BUF_DP<10>                                         
P  NNAMEm1658 P5E_CPU0_P0_RX_BUF_DP<0>                                          
P  NNAMEm1659 P5E_CPU0_P0_RX_BUF_DN<9>                                          
P  NNAMEm1660 P5E_CPU0_P0_RX_BUF_DN<8>                                          
P  NNAMEm1661 P5E_CPU0_P0_RX_BUF_DN<7>                                          
P  NNAMEm1662 P5E_CPU0_P0_RX_BUF_DN<6>                                          
P  NNAMEm1663 P5E_CPU0_P0_RX_BUF_DN<5>                                          
P  NNAMEm1664 P5E_CPU0_P0_RX_BUF_DN<4>                                          
P  NNAMEm1665 P5E_CPU0_P0_RX_BUF_DN<3>                                          
P  NNAMEm1666 P5E_CPU0_P0_RX_BUF_DN<2>                                          
P  NNAMEm1667 P5E_CPU0_P0_RX_BUF_DN<1>                                          
P  NNAMEm1668 P5E_CPU0_P0_RX_BUF_DN<15>                                         
P  NNAMEm1669 P5E_CPU0_P0_RX_BUF_DN<14>                                         
P  NNAMEm1670 P5E_CPU0_P0_RX_BUF_DN<13>                                         
P  NNAMEm1671 P5E_CPU0_P0_RX_BUF_DN<12>                                         
P  NNAMEm1672 P5E_CPU0_P0_RX_BUF_DN<11>                                         
P  NNAMEm1673 P5E_CPU0_P0_RX_BUF_DN<10>                                         
P  NNAMEm1674 P5E_CPU0_P0_RX_BUF_DN<0>                                          
P  NNAMEm1675 RST_SRST_PLD_BMC_R_N                                              
P  NNAMEm1676 RST_SRST_PLD_BMC_N                                                
P  NNAMEm1677 P12V_HSC_T_CRIT_R_N                                               
P  NNAMEm1678 P12V_HSC_T_CRIT_N                                                 
P  NNAMEm1679 P12V_HSC_TEMP_ALERT_R_N                                           
P  NNAMEm1680 P12V_HSC_TEMP_ALERT_N                                             
P  NNAMEm1681 HP_LVC3_OCP_V3_2_P12V_PWRGD_R                                     
P  NNAMEm1682 SMB_SML1_PMBUS_HSC_R1_SDA                                         
P  NNAMEm1683 SMB_SML1_PMBUS_HSC_R1_SCL                                         
P  NNAMEm1684 SMB_SCM_2_R6_SDA                                                  
P  NNAMEm1685 SMB_SCM_2_R6_SCL                                                  
P  NNAMEm1686 SMB_SCM_2_R5_SDA                                                  
P  NNAMEm1687 SMB_SCM_2_R5_SCL                                                  
P  NNAMEm1688 SMB_FRU_3V3AUX_R1_SDA                                             
P  NNAMEm1689 SMB_FRU_3V3AUX_R1_SCL                                             
P  NNAMEm1690 SMB_CPU_FRU_3V3AUX_SDA                                            
P  NNAMEm1691 SMB_CPU_FRU_3V3AUX_SCL                                            
P  NNAMEm1692 SMB_CPU0_CPU1_APML_MUX2_SDA                                       
P  NNAMEm1693 SMB_CPU0_CPU1_APML_MUX2_SCL                                       
P  NNAMEm1694 SMB_CPU0_CPU1_APML_MUX1_SDA                                       
P  NNAMEm1695 SMB_CPU0_CPU1_APML_MUX1_SCL                                       
P  NNAMEm1696 SMB_CPU0_CPU1_APML_BUF2_SDA_R2                                    
P  NNAMEm1697 SMB_CPU0_CPU1_APML_BUF2_SDA_R1                                    
P  NNAMEm1698 SMB_CPU0_CPU1_APML_BUF2_SDA                                       
P  NNAMEm1699 SMB_CPU0_CPU1_APML_BUF2_SCL_R2                                    
P  NNAMEm1700 SMB_CPU0_CPU1_APML_BUF2_SCL_R1                                    
P  NNAMEm1701 SMB_CPU0_CPU1_APML_BUF2_SCL                                       
P  NNAMEm1702 SMB_CPU0_CPU1_APML_BUF1_SDA_R2                                    
P  NNAMEm1703 SMB_CPU0_CPU1_APML_BUF1_SDA                                       
P  NNAMEm1704 SMB_CPU0_CPU1_APML_BUF1_SCL_R2                                    
P  NNAMEm1705 SMB_CPU0_CPU1_APML_BUF1_SCL                                       
P  NNAMEm1706 SMB_APML_CPU1_MUX2_SDA                                            
P  NNAMEm1707 SMB_APML_CPU1_MUX2_SCL                                            
P  NNAMEm1708 SMB_APML_CPU0_MUX2_SDA                                            
P  NNAMEm1709 SMB_APML_CPU0_MUX2_SCL                                            
P  NNAMEm1710 RST_PERST_CPU1_SWB_1_R_N                                          
P  NNAMEm1711 RST_PERST_CPU1_SWB_1_N                                            
P  NNAMEm1712 FM_APML_MUX2_SEL_R                                                
P  NNAMEm1713 FM_APML_MUX2_SEL                                                  
P  NNAMEm1714 FM_APML_MUX2_OE_R_N                                               
P  NNAMEm1715 FM_APML_MUX2_OE_N                                                 
P  NNAMEm1716 XTAL_USB_CPU0_HUB2_XOUT                                           
P  NNAMEm1717 XTAL_USB_CPU0_HUB2_XIN                                            
P  NNAMEm1718 USB_HUB2_TI_VDD_MRP_USB3DN_TXDP4                                  
P  NNAMEm1719 USB_HUB2_TI_VDD_MRP_USB3DN_TXDP3                                  
P  NNAMEm1720 USB_HUB2_TI_VDD_MRP_USB3DN_TXDM1                                  
P  NNAMEm1721 USB_HUB2_TI_VDD_MRP_USB3DN_RXDP4                                  
P  NNAMEm1722 USB_HUB2_TI_VDD_MRP_USB3DN_RXDM1                                  
P  NNAMEm1723 USB_HUB2_TI_VDD33_MRP_PRT_CTL4_GANGPWR                            
P  NNAMEm1724 USB_HUB2_TI_VDD33_MRP_PROG_FUNC7                                  
P  NNAMEm1725 USB_HUB2_TI_USB_VBUS_MRP_RESET_N                                  
P  NNAMEm1726 USB_HUB2_TI_USB_VBUS                                              
P  NNAMEm1727 USB_HUB2_TI_USB_SSRXP_DN1_MRP_VDD12                               
P  NNAMEm1728 USB_HUB2_TI_USB_SSRXM_DN4_MRP_VDD12                               
P  NNAMEm1729 USB_HUB2_TI_USB_SSRXM_DN3_MRP_VDD12                               
P  NNAMEm1730 USB_HUB2_TI_USB_R1_MRP_RBIAS                                      
P  NNAMEm1731 USB_HUB2_TI_USB_DP_DN3_MRP_VDD12                                  
P  NNAMEm1732 USB_HUB2_TI_USB_DP_DN1_MRP_CFG_STRAP                              
P  NNAMEm1733 USB_HUB2_TI_USB_DM_DN3_MRP_VDD33                                  
P  NNAMEm1734 USB_HUB2_TI_TEST_MRP_PROG_FUNC6                                   
P  NNAMEm1735 USB_HUB2_TI_SMBUSZ_MRP_PROG_FUNC2                                 
P  NNAMEm1736 SMB_USB_HUB2_TI_SDA_MRP_PRT_CTL2                                  
P  NNAMEm1737 SMB_USB_HUB2_TI_SCL_MRP_PRT_CTL1                                  
P  NNAMEm1738 USB_HUB2_TI_PWRCTL_POL_MRP_VBUS_DET                               
P  NNAMEm1739 USB_HUB2_TI_PWRCTL_POL                                            
P  NNAMEm1740 USB_HUB2_TI_PWRCTL3_MRP_VDD33                                     
P  NNAMEm1741 USB_HUB2_TI_PWRCTL2_MRP_VDD12                                     
P  NNAMEm1742 USB_HUB2_TI_OVERCUR4_MRP_I2C_SLV_CFG1                             
P  NNAMEm1743 USB_HUB2_TI_OVERCUR3_MRP_CFG_BC_EN                                
P  NNAMEm1744 USB_HUB2_TI_OVERCUR3                                              
P  NNAMEm1745 USB_HUB2_TI_OVERCUR2_MRP_PROG_FUNC5                               
P  NNAMEm1746 USB_HUB2_TI_OVERCUR2                                              
P  NNAMEm1747 USB_HUB2_TI_OVERCUR1_MRP_PROG_FUNC4                               
P  NNAMEm1748 USB_HUB2_TI_OVERCUR1                                              
P  NNAMEm1749 USB_HUB2_TI_OVERCCUR4                                             
P  NNAMEm1750 USB_HUB2_TI_NC_MRP_ATEST                                          
P  NNAMEm1751 USB_HUB2_TI_HS_SUSPEND_MRP_CFG_NON_REM                            
P  NNAMEm1752 USB_HUB2_TI_HS_SUSPEND                                            
P  NNAMEm1753 USB_HUB2_TI_GRSTZ_MRP_PROG_FUNC1                                  
P  NNAMEm1754 USB_HUB2_TI_GANGED_MRP_I2C_SLV_CFG0                               
P  NNAMEm1755 USB_HUB2_TI_GANGED                                                
P  NNAMEm1756 USB_HUB2_TI_FULLPWRMGMTZ_MRP_PROG_FUNC3                           
P  NNAMEm1757 USB_HUB2_MRP_VBUS_DET                                             
P  NNAMEm1758 USB_HUB2_MRP_RESET_N                                              
P  NNAMEm1759 USB_HUB2_MRP_PRT_CTL4_GANGPWR                                     
P  NNAMEm1760 USB_HUB2_MRP_PROG_FUNC6                                           
P  NNAMEm1761 USB_HUB2_MRP_I2C_SLV_CFG1                                         
P  NNAMEm1762 USB_HUB2_MRP_I2C_SLV_CFG0                                         
P  NNAMEm1763 USB_HUB2_MRP_CFG_STRAP                                            
P  NNAMEm1764 USB_HUB2_MRP_CFG_NON_REM                                          
P  NNAMEm1765 USB_HUB2_MRP_CFG_BC_EN                                            
P  NNAMEm1766 SMB_HSC_TYPE_ADC_SDA                                              
P  NNAMEm1767 SMB_HSC_TYPE_ADC_SCL                                              
P  NNAMEm1768 P3V3_AUX_CPU0_USB2_AVDD33                                         
P  NNAMEm1769 P1V2_CPU0_USB2_DVDD12                                             
P  NNAMEm1770 NC_HSC_TYPE_VINP                                                  
P  NNAMEm1771 NC_HSC_TYPE_VINM                                                  
P  NNAMEm1772 NC_HSC_TYPE_NC5                                                   
P  NNAMEm1773 NC_HSC_TYPE_NC4                                                   
P  NNAMEm1774 NC_HSC_TYPE_NC3                                                   
P  NNAMEm1775 NC_HSC_TYPE_NC2                                                   
P  NNAMEm1776 NC_HSC_TYPE_NC1                                                   
P  NNAMEm1777 HSC_TYPE_ADC_ALERT                                                
P  NNAMEm1778 HSC_TYPE_ADC_A1                                                   
P  NNAMEm1779 HSC_TYPE_ADC_A0                                                   
P  NNAMEm1780 XTAL_USB_CPU0_HUB1_XOUT                                           
P  NNAMEm1781 XTAL_USB_CPU0_HUB1_XIN                                            
P  NNAMEm1782 USB_CPU0_HUB1_VBUS_US                                             
P  NNAMEm1783 USB_CPU0_HUB1_VBUS_DS                                             
P  NNAMEm1784 USB_CPU0_HUB1_RREF_USB2                                           
P  NNAMEm1785 USB_CPU0_HUB1_RREF_SS                                             
P  NNAMEm1786 USB_CPU0_HUB1_MODE_SEL1                                           
P  NNAMEm1787 USB_CPU0_HUB1_MODE_SEL0                                           
P  NNAMEm1788 USB_CPU0_ADD_A2                                                   
P  NNAMEm1789 USB_CPU0_ADD_A1                                                   
P  NNAMEm1790 USB_CPU0_ADD_A0                                                   
P  NNAMEm1791 USB3_CPU0_BMC_TX_C2_DP                                            
P  NNAMEm1792 USB3_CPU0_BMC_TX_C2_DN                                            
P  NNAMEm1793 USB3_CPU0_BMC_TX_C1_DP                                            
P  NNAMEm1794 USB3_CPU0_BMC_TX_C1_DN                                            
P  NNAMEm1795 USB3_CPU0_BMC_RX_HUB_C_DP                                         
P  NNAMEm1796 USB3_CPU0_BMC_RX_HUB_C_DN                                         
P  NNAMEm1797 USB3_CPU0_BMC_RX_HUB2_DP                                          
P  NNAMEm1798 USB3_CPU0_BMC_RX_HUB2_DN                                          
P  NNAMEm1799 USB3_CPU0_BMC_RX_HUB1_DP                                          
P  NNAMEm1800 USB3_CPU0_BMC_RX_HUB1_DN                                          
P  NNAMEm1801 USB3_CPU0_BMC_RX_C2_DP                                            
P  NNAMEm1802 USB3_CPU0_BMC_RX_C2_DN                                            
P  NNAMEm1803 USB3_CPU0_BMC_RX_C1_DP                                            
P  NNAMEm1804 USB3_CPU0_BMC_RX_C1_DN                                            
P  NNAMEm1805 USB3_CPU0_BMC_HUB2_TX_DP                                          
P  NNAMEm1806 USB3_CPU0_BMC_HUB2_TX_DN                                          
P  NNAMEm1807 USB3_CPU0_BMC_HUB1_TX_DP                                          
P  NNAMEm1808 USB3_CPU0_BMC_HUB1_TX_DN                                          
P  NNAMEm1809 USB2_HUB_EXT_DP                                                   
P  NNAMEm1810 USB2_HUB_EXT_DN                                                   
P  NNAMEm1811 USB2_CPU0_P0_R2_DP                                                
P  NNAMEm1812 USB2_CPU0_P0_R2_DN                                                
P  NNAMEm1813 USB2_CPU0_P0_R1_DP                                                
P  NNAMEm1814 USB2_CPU0_P0_R1_DN                                                
P  NNAMEm1815 USB2_CPU0_P0_HUB2_R_DP                                            
P  NNAMEm1816 USB2_CPU0_P0_HUB2_R_DN                                            
P  NNAMEm1817 USB2_CPU0_P0_HUB1_R_DP                                            
P  NNAMEm1818 USB2_CPU0_P0_HUB1_R_DN                                            
P  NNAMEm1819 TP_CPU0_USB_HUB1_SUSPEND                                          
P  NNAMEm1820 NC_HSC_TYPE_NC0                                                   
P  NNAMEm1821 SW_P12V_AUX_P1V8_AUX_FLT                                          
P  NNAMEm1822 SW_P12V_AUX_P1V2_AUX_FLT                                          
P  NNAMEm1823 SMB_USB_CPU0_HUB1_SDA_R2                                          
P  NNAMEm1824 SMB_USB_CPU0_HUB1_SDA_R                                           
P  NNAMEm1825 SMB_USB_CPU0_HUB1_SDA                                             
P  NNAMEm1826 SMB_USB_CPU0_HUB1_SCL_R2                                          
P  NNAMEm1827 SMB_USB_CPU0_HUB1_SCL_R                                           
P  NNAMEm1828 SMB_USB_CPU0_HUB1_SCL                                             
P  NNAMEm1829 SMB_P12V_HSC_SDA_R                                                
P  NNAMEm1830 SMB_P12V_HSC_SCL_R                                                
P  NNAMEm1831 RST_USB_CPU0_HUB1_R_N                                             
P  NNAMEm1832 PWRGD_P1V2_AUX_R                                                  
P  NNAMEm1833 PU_CPU0_USB_HUB_RESERVED2                                         
P  NNAMEm1834 PU_CPU0_USB_HUB_RESERVED1                                         
P  NNAMEm1835 PU_CPU0_USB_HUB_PWR_EN                                            
P  NNAMEm1836 PU_CPU0_USB_HUB_OVRCURR                                           
P  NNAMEm1837 P3V3_AUX_CPU0_USB_AVDD33                                          
P  NNAMEm1838 P1V8_AUX_ENABLE                                                   
P  NNAMEm1839 P1V2_CPU0_USB_DVDD12                                              
P  NNAMEm1840 P1V2_AUX_ENABLE                                                   
P  NNAMEm1841 LED_PWRGD_P1V2_AUX_D                                              
P  NNAMEm1842 LED_PWRGD_P1V2_AUX                                                
P  NNAMEm1843 A_HSC_LOW_DRAIN                                                   
P  NNAMEm1844 SMB_CPU0_SEC_R_SDA                                                
P  NNAMEm1845 FM_SEC_MUX_R_SEL                                                  
P  NNAMEm1846 FM_SEC_MUX_OE_R_N                                                 
P  NNAMEm1847 FM_SEC_MUX_OE_N                                                   
P  NNAMEm1848 SMB_P12V_HSC_SDA                                                  
P  NNAMEm1849 SMB_P12V_HSC_SCL                                                  
P  NNAMEm1850 PD_P2E_BUF2_ENSMB                                                 
P  NNAMEm1851 P2E_MB_BMC_TX_C_R2_DP<0>                                          
P  NNAMEm1852 P2E_MB_BMC_TX_C_R2_DN<0>                                          
P  NNAMEm1853 P2E_MB_BMC_TX_C_R1_DP<0>                                          
P  NNAMEm1854 P2E_MB_BMC_TX_C_R1_DN<0>                                          
P  NNAMEm1855 P2E_MB_BMC_TX_BUF2_DP<0>                                          
P  NNAMEm1856 P2E_MB_BMC_TX_BUF2_DN<0>                                          
P  NNAMEm1857 P2E_MB_BMC_RX_R2_DP<0>                                            
P  NNAMEm1858 P2E_MB_BMC_RX_R2_DN<0>                                            
P  NNAMEm1859 P2E_MB_BMC_RX_R1_DP<0>                                            
P  NNAMEm1860 P2E_MB_BMC_RX_R1_DN<0>                                            
P  NNAMEm1861 P2E_MB_BMC_RX_BUF2_C_DP<0>                                        
P  NNAMEm1862 P2E_MB_BMC_RX_BUF2_C_DN<0>                                        
P  NNAMEm1863 SMB_P12V_HSC_TEMP_SDA                                             
P  NNAMEm1864 SMB_P12V_HSC_TEMP_SCL                                             
P  NNAMEm1865 P12V_HSC_TEMP_R                                                   
P  NNAMEm1866 P12V_HSC_TEMP_E                                                   
P  NNAMEm1867 P12V_HSC_TEMP_D-                                                  
P  NNAMEm1868 P12V_HSC_TEMP_D+                                                  
P  NNAMEm1869 P12V_HSC_SENSE2_R4_P                                              
P  NNAMEm1870 P12V_HSC_SENSE2_R4_N                                              
P  NNAMEm1871 P12V_HSC_SENSE2_R3_P                                              
P  NNAMEm1872 P12V_HSC_SENSE2_R3_N                                              
P  NNAMEm1873 P12V_HSC_SENSE2_R2_P                                              
P  NNAMEm1874 P12V_HSC_SENSE2_R2_N                                              
P  NNAMEm1875 P12V_HSC_SENSE2_R1_P                                              
P  NNAMEm1876 P12V_HSC_SENSE2_R1_N                                              
P  NNAMEm1877 P12V_HSC_SENSE2_P                                                 
P  NNAMEm1878 P12V_HSC_SENSE2_N                                                 
P  NNAMEm1879 P12V_HSC_SENSE1_P                                                 
P  NNAMEm1880 P12V_HSC_SENSE1_N                                                 
P  NNAMEm1881 P12V_HSC_GATE_RC                                                  
P  NNAMEm1882 P12V_HSC_GATE_G6                                                  
P  NNAMEm1883 P12V_HSC_GATE_G5                                                  
P  NNAMEm1884 P12V_HSC_GATE_G4                                                  
P  NNAMEm1885 P12V_HSC_GATE_G3                                                  
P  NNAMEm1886 P12V_HSC_GATE_G2                                                  
P  NNAMEm1887 P12V_HSC_GATE_G1                                                  
P  NNAMEm1888 FM_P2E_BUF2_VOD_SEL                                               
P  NNAMEm1889 FM_P2E_BUF2_VODB_DB                                               
P  NNAMEm1890 FM_P2E_BUF2_VODA_DB                                               
P  NNAMEm1891 FM_P2E_BUF2_SD_TH                                                 
P  NNAMEm1892 FM_P2E_BUF2_RXDET                                                 
P  NNAMEm1893 FM_P2E_BUF2_EQB1                                                  
P  NNAMEm1894 FM_P2E_BUF2_EQB0                                                  
P  NNAMEm1895 FM_P2E_BUF2_EQA1                                                  
P  NNAMEm1896 FM_P2E_BUF2_EQA0                                                  
P  NNAMEm1897 OCP_SFF_AUX_PWR_EN_R2                                             
P  NNAMEm1898 FM_BOARD_SKU_ID4                                                  
P  NNAMEm1899 FM_BOARD_SKU_ID3                                                  
P  NNAMEm1900 FM_BOARD_SKU_ID2                                                  
P  NNAMEm1901 FM_BOARD_SKU_ID1                                                  
P  NNAMEm1902 FM_BOARD_SKU_ID0                                                  
P  NNAMEm1903 FM_BOARD_BMC_SKU_ID4                                              
P  NNAMEm1904 FM_BOARD_BMC_SKU_ID3                                              
P  NNAMEm1905 FM_BOARD_BMC_SKU_ID2                                              
P  NNAMEm1906 FM_BOARD_BMC_SKU_ID1                                              
P  NNAMEm1907 FM_BOARD_BMC_SKU_ID0                                              
P  NNAMEm1908 FAB_BMC_REV_ID2                                                   
P  NNAMEm1909 FAB_BMC_REV_ID1                                                   
P  NNAMEm1910 FAB_BMC_REV_ID0                                                   
P  NNAMEm1911 TP_SLOT2_BUF_SKU_ID1                                              
P  NNAMEm1912 TP_SLOT2_BUF_SKU_ID0                                              
P  NNAMEm1913 SMB_CPU0_CPU1_SEC_SDA_R                                           
P  NNAMEm1914 SMB_CPU0_CPU1_SEC_SCL_R                                           
P  NNAMEm1915 PWRGD_P5V_AUX_R3                                                  
P  NNAMEm1916 PRSNT_OCP_V3_2_N                                                  
P  NNAMEm1917 FM_GPU_HSC_EN_R                                                   
P  NNAMEm1918 RST_PERST_CPU1_SWB_R_N                                            
P  NNAMEm1919 RST_PERST_CPU1_SWB_N                                              
P  NNAMEm1920 RST_PERST_CPU0_SWB_R_N                                            
P  NNAMEm1921 RST_PERST_CPU0_SWB_N                                              
P  NNAMEm1922 P12V_SCM_PWRGD_R                                                  
P  NNAMEm1923 LED_RST_RSMRST_PLD_R_N_D                                          
P  NNAMEm1924 LED_RST_RSMRST_PLD_R_N                                            
P  NNAMEm1925 LED_PWRGD_PVDDIO_P1_R                                             
P  NNAMEm1926 LED_PWRGD_PVDDIO_P1_D                                             
P  NNAMEm1927 LED_PWRGD_PVDDIO_P0_R                                             
P  NNAMEm1928 LED_PWRGD_PVDDIO_P0_D                                             
P  NNAMEm1929 LED_PWRGD_PVDDCR_SOC_P1_R                                         
P  NNAMEm1930 LED_PWRGD_PVDDCR_SOC_P1_D                                         
P  NNAMEm1931 LED_PWRGD_PVDDCR_SOC_P0_R                                         
P  NNAMEm1932 LED_PWRGD_PVDDCR_SOC_P0_D                                         
P  NNAMEm1933 LED_PWRGD_PVDDCR_CPU1_P1_R                                        
P  NNAMEm1934 LED_PWRGD_PVDDCR_CPU1_P1_D                                        
P  NNAMEm1935 LED_PWRGD_PVDDCR_CPU1_P0_R                                        
P  NNAMEm1936 LED_PWRGD_PVDDCR_CPU1_P0_D                                        
P  NNAMEm1937 LED_PWRGD_PVDDCR_CPU0_P1_R                                        
P  NNAMEm1938 LED_PWRGD_PVDDCR_CPU0_P1_D                                        
P  NNAMEm1939 LED_PWRGD_PVDDCR_CPU0_P0_R                                        
P  NNAMEm1940 LED_PWRGD_PVDDCR_CPU0_P0_D                                        
P  NNAMEm1941 LED_PWRGD_PVDD33_S5_R                                             
P  NNAMEm1942 LED_PWRGD_PVDD33_S5_D                                             
P  NNAMEm1943 LED_PWRGD_PVDD18_S5_P1_R                                          
P  NNAMEm1944 LED_PWRGD_PVDD18_S5_P1_D                                          
P  NNAMEm1945 LED_PWRGD_PVDD18_S5_P0_R                                          
P  NNAMEm1946 LED_PWRGD_PVDD18_S5_P0_D                                          
P  NNAMEm1947 LED_PWRGD_PVDD11_S3_P1_R                                          
P  NNAMEm1948 LED_PWRGD_PVDD11_S3_P1_D                                          
P  NNAMEm1949 LED_PWRGD_PVDD11_S3_P0_R                                          
P  NNAMEm1950 LED_PWRGD_PVDD11_S3_P0_D                                          
P  NNAMEm1951 FM_LED_PWRGD_PVDDIO_P1                                            
P  NNAMEm1952 FM_LED_PWRGD_PVDDIO_P0                                            
P  NNAMEm1953 FM_LED_PWRGD_PVDDCR_SOC_P1                                        
P  NNAMEm1954 FM_LED_PWRGD_PVDDCR_SOC_P0                                        
P  NNAMEm1955 FM_LED_PWRGD_PVDDCR_CPU1_P1                                       
P  NNAMEm1956 FM_LED_PWRGD_PVDDCR_CPU1_P0                                       
P  NNAMEm1957 FM_LED_PWRGD_PVDDCR_CPU0_P1                                       
P  NNAMEm1958 FM_LED_PWRGD_PVDDCR_CPU0_P0                                       
P  NNAMEm1959 FM_LED_PWRGD_PVDD33_S5                                            
P  NNAMEm1960 FM_LED_PWRGD_PVDD18_S5_P1                                         
P  NNAMEm1961 FM_LED_PWRGD_PVDD18_S5_P0                                         
P  NNAMEm1962 FM_LED_PWRGD_PVDD11_S3_P1                                         
P  NNAMEm1963 FM_LED_PWRGD_PVDD11_S3_P0                                         
P  NNAMEm1964 SGPIO_SCM_INTR_R1_N                                               
P  NNAMEm1965 JTAG_CPUX_TDO_R                                                   
P  NNAMEm1966 TDR_SE_50_OHM_TOP                                                 
P  NNAMEm1967 TDR_SE_50_OHM_IN6                                                 
P  NNAMEm1968 TDR_SE_50_OHM_IN5                                                 
P  NNAMEm1969 TDR_SE_50_OHM_IN4                                                 
P  NNAMEm1970 TDR_SE_50_OHM_IN3                                                 
P  NNAMEm1971 TDR_SE_50_OHM_IN2                                                 
P  NNAMEm1972 TDR_SE_50_OHM_IN1                                                 
P  NNAMEm1973 TDR_SE_50_OHM_BOT                                                 
P  NNAMEm1974 TDR_SE_45_OHM_TOP                                                 
P  NNAMEm1975 TDR_SE_45_OHM_IN6                                                 
P  NNAMEm1976 TDR_SE_45_OHM_IN5                                                 
P  NNAMEm1977 TDR_SE_45_OHM_IN4                                                 
P  NNAMEm1978 TDR_SE_45_OHM_IN3                                                 
P  NNAMEm1979 TDR_SE_45_OHM_IN2                                                 
P  NNAMEm1980 TDR_SE_45_OHM_IN1                                                 
P  NNAMEm1981 TDR_SE_45_OHM_BOT                                                 
P  NNAMEm1982 TDR_DIFF_85_TOP_DP                                                
P  NNAMEm1983 TDR_DIFF_85_TOP_DN                                                
P  NNAMEm1984 TDR_DIFF_85_NECK_IN6_DP                                           
P  NNAMEm1985 TDR_DIFF_85_NECK_IN6_DN                                           
P  NNAMEm1986 TDR_DIFF_85_NECK_IN5_DP                                           
P  NNAMEm1987 TDR_DIFF_85_NECK_IN5_DN                                           
P  NNAMEm1988 TDR_DIFF_85_NECK_IN4_DP                                           
P  NNAMEm1989 TDR_DIFF_85_NECK_IN4_DN                                           
P  NNAMEm1990 TDR_DIFF_85_NECK_IN3_DP                                           
P  NNAMEm1991 TDR_DIFF_85_NECK_IN3_DN                                           
P  NNAMEm1992 TDR_DIFF_85_NECK_IN2_DP                                           
P  NNAMEm1993 TDR_DIFF_85_NECK_IN2_DN                                           
P  NNAMEm1994 TDR_DIFF_85_NECK_IN1_DP                                           
P  NNAMEm1995 TDR_DIFF_85_NECK_IN1_DN                                           
P  NNAMEm1996 TDR_DIFF_85_IN6_DP                                                
P  NNAMEm1997 TDR_DIFF_85_IN6_DN                                                
P  NNAMEm1998 TDR_DIFF_85_IN5_DP                                                
P  NNAMEm1999 TDR_DIFF_85_IN5_DN                                                
P  NNAMEm2000 TDR_DIFF_85_IN4_DP                                                
P  NNAMEm2001 TDR_DIFF_85_IN4_DN                                                
P  NNAMEm2002 TDR_DIFF_85_IN3_DP                                                
P  NNAMEm2003 TDR_DIFF_85_IN3_DN                                                
P  NNAMEm2004 TDR_DIFF_85_IN2_DP                                                
P  NNAMEm2005 TDR_DIFF_85_IN2_DN                                                
P  NNAMEm2006 TDR_DIFF_85_IN1_DP                                                
P  NNAMEm2007 TDR_DIFF_85_IN1_DN                                                
P  NNAMEm2008 TDR_DIFF_85_BOT_DP                                                
P  NNAMEm2009 TDR_DIFF_85_BOT_DN                                                
P  NNAMEm2010 TDR_DIFF_80_TOP_DP                                                
P  NNAMEm2011 TDR_DIFF_80_TOP_DN                                                
P  NNAMEm2012 TDR_DIFF_80_IN6_DP                                                
P  NNAMEm2013 TDR_DIFF_80_IN6_DN                                                
P  NNAMEm2014 TDR_DIFF_80_IN5_DP                                                
P  NNAMEm2015 TDR_DIFF_80_IN5_DN                                                
P  NNAMEm2016 TDR_DIFF_80_IN4_DP                                                
P  NNAMEm2017 TDR_DIFF_80_IN4_DN                                                
P  NNAMEm2018 TDR_DIFF_80_IN3_DP                                                
P  NNAMEm2019 TDR_DIFF_80_IN3_DN                                                
P  NNAMEm2020 TDR_DIFF_80_IN2_DP                                                
P  NNAMEm2021 TDR_DIFF_80_IN2_DN                                                
P  NNAMEm2022 TDR_DIFF_80_IN1_DP                                                
P  NNAMEm2023 TDR_DIFF_80_IN1_DN                                                
P  NNAMEm2024 TDR_DIFF_80_BOT_DP                                                
P  NNAMEm2025 TDR_DIFF_80_BOT_DN                                                
P  NNAMEm2026 SCM_JTAG_MUX_S0_R2                                                
P  NNAMEm2027 SCM_JTAG_MUX_S0_R1                                                
P  NNAMEm2028 PWRGD_P3V3_AUX_R1                                                 
P  NNAMEm2029 TP_P12V_AUX_CPU1_DIMM_ISEN_P                                      
P  NNAMEm2030 TP_P12V_AUX_CPU1_DIMM_ISEN_N                                      
P  NNAMEm2031 TP_P12V_AUX_CPU0_DIMM_ISEN_P                                      
P  NNAMEm2032 TP_P12V_AUX_CPU0_DIMM_ISEN_N                                      
P  NNAMEm2033 JTAG_CPUX_TDI_R1                                                  
P  NNAMEm2034 JTAG_CPU0_TDO_CPU1_TDI_R1                                         
P  NNAMEm2035 JTAG_CPU0_BYPASS_R1                                               
P  NNAMEm2036 FM_BIOS_POST_CMPLT_BUF_R1_N                                       
P  NNAMEm2037 DELTA_L_85_5INCH_TOP_DP                                           
P  NNAMEm2038 DELTA_L_85_5INCH_TOP_DN                                           
P  NNAMEm2039 DELTA_L_85_5INCH_IN6_DP                                           
P  NNAMEm2040 DELTA_L_85_5INCH_IN6_DN                                           
P  NNAMEm2041 DELTA_L_85_5INCH_IN5_DP                                           
P  NNAMEm2042 DELTA_L_85_5INCH_IN5_DN                                           
P  NNAMEm2043 DELTA_L_85_5INCH_IN4_DP                                           
P  NNAMEm2044 DELTA_L_85_5INCH_IN4_DN                                           
P  NNAMEm2045 DELTA_L_85_5INCH_IN3_DP                                           
P  NNAMEm2046 DELTA_L_85_5INCH_IN3_DN                                           
P  NNAMEm2047 DELTA_L_85_5INCH_IN2_DP                                           
P  NNAMEm2048 DELTA_L_85_5INCH_IN2_DN                                           
P  NNAMEm2049 DELTA_L_85_5INCH_IN1_DP                                           
P  NNAMEm2050 DELTA_L_85_5INCH_IN1_DN                                           
P  NNAMEm2051 DELTA_L_85_5INCH_BOT_DP                                           
P  NNAMEm2052 DELTA_L_85_5INCH_BOT_DN                                           
P  NNAMEm2053 DELTA_L_85_10INCH_TOP_DP                                          
P  NNAMEm2054 DELTA_L_85_10INCH_TOP_DN                                          
P  NNAMEm2055 DELTA_L_85_10INCH_IN6_DP                                          
P  NNAMEm2056 DELTA_L_85_10INCH_IN6_DN                                          
P  NNAMEm2057 DELTA_L_85_10INCH_IN5_DP                                          
P  NNAMEm2058 DELTA_L_85_10INCH_IN5_DN                                          
P  NNAMEm2059 DELTA_L_85_10INCH_IN4_DP                                          
P  NNAMEm2060 DELTA_L_85_10INCH_IN4_DN                                          
P  NNAMEm2061 DELTA_L_85_10INCH_IN3_DP                                          
P  NNAMEm2062 DELTA_L_85_10INCH_IN3_DN                                          
P  NNAMEm2063 DELTA_L_85_10INCH_IN2_DP                                          
P  NNAMEm2064 DELTA_L_85_10INCH_IN2_DN                                          
P  NNAMEm2065 DELTA_L_85_10INCH_IN1_DP                                          
P  NNAMEm2066 DELTA_L_85_10INCH_IN1_DN                                          
P  NNAMEm2067 DELTA_L_85_10INCH_BOT_DP                                          
P  NNAMEm2068 DELTA_L_85_10INCH_BOT_DN                                          
P  NNAMEm2069 XTAL_CPU1_X48M_X2_R                                               
P  NNAMEm2070 XTAL_CPU0_X48M_X2_R                                               
P  NNAMEm2071 USB2_CPU0_P11_DP                                                  
P  NNAMEm2072 USB2_CPU0_P11_DN                                                  
P  NNAMEm2073 SWB_HSC_PWRGD_ISO_R                                               
P  NNAMEm2074 SCM_SYS_PWROK_R2                                                  
P  NNAMEm2075 SCM_SYS_PWROK_R1                                                  
P  NNAMEm2076 RST_PERST_OCP_V3_2_BUF2_N                                         
P  NNAMEm2077 RST_PERST_OCP_SFF_BUF2_N                                          
P  NNAMEm2078 RST_BMC_FROM_SWB_ISO_R_N                                          
P  NNAMEm2079 PWRGD_P3V3_AUX_R                                                  
P  NNAMEm2080 PWRGD_P1V8_AUX_R                                                  
P  NNAMEm2081 PWRGD_P12V_MEM_R                                                  
P  NNAMEm2082 PWRGD_P12V_MEM_CPU1_R                                             
P  NNAMEm2083 PWRGD_P12V_MEM_CPU1_EN_N                                          
P  NNAMEm2084 PWRGD_P12V_MEM_CPU1_EN                                            
P  NNAMEm2085 PWRGD_P12V_MEM_CPU1                                               
P  NNAMEm2086 PWRGD_P12V_MEM_CPU0_R                                             
P  NNAMEm2087 PWRGD_P12V_MEM_CPU0_EN_N                                          
P  NNAMEm2088 PWRGD_P12V_MEM_CPU0_EN                                            
P  NNAMEm2089 PWRGD_P12V_MEM_CPU0                                               
P  NNAMEm2090 PU_SPI_PLD_CS_N                                                   
P  NNAMEm2091 LED_PWRGD_SYS_PWROK_R_D                                           
P  NNAMEm2092 LED_PWRGD_SYS_PWROK_R                                             
P  NNAMEm2093 LED_PWRGD_P1V8_AUX_D                                              
P  NNAMEm2094 LED_PWRGD_P1V8_AUX                                                
P  NNAMEm2095 IRQ_HSC_FAULT_BUF_R_N                                             
P  NNAMEm2096 HPDB_HSC_PWRGD_ISO_R                                              
P  NNAMEm2097 GPU_WP_HW_CTRL_R_N                                                
P  NNAMEm2098 GPU_PRSNT_N_ISO_R                                                 
P  NNAMEm2099 GPU_NVS_PWR_BRAKE_R_N                                             
P  NNAMEm2100 GPU_HMC_PRSNT_ISO_R_N                                             
P  NNAMEm2101 GPU_FPGA_THERM_OVERT_ISO_R_N                                      
P  NNAMEm2102 GPU_FPGA_READY_ISO_R                                              
P  NNAMEm2103 GPU_FPGA_OVERT_ISO_R_N                                            
P  NNAMEm2104 GPU_FPGA_EROT_RST_R_N                                             
P  NNAMEm2105 GPU_FPGA_EROT_RECOV_R_N                                           
P  NNAMEm2106 GPU_FPGA_EROT_FATALERR_ISO_R_N                                    
P  NNAMEm2107 GPU_FPGA_BOOT_EN_R                                                
P  NNAMEm2108 PRSNT_CABLE_GPU_A1_ISO_R_N                                        
P  NNAMEm2109 GPU_BASE_STBY_EN_R                                                
P  NNAMEm2110 GPU_BASE_HMC_READY_ISO_R                                          
P  NNAMEm2111 GPU_3V3IO_RSVD5_FFU_ISO_R                                         
P  NNAMEm2112 GPU_3V3IO_RSVD4_ISO_R                                             
P  NNAMEm2113 PRSNT_CABLE_GPU_A2_ISO_R_N                                        
P  NNAMEm2114 GPU_3V3IO_RSVD3_ISO_R                                             
P  NNAMEm2115 GPU_3V3IO_RSVD3_FFU_ISO_R                                         
P  NNAMEm2116 PRSNT_CABLE_GPU_B3_ISO_R_N                                        
P  NNAMEm2117 GPU_3V3IO_RSVD1_ISO_R                                             
P  NNAMEm2118 GPU_3V3IO_RSVD1_FFU_ISO_R                                         
P  NNAMEm2119 GPU_3V3IO_RSVD0_FFU_ISO_R                                         
P  NNAMEm2120 FM_UV_ADR_TRIGGER_R_N                                             
P  NNAMEm2121 FM_SWB_PWRGD_ISO_R                                                
P  NNAMEm2122 FM_SWB_BIC_READY_ISO_R_N                                          
P  NNAMEm2123 FM_SMB_2_ALERT_GPU_ISO_R_N                                        
P  NNAMEm2124 FM_SMB_1_ALERT_GPU_ISO_R_N                                        
P  NNAMEm2125 FM_GPU_PWRGD_ISO_R                                                
P  NNAMEm2126 E1S_0_PERST1_CLKREQ_R_N                                           
P  NNAMEm2127 CPU0_RTC_LDO_SELECT                                               
P  NNAMEm2128 BIC_MONITER_ISO_R                                                 
P  NNAMEm2129 UART_CPU0_SCM_LVC3_UART1_R1_TX                                    
P  NNAMEm2130 SMB_SEN_TIC_3V3AUX_SDA                                            
P  NNAMEm2131 SMB_SEN_TIC_3V3AUX_SCL                                            
P  NNAMEm2132 SMB_SCM_2_R4_SDA                                                  
P  NNAMEm2133 SMB_SCM_2_R4_SCL                                                  
P  NNAMEm2134 SMB_SCM_2_R3_SDA                                                  
P  NNAMEm2135 SMB_SCM_2_R3_SCL                                                  
P  NNAMEm2136 RST_PERST_OCP_V3_2_N                                              
P  NNAMEm2137 PWRGD_P5V_AUX_R2                                                  
P  NNAMEm2138 PWRGD_P5V_AUX_R1                                                  
P  NNAMEm2139 PWRGD_P3V3_EN_N                                                   
P  NNAMEm2140 PU_JTAG_DBP_BMC_PRDY_N                                            
P  NNAMEm2141 P3V3_PDB_AUX_ADC_TIC                                              
P  NNAMEm2142 P3V3_PDB_AUX_ADC_MAM                                              
P  NNAMEm2143 P3V3_OCP_V3_2_EN_R                                                
P  NNAMEm2144 P3V3_MAX11617_VDD                                                 
P  NNAMEm2145 P3V3_AUX_ADC_TIC                                                  
P  NNAMEm2146 P3V3_AUX_ADC_MAM                                                  
P  NNAMEm2147 P3V3_ADC128_VCC                                                   
P  NNAMEm2148 P12V_OCP_V3_2_ISENSE_TIC                                          
P  NNAMEm2149 P12V_OCP_V3_2_ISENSE_MAM                                          
P  NNAMEm2150 P12V_OCP_V3_2_EN_R                                                
P  NNAMEm2151 P12V_OCP_SFF_ISENSE_TIC                                           
P  NNAMEm2152 P12V_OCP_SFF_ISENSE_MAM                                           
P  NNAMEm2153 P12V_E1S_0_ISENSE_TIC                                             
P  NNAMEm2154 P12V_E1S_0_ISENSE_MAM                                             
P  NNAMEm2155 P12V_AUX_ADC_TIC                                                  
P  NNAMEm2156 P12V_AUX_ADC_MAM                                                  
P  NNAMEm2157 MAX11617_VREF_R                                                   
P  NNAMEm2158 M2_0_PEWAKE_R_N                                                   
P  NNAMEm2159 LED_HDD_ACTIVITY_B_PLD_N                                          
P  NNAMEm2160 IRQ_OCP_V3_2_WAKE_BUF_N                                           
P  NNAMEm2161 IRQ_OCP_SFF_WAKE_BUF_N                                            
P  NNAMEm2162 HP_LVC3_SCM_HSC_PWRGD                                             
P  NNAMEm2163 FM_THERMAL_ALERT_R_N                                              
P  NNAMEm2164 FM_SMB_RST_E1S_0_R_N                                              
P  NNAMEm2165 FM_BMC_READY_R_N                                                  
P  NNAMEm2166 FM_PDB_BUF_EN_N                                                   
P  NNAMEm2167 PVDD_33_S5_MODE                                                   
P  NNAMEm2168 TP_SLOT2_CLKREQ_0_R_N                                             
P  NNAMEm2169 TP_SLOT1_CLKREQ_0_R_N                                             
P  NNAMEm2170 TP_FM_CLK_BUFFER_EN_R                                             
P  NNAMEm2171 RST_PERST_M2_0_N                                                  
P  NNAMEm2172 RST_PERST_E1S_0_N                                                 
P  NNAMEm2173 PWRGD_PS_PWROK_PLD_N                                              
P  NNAMEm2174 PWRGD_PS_PWROK_PLD_ISO_R                                          
P  NNAMEm2175 PWRGD_PS_PWROK_PLD_ISO                                            
P  NNAMEm2176 PWRGD_PS_PWROK_PLD                                                
P  NNAMEm2177 PWRGD_OCP_SFF_PWR_GOOD                                            
P  NNAMEm2178 PU_FPGA_DEBUG_SW_SPARE                                            
P  NNAMEm2179 PU_FPGA_DEBUG_LED_CTRL                                            
P  NNAMEm2180 PRSNT_OCP_SFF_N                                                   
P  NNAMEm2181 P3V3_E1S_PWRGD_0_R                                                
P  NNAMEm2182 P3V3_E1S_EN_0_R                                                   
P  NNAMEm2183 P12V_OCP_V3_1_PWRGD                                               
P  NNAMEm2184 P12V_OCP_SFF_EN_R                                                 
P  NNAMEm2185 P12V_E1S_0_PWRGD                                                  
P  NNAMEm2186 LED_PWRGD_PS_PWROK_PLD_D                                          
P  NNAMEm2187 LED_PWRGD_PS_PWROK_PLD                                            
P  NNAMEm2188 IRQ_TPM_SPI_R_N                                                   
P  NNAMEm2189 IRQ_SMI_ACTIVE_N                                                  
P  NNAMEm2190 IRQ_CPU_BMC_NMI_N                                                 
P  NNAMEm2191 FPGA_DEBUG_SW_SPARE                                               
P  NNAMEm2192 FPGA_DEBUG_LED_CTRL                                               
P  NNAMEm2193 FM_SMM_CRASHDUMP                                                  
P  NNAMEm2194 FM_LED_ACTIVE_E1S_0_R_BUF                                         
P  NNAMEm2195 FM_LED_ACTIVE_E1S_0_R                                             
P  NNAMEm2196 FM_LED_ACTIVE_E1S_0_BUF                                           
P  NNAMEm2197 FM_LED_ACTIVE_E1S_0                                               
P  NNAMEm2198 FM_FPGA_DEBUG_SW_SPARE                                            
P  NNAMEm2199 FM_FORCE_ALL_PWRON_ON                                             
P  NNAMEm2200 FM_BMC_TPM_PRES_N                                                 
P  NNAMEm2201 E1S_0_PRSNT_R_N                                                   
P  NNAMEm2202 SMB_HOST_CLK_3V3AUX_SDA                                           
P  NNAMEm2203 SMB_HOST_CLK_3V3AUX_SCL                                           
P  NNAMEm2204 CLK_100M_CPU1_CLK12_R_DP                                          
P  NNAMEm2205 CLK_100M_CPU1_CLK12_R_DN                                          
P  NNAMEm2206 CLK_100M_CPU1_CLK12_DP                                            
P  NNAMEm2207 CLK_100M_CPU1_CLK12_DN                                            
P  NNAMEm2208 CLK_100M_CPU1_CLK05_R_DP                                          
P  NNAMEm2209 CLK_100M_CPU1_CLK05_R_DN                                          
P  NNAMEm2210 CLK_100M_CPU1_CLK05_DP                                            
P  NNAMEm2211 CLK_100M_CPU1_CLK05_DN                                            
P  NNAMEm2212 CLK_100M_CPU1_CLK04_R_DP                                          
P  NNAMEm2213 CLK_100M_CPU1_CLK04_R_DN                                          
P  NNAMEm2214 CLK_100M_CPU1_CLK04_DP                                            
P  NNAMEm2215 CLK_100M_CPU1_CLK04_DN                                            
P  NNAMEm2216 CLK_100M_CPU1_CLK03_R_DP                                          
P  NNAMEm2217 CLK_100M_CPU1_CLK03_R_DN                                          
P  NNAMEm2218 CLK_100M_CPU1_CLK03_DP                                            
P  NNAMEm2219 CLK_100M_CPU1_CLK03_DN                                            
P  NNAMEm2220 CLK_100M_CPU1_CLK02_R_DP                                          
P  NNAMEm2221 CLK_100M_CPU1_CLK02_R_DN                                          
P  NNAMEm2222 CLK_100M_CPU1_CLK02_DP                                            
P  NNAMEm2223 CLK_100M_CPU1_CLK02_DN                                            
P  NNAMEm2224 CLK_100M_CPU1_CLK01_R_DP                                          
P  NNAMEm2225 CLK_100M_CPU1_CLK01_R_DN                                          
P  NNAMEm2226 CLK_100M_CPU1_CLK01_DP                                            
P  NNAMEm2227 CLK_100M_CPU1_CLK01_DN                                            
P  NNAMEm2228 CLK_100M_CPU0_CLK12_R_DP                                          
P  NNAMEm2229 CLK_100M_CPU0_CLK12_R_DN                                          
P  NNAMEm2230 CLK_100M_CPU0_CLK12_DP                                            
P  NNAMEm2231 CLK_100M_CPU0_CLK12_DN                                            
P  NNAMEm2232 VIRTUAL_RESEAT_FPGA_R_N                                           
P  NNAMEm2233 VFG_3P3A_CLK_GEN                                                  
P  NNAMEm2234 USB3_CPU0_BMC_TX_DP                                               
P  NNAMEm2235 USB3_CPU0_BMC_TX_DN                                               
P  NNAMEm2236 USB3_CPU0_BMC_TX_BUF_C_DP                                         
P  NNAMEm2237 USB3_CPU0_BMC_TX_BUF_C_DN                                         
P  NNAMEm2238 USB3_CPU0_BMC_RX_DP                                               
P  NNAMEm2239 USB3_CPU0_BMC_RX_DN                                               
P  NNAMEm2240 TP_TCA9539_0_P0_3                                                 
P  NNAMEm2241 TP_TCA9539_0_P0_2                                                 
P  NNAMEm2242 TP_PVCCIO_PECI_BMC                                                
P  NNAMEm2243 SMB_VR_SENSOR_3V3AUX_SDA_R                                        
P  NNAMEm2244 SMB_VR_SENSOR_3V3AUX_SCL_R                                        
P  NNAMEm2245 SMB_VR_3V3AUX_SDA_R6                                              
P  NNAMEm2246 SMB_VR_3V3AUX_SCL_R6                                              
P  NNAMEm2247 SMB_PMBUS_3V3AUX_SDA                                              
P  NNAMEm2248 SMB_PMBUS_3V3AUX_SCL                                              
P  NNAMEm2249 SMB_PCIE0_3V3AUX_SDA_R5                                           
P  NNAMEm2250 SMB_PCIE0_3V3AUX_SDA_R3                                           
P  NNAMEm2251 SMB_PCIE0_3V3AUX_SDA_R                                            
P  NNAMEm2252 SMB_PCIE0_3V3AUX_SCL_R5                                           
P  NNAMEm2253 SMB_PCIE0_3V3AUX_SCL_R3                                           
P  NNAMEm2254 SMB_PCIE0_3V3AUX_SCL_R                                            
P  NNAMEm2255 SMB_LM75_3_3V3AUX_SDA_R                                           
P  NNAMEm2256 SMB_LM75_3_3V3AUX_SCL_R                                           
P  NNAMEm2257 SMB_LM75_2_3V3AUX_SDA_R                                           
P  NNAMEm2258 SMB_LM75_2_3V3AUX_SCL_R                                           
P  NNAMEm2259 SMB_LM75_1_3V3AUX_SDA_R                                           
P  NNAMEm2260 SMB_LM75_1_3V3AUX_SCL_R                                           
P  NNAMEm2261 SMB_LM75_0_3V3AUX_SDA_R                                           
P  NNAMEm2262 SMB_LM75_0_3V3AUX_SCL_R                                           
P  NNAMEm2263 SMB_IOEXP_3V3AUX_SDA_R1                                           
P  NNAMEm2264 SMB_IOEXP_3V3AUX_SDA_R                                            
P  NNAMEm2265 SMB_IOEXP_3V3AUX_SDA                                              
P  NNAMEm2266 SMB_IOEXP_3V3AUX_SCL_R1                                           
P  NNAMEm2267 SMB_IOEXP_3V3AUX_SCL_R                                            
P  NNAMEm2268 SMB_IOEXP_3V3AUX_SCL                                              
P  NNAMEm2269 SMB_INA230_3V3AUX_SDA_R                                           
P  NNAMEm2270 SMB_INA230_3V3AUX_SDA                                             
P  NNAMEm2271 SMB_INA230_3V3AUX_SCL_R                                           
P  NNAMEm2272 SMB_INA230_3V3AUX_SCL                                             
P  NNAMEm2273 SMB_FRU_3V3AUX_SDA_R                                              
P  NNAMEm2274 SMB_FRU_3V3AUX_SCL_R                                              
P  NNAMEm2275 SMB_CPU0_CPU1_SEC_SDA                                             
P  NNAMEm2276 SMB_CPU0_CPU1_SEC_SCL                                             
P  NNAMEm2277 SMB_CPU0_CPU1_APML_SDA                                            
P  NNAMEm2278 SMB_CPU0_CPU1_APML_SCL                                            
P  NNAMEm2279 SMB_BMC_SWB_SDA_R4                                                
P  NNAMEm2280 SMB_BMC_SWB_SDA                                                   
P  NNAMEm2281 SMB_BMC_SWB_SCL_R4                                                
P  NNAMEm2282 SMB_BMC_SWB_SCL                                                   
P  NNAMEm2283 SMB_BMC_SWB_R_SDA                                                 
P  NNAMEm2284 SMB_BMC_SWB_R_SCL                                                 
P  NNAMEm2285 SMB_BMC_SWB_EN_R2                                                 
P  NNAMEm2286 SMB_BMC_SWB_EN_R                                                  
P  NNAMEm2287 SMB_BMC_SWB_BUF_R_SDA                                             
P  NNAMEm2288 SMB_BMC_SWB_BUF_R_SCL                                             
P  NNAMEm2289 SMB_BMC_GPU_EN_R3                                                 
P  NNAMEm2290 SMB_BMC_GPU_EN_R1                                                 
P  NNAMEm2291 SMB_2_BMC_GPU_R_SDA                                               
P  NNAMEm2292 SMB_2_BMC_GPU_R_SCL                                               
P  NNAMEm2293 SMB_2_BMC_GPU_BUF_R_SDA                                           
P  NNAMEm2294 SMB_2_BMC_GPU_BUF_R_SCL                                           
P  NNAMEm2295 SMB_1_BMC_GPU_R_SDA                                               
P  NNAMEm2296 SMB_1_BMC_GPU_R_SCL                                               
P  NNAMEm2297 SMB_1_BMC_GPU_BUF_R_SDA                                           
P  NNAMEm2298 SMB_1_BMC_GPU_BUF_R_SCL                                           
P  NNAMEm2299 SGPIO_SCM_RESET_R_N                                               
P  NNAMEm2300 SGPIO_SCM_LD_R_<1>                                                
P  NNAMEm2301 SGPIO_SCM_LD_R_<0>                                                
P  NNAMEm2302 SGPIO_SCM_DO_R_<1>                                                
P  NNAMEm2303 SGPIO_SCM_DO_R_<0>                                                
P  NNAMEm2304 SGPIO_SCM_DI_R_<1>                                                
P  NNAMEm2305 SGPIO_SCM_DI_R_<0>                                                
P  NNAMEm2306 SGPIO_SCM_CLK_R_<1>                                               
P  NNAMEm2307 SGPIO_SCM_CLK_R_<0>                                               
P  NNAMEm2308 SGPIO_SCM_CLK_<1>                                                 
P  NNAMEm2309 SGPIO_SCM_CLK_<0>                                                 
P  NNAMEm2310 SCM_HDT_DBREQ_N                                                   
P  NNAMEm2311 PU_RST_SMB_U181_N                                                 
P  NNAMEm2312 PU_RST_SMB_PCIE2_N                                                
P  NNAMEm2313 PU_RST_SMB_PCIE0_N                                                
P  NNAMEm2314 PCA9548_PCIE3_ADDR2                                               
P  NNAMEm2315 PCA9548_PCIE3_ADDR1                                               
P  NNAMEm2316 PCA9548_PCIE3_ADDR0                                               
P  NNAMEm2317 PCA9548_PCIE0_ADDR2                                               
P  NNAMEm2318 PCA9548_PCIE0_ADDR1                                               
P  NNAMEm2319 PCA9548_PCIE0_ADDR0                                               
P  NNAMEm2320 P3V3_PWRGD_CLKGEN                                                 
P  NNAMEm2321 P2E_CPU0_P5_TX_DP                                                 
P  NNAMEm2322 P2E_CPU0_P5_TX_DN                                                 
P  NNAMEm2323 I3C_BMC_SWB_R_SDA                                                 
P  NNAMEm2324 I3C_BMC_SWB_R_SCL                                                 
P  NNAMEm2325 I3C_BMC_SWB_BUF_R_SDA                                             
P  NNAMEm2326 I3C_BMC_SWB_BUF_R_SCL                                             
P  NNAMEm2327 HP_LVC3_OCP_V3_2_R_EN                                             
P  NNAMEm2328 HP_LVC3_OCP_V3_1_R_EN                                             
P  NNAMEm2329 RST_MB_STBY_R_N                                                   
P  NNAMEm2330 GPU_PEX_STRAP1_R                                                  
P  NNAMEm2331 GPU_PEX_STRAP0_R                                                  
P  NNAMEm2332 GPU_FPGA_READY_R_N                                                
P  NNAMEm2333 CLK_GEN2_XTAL_OUT                                                 
P  NNAMEm2334 CLK_GEN2_XTAL_IN_R                                                
P  NNAMEm2335 CLK_GEN2_XTAL_IN                                                  
P  NNAMEm2336 CLK_GEN2_SMB_SADR                                                 
P  NNAMEm2337 CLK_GEN2_GPU_OE_N                                                 
P  NNAMEm2338 CLK_GEN2_GPU_FPGA_OE_R_N                                          
P  NNAMEm2339 CLK_GEN2_GPU_FPGA_OE_R2_N                                         
P  NNAMEm2340 CLK_GEN2_GPU_FPGA_OE_N                                            
P  NNAMEm2341 CLK_GEN2_BMC_RC_OE_R_N                                            
P  NNAMEm2342 CLK_GEN2_BMC_RC_OE_R3_N                                           
P  NNAMEm2343 CLK_GEN2_BMC_RC_OE_N                                              
P  NNAMEm2344 CLK_100M_GPU_FPGA_DP_R                                            
P  NNAMEm2345 CLK_100M_GPU_FPGA_DN_R                                            
P  NNAMEm2346 CLK_100M_CPU0_CLK05_R_DP                                          
P  NNAMEm2347 CLK_100M_CPU0_CLK05_R_DN                                          
P  NNAMEm2348 CLK_100M_CPU0_CLK05_DP                                            
P  NNAMEm2349 CLK_100M_CPU0_CLK05_DN                                            
P  NNAMEm2350 CLK_100M_CPU0_CLK04_R_DP                                          
P  NNAMEm2351 CLK_100M_CPU0_CLK04_R_DN                                          
P  NNAMEm2352 CLK_100M_CPU0_CLK04_DP                                            
P  NNAMEm2353 CLK_100M_CPU0_CLK04_DN                                            
P  NNAMEm2354 CLK_100M_CPU0_CLK03_R_DP                                          
P  NNAMEm2355 CLK_100M_CPU0_CLK03_R_DN                                          
P  NNAMEm2356 CLK_100M_CPU0_CLK03_DP                                            
P  NNAMEm2357 CLK_100M_CPU0_CLK03_DN                                            
P  NNAMEm2358 CLK_100M_CPU0_CLK02_R_DP                                          
P  NNAMEm2359 CLK_100M_CPU0_CLK02_R_DN                                          
P  NNAMEm2360 CLK_100M_CPU0_CLK02_DP                                            
P  NNAMEm2361 CLK_100M_CPU0_CLK02_DN                                            
P  NNAMEm2362 CLK_100M_CPU0_CLK01_R_DP                                          
P  NNAMEm2363 CLK_100M_CPU0_CLK01_R_DN                                          
P  NNAMEm2364 CLK_100M_BMC_RC_DP_R                                              
P  NNAMEm2365 CLK_100M_BMC_RC_DN_R                                              
P  NNAMEm2366 P3E_CPU1_P5_TX_C_DP<1>                                            
P  NNAMEm2367 P3E_CPU1_P5_TX_C_DP<0>                                            
P  NNAMEm2368 P3E_CPU1_P5_TX_C_DN<1>                                            
P  NNAMEm2369 P3E_CPU1_P5_TX_C_DN<0>                                            
P  NNAMEm2370 P3E_CPU1_P4_TX_C_DP<3>                                            
P  NNAMEm2371 P3E_CPU1_P4_TX_C_DP<2>                                            
P  NNAMEm2372 P3E_CPU1_P4_TX_C_DP<1>                                            
P  NNAMEm2373 P3E_CPU1_P4_TX_C_DP<0>                                            
P  NNAMEm2374 P3E_CPU1_P4_TX_C_DN<3>                                            
P  NNAMEm2375 P3E_CPU1_P4_TX_C_DN<2>                                            
P  NNAMEm2376 P3E_CPU1_P4_TX_C_DN<1>                                            
P  NNAMEm2377 P3E_CPU1_P4_TX_C_DN<0>                                            
P  NNAMEm2378 P3E_CPU0_P4_TX_C_DP<3>                                            
P  NNAMEm2379 P3E_CPU0_P4_TX_C_DP<2>                                            
P  NNAMEm2380 P3E_CPU0_P4_TX_C_DP<1>                                            
P  NNAMEm2381 P3E_CPU0_P4_TX_C_DP<0>                                            
P  NNAMEm2382 P3E_CPU0_P4_TX_C_DN<3>                                            
P  NNAMEm2383 P3E_CPU0_P4_TX_C_DN<2>                                            
P  NNAMEm2384 P3E_CPU0_P4_TX_C_DN<1>                                            
P  NNAMEm2385 P3E_CPU0_P4_TX_C_DN<0>                                            
P  NNAMEm2386 P2E_MB_BMC_TX_BUF_DP<0>                                           
P  NNAMEm2387 P2E_MB_BMC_TX_BUF_DN<0>                                           
P  NNAMEm2388 P2E_MB_BMC_RX_BUF_C_DP<0>                                         
P  NNAMEm2389 P2E_MB_BMC_RX_BUF_C_DN<0>                                         
P  NNAMEm2390 P2E_CPU0_P5_TX_C_DP                                               
P  NNAMEm2391 P2E_CPU0_P5_TX_C_DN                                               
P  NNAMEm2392 CLK_GEN2_GPU_FPGA_OE_OR_N                                         
P  NNAMEm2393 VSENSE_P3V3_INA230_2_INP                                          
P  NNAMEm2394 VSENSE_P3V3_INA230_2_INN                                          
P  NNAMEm2395 VSENSE_P3V3_INA230_1_INP                                          
P  NNAMEm2396 VSENSE_P3V3_INA230_1_INN                                          
P  NNAMEm2397 VSENSE_P12V_INA230_5_INP                                          
P  NNAMEm2398 VSENSE_P12V_INA230_5_INN                                          
P  NNAMEm2399 VSENSE_P12V_INA230_4_INP                                          
P  NNAMEm2400 VSENSE_P12V_INA230_4_INN                                          
P  NNAMEm2401 VSENSE_P12V_INA230_3_INP                                          
P  NNAMEm2402 VSENSE_P12V_INA230_3_INN                                          
P  NNAMEm2403 USB_HUB_XTAL_OUT                                                  
P  NNAMEm2404 USB_HUB_XTAL_IN                                                   
P  NNAMEm2405 USB2_HUB_SWB_DP                                                   
P  NNAMEm2406 USB2_HUB_SWB_DN                                                   
P  NNAMEm2407 USB2_HUB_BUF_SWB_R_DP                                             
P  NNAMEm2408 USB2_HUB_BUF_SWB_R_DN                                             
P  NNAMEm2409 USB2_HOST_BMC_B_BUF_DP                                            
P  NNAMEm2410 USB2_HOST_BMC_B_BUF_DN                                            
P  NNAMEm2411 SMB_LM75_3_3V3AUX_SDA_R1                                          
P  NNAMEm2412 SMB_LM75_3_3V3AUX_SDA                                             
P  NNAMEm2413 SMB_LM75_3_3V3AUX_SCL_R1                                          
P  NNAMEm2414 SMB_LM75_3_3V3AUX_SCL                                             
P  NNAMEm2415 SMB_LM75_2_3V3AUX_SDA_R1                                          
P  NNAMEm2416 SMB_LM75_2_3V3AUX_SDA                                             
P  NNAMEm2417 SMB_LM75_2_3V3AUX_SCL_R1                                          
P  NNAMEm2418 SMB_LM75_2_3V3AUX_SCL                                             
P  NNAMEm2419 SMB_LM75_1_3V3AUX_SDA_R1                                          
P  NNAMEm2420 SMB_LM75_1_3V3AUX_SDA                                             
P  NNAMEm2421 SMB_LM75_1_3V3AUX_SCL_R1                                          
P  NNAMEm2422 SMB_LM75_1_3V3AUX_SCL                                             
P  NNAMEm2423 SMB_LM75_0_3V3AUX_SDA_R1                                          
P  NNAMEm2424 SMB_LM75_0_3V3AUX_SDA                                             
P  NNAMEm2425 SMB_LM75_0_3V3AUX_SCL_R1                                          
P  NNAMEm2426 SMB_LM75_0_3V3AUX_SCL                                             
P  NNAMEm2427 SMB_INA230_5_3V3AUX_SDA_R1                                        
P  NNAMEm2428 SMB_INA230_5_3V3AUX_SDA_R                                         
P  NNAMEm2429 SMB_INA230_5_3V3AUX_SCL_R1                                        
P  NNAMEm2430 SMB_INA230_5_3V3AUX_SCL_R                                         
P  NNAMEm2431 SMB_INA230_4_3V3AUX_SDA_R1                                        
P  NNAMEm2432 SMB_INA230_4_3V3AUX_SDA_R                                         
P  NNAMEm2433 SMB_INA230_4_3V3AUX_SCL_R1                                        
P  NNAMEm2434 SMB_INA230_4_3V3AUX_SCL_R                                         
P  NNAMEm2435 SMB_INA230_3_3V3AUX_SDA_R1                                        
P  NNAMEm2436 SMB_INA230_3_3V3AUX_SDA_R                                         
P  NNAMEm2437 SMB_INA230_3_3V3AUX_SCL_R1                                        
P  NNAMEm2438 SMB_INA230_3_3V3AUX_SCL_R                                         
P  NNAMEm2439 SMB_INA230_2_3V3AUX_SDA_R1                                        
P  NNAMEm2440 SMB_INA230_2_3V3AUX_SDA_R                                         
P  NNAMEm2441 SMB_INA230_2_3V3AUX_SCL_R1                                        
P  NNAMEm2442 SMB_INA230_2_3V3AUX_SCL_R                                         
P  NNAMEm2443 SMB_INA230_1_3V3AUX_SDA_R1                                        
P  NNAMEm2444 SMB_INA230_1_3V3AUX_SDA_R                                         
P  NNAMEm2445 SMB_INA230_1_3V3AUX_SCL_R1                                        
P  NNAMEm2446 SMB_INA230_1_3V3AUX_SCL_R                                         
P  NNAMEm2447 SMB_FRU_3V3AUX_SDA                                                
P  NNAMEm2448 SMB_FRU_3V3AUX_SCL                                                
P  NNAMEm2449 SMB_FAN_3V3AUX_R_SDA                                              
P  NNAMEm2450 SMB_FAN_3V3AUX_R_SCL                                              
P  NNAMEm2451 SMB_FAN_3V3AUX_BUF_SDA                                            
P  NNAMEm2452 SMB_FAN_3V3AUX_BUF_SCL                                            
P  NNAMEm2453 SMB_FAN_3V3AUX_BUF_R_SDA                                          
P  NNAMEm2454 SMB_FAN_3V3AUX_BUF_R_SCL                                          
P  NNAMEm2455 RST_USB_HUB_R_N                                                   
P  NNAMEm2456 RST_SMB_SWITCH_R_N                                                
P  NNAMEm2457 PWRGD_P3V3_AUX_PDB_R                                              
P  NNAMEm2458 PWRGD_P3V3_AUX_PDB_BUF_R                                          
P  NNAMEm2459 PWRGD_P3V3_AUX_PDB_BUF                                            
P  NNAMEm2460 PWRGD_P3V3_AUX_PDB                                                
P  NNAMEm2461 P5E_CPU1_P3_TX_C_DP<9>                                            
P  NNAMEm2462 P5E_CPU1_P3_TX_C_DP<8>                                            
P  NNAMEm2463 P5E_CPU1_P3_TX_C_DP<7>                                            
P  NNAMEm2464 P5E_CPU1_P3_TX_C_DP<6>                                            
P  NNAMEm2465 P5E_CPU1_P3_TX_C_DP<5>                                            
P  NNAMEm2466 P5E_CPU1_P3_TX_C_DP<4>                                            
P  NNAMEm2467 P5E_CPU1_P3_TX_C_DP<3>                                            
P  NNAMEm2468 P5E_CPU1_P3_TX_C_DP<2>                                            
P  NNAMEm2469 P5E_CPU1_P3_TX_C_DP<1>                                            
P  NNAMEm2470 P5E_CPU1_P3_TX_C_DP<15>                                           
P  NNAMEm2471 P5E_CPU1_P3_TX_C_DP<14>                                           
P  NNAMEm2472 P5E_CPU1_P3_TX_C_DP<13>                                           
P  NNAMEm2473 P5E_CPU1_P3_TX_C_DP<12>                                           
P  NNAMEm2474 P5E_CPU1_P3_TX_C_DP<11>                                           
P  NNAMEm2475 P5E_CPU1_P3_TX_C_DP<10>                                           
P  NNAMEm2476 P5E_CPU1_P3_TX_C_DP<0>                                            
P  NNAMEm2477 P5E_CPU1_P3_TX_C_DN<9>                                            
P  NNAMEm2478 P5E_CPU1_P3_TX_C_DN<8>                                            
P  NNAMEm2479 P5E_CPU1_P3_TX_C_DN<7>                                            
P  NNAMEm2480 P5E_CPU1_P3_TX_C_DN<6>                                            
P  NNAMEm2481 P5E_CPU1_P3_TX_C_DN<5>                                            
P  NNAMEm2482 P5E_CPU1_P3_TX_C_DN<4>                                            
P  NNAMEm2483 P5E_CPU1_P3_TX_C_DN<3>                                            
P  NNAMEm2484 P5E_CPU1_P3_TX_C_DN<2>                                            
P  NNAMEm2485 P5E_CPU1_P3_TX_C_DN<1>                                            
P  NNAMEm2486 P5E_CPU1_P3_TX_C_DN<15>                                           
P  NNAMEm2487 P5E_CPU1_P3_TX_C_DN<14>                                           
P  NNAMEm2488 P5E_CPU1_P3_TX_C_DN<13>                                           
P  NNAMEm2489 P5E_CPU1_P3_TX_C_DN<12>                                           
P  NNAMEm2490 P5E_CPU1_P3_TX_C_DN<11>                                           
P  NNAMEm2491 P5E_CPU1_P3_TX_C_DN<10>                                           
P  NNAMEm2492 P5E_CPU1_P3_TX_C_DN<0>                                            
P  NNAMEm2493 P5E_CPU1_P2_TX_C_DP<9>                                            
P  NNAMEm2494 P5E_CPU1_P2_TX_C_DP<8>                                            
P  NNAMEm2495 P5E_CPU1_P2_TX_C_DP<7>                                            
P  NNAMEm2496 P5E_CPU1_P2_TX_C_DP<6>                                            
P  NNAMEm2497 P5E_CPU1_P2_TX_C_DP<5>                                            
P  NNAMEm2498 P5E_CPU1_P2_TX_C_DP<4>                                            
P  NNAMEm2499 P5E_CPU1_P2_TX_C_DP<3>                                            
P  NNAMEm2500 P5E_CPU1_P2_TX_C_DP<2>                                            
P  NNAMEm2501 P5E_CPU1_P2_TX_C_DP<1>                                            
P  NNAMEm2502 P5E_CPU1_P2_TX_C_DP<15>                                           
P  NNAMEm2503 P5E_CPU1_P2_TX_C_DP<14>                                           
P  NNAMEm2504 P5E_CPU1_P2_TX_C_DP<13>                                           
P  NNAMEm2505 P5E_CPU1_P2_TX_C_DP<12>                                           
P  NNAMEm2506 P5E_CPU1_P2_TX_C_DP<11>                                           
P  NNAMEm2507 P5E_CPU1_P2_TX_C_DP<10>                                           
P  NNAMEm2508 P5E_CPU1_P2_TX_C_DP<0>                                            
P  NNAMEm2509 P5E_CPU1_P2_TX_C_DN<9>                                            
P  NNAMEm2510 P5E_CPU1_P2_TX_C_DN<8>                                            
P  NNAMEm2511 P5E_CPU1_P2_TX_C_DN<7>                                            
P  NNAMEm2512 P5E_CPU1_P2_TX_C_DN<6>                                            
P  NNAMEm2513 P5E_CPU1_P2_TX_C_DN<5>                                            
P  NNAMEm2514 P5E_CPU1_P2_TX_C_DN<4>                                            
P  NNAMEm2515 P5E_CPU1_P2_TX_C_DN<3>                                            
P  NNAMEm2516 P5E_CPU1_P2_TX_C_DN<2>                                            
P  NNAMEm2517 P5E_CPU1_P2_TX_C_DN<1>                                            
P  NNAMEm2518 P5E_CPU1_P2_TX_C_DN<15>                                           
P  NNAMEm2519 P5E_CPU1_P2_TX_C_DN<14>                                           
P  NNAMEm2520 P5E_CPU1_P2_TX_C_DN<13>                                           
P  NNAMEm2521 P5E_CPU1_P2_TX_C_DN<12>                                           
P  NNAMEm2522 P5E_CPU1_P2_TX_C_DN<11>                                           
P  NNAMEm2523 P5E_CPU1_P2_TX_C_DN<10>                                           
P  NNAMEm2524 P5E_CPU1_P2_TX_C_DN<0>                                            
P  NNAMEm2525 P5E_CPU1_P1_TX_C_DP<9>                                            
P  NNAMEm2526 P5E_CPU1_P1_TX_C_DP<8>                                            
P  NNAMEm2527 P5E_CPU1_P1_TX_C_DP<7>                                            
P  NNAMEm2528 P5E_CPU1_P1_TX_C_DP<6>                                            
P  NNAMEm2529 P5E_CPU1_P1_TX_C_DP<5>                                            
P  NNAMEm2530 P5E_CPU1_P1_TX_C_DP<4>                                            
P  NNAMEm2531 P5E_CPU1_P1_TX_C_DP<3>                                            
P  NNAMEm2532 P5E_CPU1_P1_TX_C_DP<2>                                            
P  NNAMEm2533 P5E_CPU1_P1_TX_C_DP<1>                                            
P  NNAMEm2534 P5E_CPU1_P1_TX_C_DP<15>                                           
P  NNAMEm2535 P5E_CPU1_P1_TX_C_DP<14>                                           
P  NNAMEm2536 P5E_CPU1_P1_TX_C_DP<13>                                           
P  NNAMEm2537 P5E_CPU1_P1_TX_C_DP<12>                                           
P  NNAMEm2538 P5E_CPU1_P1_TX_C_DP<11>                                           
P  NNAMEm2539 P5E_CPU1_P1_TX_C_DP<10>                                           
P  NNAMEm2540 P5E_CPU1_P1_TX_C_DP<0>                                            
P  NNAMEm2541 P5E_CPU1_P1_TX_C_DN<9>                                            
P  NNAMEm2542 P5E_CPU1_P1_TX_C_DN<8>                                            
P  NNAMEm2543 P5E_CPU1_P1_TX_C_DN<7>                                            
P  NNAMEm2544 P5E_CPU1_P1_TX_C_DN<6>                                            
P  NNAMEm2545 P5E_CPU1_P1_TX_C_DN<5>                                            
P  NNAMEm2546 P5E_CPU1_P1_TX_C_DN<4>                                            
P  NNAMEm2547 P5E_CPU1_P1_TX_C_DN<3>                                            
P  NNAMEm2548 P5E_CPU1_P1_TX_C_DN<2>                                            
P  NNAMEm2549 P5E_CPU1_P1_TX_C_DN<1>                                            
P  NNAMEm2550 P5E_CPU1_P1_TX_C_DN<15>                                           
P  NNAMEm2551 P5E_CPU1_P1_TX_C_DN<14>                                           
P  NNAMEm2552 P5E_CPU1_P1_TX_C_DN<13>                                           
P  NNAMEm2553 P5E_CPU1_P1_TX_C_DN<12>                                           
P  NNAMEm2554 P5E_CPU1_P1_TX_C_DN<11>                                           
P  NNAMEm2555 P5E_CPU1_P1_TX_C_DN<10>                                           
P  NNAMEm2556 P5E_CPU1_P1_TX_C_DN<0>                                            
P  NNAMEm2557 P5E_CPU1_P0_TX_C_DP<9>                                            
P  NNAMEm2558 P5E_CPU1_P0_TX_C_DP<8>                                            
P  NNAMEm2559 P5E_CPU1_P0_TX_C_DP<7>                                            
P  NNAMEm2560 P5E_CPU1_P0_TX_C_DP<6>                                            
P  NNAMEm2561 P5E_CPU1_P0_TX_C_DP<5>                                            
P  NNAMEm2562 P5E_CPU1_P0_TX_C_DP<4>                                            
P  NNAMEm2563 P5E_CPU1_P0_TX_C_DP<3>                                            
P  NNAMEm2564 P5E_CPU1_P0_TX_C_DP<2>                                            
P  NNAMEm2565 P5E_CPU1_P0_TX_C_DP<1>                                            
P  NNAMEm2566 P5E_CPU1_P0_TX_C_DP<15>                                           
P  NNAMEm2567 P5E_CPU1_P0_TX_C_DP<14>                                           
P  NNAMEm2568 P5E_CPU1_P0_TX_C_DP<13>                                           
P  NNAMEm2569 P5E_CPU1_P0_TX_C_DP<12>                                           
P  NNAMEm2570 P5E_CPU1_P0_TX_C_DP<11>                                           
P  NNAMEm2571 P5E_CPU1_P0_TX_C_DP<10>                                           
P  NNAMEm2572 P5E_CPU1_P0_TX_C_DP<0>                                            
P  NNAMEm2573 P5E_CPU1_P0_TX_C_DN<9>                                            
P  NNAMEm2574 P5E_CPU1_P0_TX_C_DN<8>                                            
P  NNAMEm2575 P5E_CPU1_P0_TX_C_DN<7>                                            
P  NNAMEm2576 P5E_CPU1_P0_TX_C_DN<6>                                            
P  NNAMEm2577 P5E_CPU1_P0_TX_C_DN<5>                                            
P  NNAMEm2578 P5E_CPU1_P0_TX_C_DN<4>                                            
P  NNAMEm2579 P5E_CPU1_P0_TX_C_DN<3>                                            
P  NNAMEm2580 P5E_CPU1_P0_TX_C_DN<2>                                            
P  NNAMEm2581 P5E_CPU1_P0_TX_C_DN<1>                                            
P  NNAMEm2582 P5E_CPU1_P0_TX_C_DN<15>                                           
P  NNAMEm2583 P5E_CPU1_P0_TX_C_DN<14>                                           
P  NNAMEm2584 P5E_CPU1_P0_TX_C_DN<13>                                           
P  NNAMEm2585 P5E_CPU1_P0_TX_C_DN<12>                                           
P  NNAMEm2586 P5E_CPU1_P0_TX_C_DN<11>                                           
P  NNAMEm2587 P5E_CPU1_P0_TX_C_DN<10>                                           
P  NNAMEm2588 P5E_CPU1_P0_TX_C_DN<0>                                            
P  NNAMEm2589 P5E_CPU1_G1_TX_DP<9>                                              
P  NNAMEm2590 P5E_CPU1_G1_TX_DP<8>                                              
P  NNAMEm2591 P5E_CPU1_G1_TX_DP<7>                                              
P  NNAMEm2592 P5E_CPU1_G1_TX_DP<6>                                              
P  NNAMEm2593 P5E_CPU1_G1_TX_DP<5>                                              
P  NNAMEm2594 P5E_CPU1_G1_TX_DP<4>                                              
P  NNAMEm2595 P5E_CPU1_G1_TX_DP<3>                                              
P  NNAMEm2596 P5E_CPU1_G1_TX_DP<2>                                              
P  NNAMEm2597 P5E_CPU1_G1_TX_DP<1>                                              
P  NNAMEm2598 P5E_CPU1_G1_TX_DP<15>                                             
P  NNAMEm2599 P5E_CPU1_G1_TX_DP<14>                                             
P  NNAMEm2600 P5E_CPU1_G1_TX_DP<13>                                             
P  NNAMEm2601 P5E_CPU1_G1_TX_DP<12>                                             
P  NNAMEm2602 P5E_CPU1_G1_TX_DP<11>                                             
P  NNAMEm2603 P5E_CPU1_G1_TX_DP<10>                                             
P  NNAMEm2604 P5E_CPU1_G1_TX_DP<0>                                              
P  NNAMEm2605 P5E_CPU1_G1_TX_DN<9>                                              
P  NNAMEm2606 P5E_CPU1_G1_TX_DN<8>                                              
P  NNAMEm2607 P5E_CPU1_G1_TX_DN<7>                                              
P  NNAMEm2608 P5E_CPU1_G1_TX_DN<6>                                              
P  NNAMEm2609 P5E_CPU1_G1_TX_DN<5>                                              
P  NNAMEm2610 P5E_CPU1_G1_TX_DN<4>                                              
P  NNAMEm2611 P5E_CPU1_G1_TX_DN<3>                                              
P  NNAMEm2612 P5E_CPU1_G1_TX_DN<2>                                              
P  NNAMEm2613 P5E_CPU1_G1_TX_DN<1>                                              
P  NNAMEm2614 P5E_CPU1_G1_TX_DN<15>                                             
P  NNAMEm2615 P5E_CPU1_G1_TX_DN<14>                                             
P  NNAMEm2616 P5E_CPU1_G1_TX_DN<13>                                             
P  NNAMEm2617 P5E_CPU1_G1_TX_DN<12>                                             
P  NNAMEm2618 P5E_CPU1_G1_TX_DN<11>                                             
P  NNAMEm2619 P5E_CPU1_G1_TX_DN<10>                                             
P  NNAMEm2620 P5E_CPU1_G1_TX_DN<0>                                              
P  NNAMEm2621 P5E_CPU1_G1_TX_C_DP<9>                                            
P  NNAMEm2622 P5E_CPU1_G1_TX_C_DP<8>                                            
P  NNAMEm2623 P5E_CPU1_G1_TX_C_DP<7>                                            
P  NNAMEm2624 P5E_CPU1_G1_TX_C_DP<6>                                            
P  NNAMEm2625 P5E_CPU1_G1_TX_C_DP<5>                                            
P  NNAMEm2626 P5E_CPU1_G1_TX_C_DP<4>                                            
P  NNAMEm2627 P5E_CPU1_G1_TX_C_DP<3>                                            
P  NNAMEm2628 P5E_CPU1_G1_TX_C_DP<2>                                            
P  NNAMEm2629 P5E_CPU1_G1_TX_C_DP<1>                                            
P  NNAMEm2630 P5E_CPU1_G1_TX_C_DP<15>                                           
P  NNAMEm2631 P5E_CPU1_G1_TX_C_DP<14>                                           
P  NNAMEm2632 P5E_CPU1_G1_TX_C_DP<13>                                           
P  NNAMEm2633 P5E_CPU1_G1_TX_C_DP<12>                                           
P  NNAMEm2634 P5E_CPU1_G1_TX_C_DP<11>                                           
P  NNAMEm2635 P5E_CPU1_G1_TX_C_DP<10>                                           
P  NNAMEm2636 P5E_CPU1_G1_TX_C_DP<0>                                            
P  NNAMEm2637 P5E_CPU1_G1_TX_C_DN<9>                                            
P  NNAMEm2638 P5E_CPU1_G1_TX_C_DN<8>                                            
P  NNAMEm2639 P5E_CPU1_G1_TX_C_DN<7>                                            
P  NNAMEm2640 P5E_CPU1_G1_TX_C_DN<6>                                            
P  NNAMEm2641 P5E_CPU1_G1_TX_C_DN<5>                                            
P  NNAMEm2642 P5E_CPU1_G1_TX_C_DN<4>                                            
P  NNAMEm2643 P5E_CPU1_G1_TX_C_DN<3>                                            
P  NNAMEm2644 P5E_CPU1_G1_TX_C_DN<2>                                            
P  NNAMEm2645 P5E_CPU1_G1_TX_C_DN<1>                                            
P  NNAMEm2646 P5E_CPU1_G1_TX_C_DN<15>                                           
P  NNAMEm2647 P5E_CPU1_G1_TX_C_DN<14>                                           
P  NNAMEm2648 P5E_CPU1_G1_TX_C_DN<13>                                           
P  NNAMEm2649 P5E_CPU1_G1_TX_C_DN<12>                                           
P  NNAMEm2650 P5E_CPU1_G1_TX_C_DN<11>                                           
P  NNAMEm2651 P5E_CPU1_G1_TX_C_DN<10>                                           
P  NNAMEm2652 P5E_CPU1_G1_TX_C_DN<0>                                            
P  NNAMEm2653 P5E_CPU0_P3_TX_DP<9>                                              
P  NNAMEm2654 P5E_CPU0_P3_TX_DP<8>                                              
P  NNAMEm2655 P5E_CPU0_P3_TX_DP<3>                                              
P  NNAMEm2656 P5E_CPU0_P3_TX_DP<2>                                              
P  NNAMEm2657 P5E_CPU0_P3_TX_DP<1>                                              
P  NNAMEm2658 P5E_CPU0_P3_TX_DP<15>                                             
P  NNAMEm2659 P5E_CPU0_P3_TX_DP<14>                                             
P  NNAMEm2660 P5E_CPU0_P3_TX_DP<13>                                             
P  NNAMEm2661 P5E_CPU0_P3_TX_DP<12>                                             
P  NNAMEm2662 P5E_CPU0_P3_TX_DP<11>                                             
P  NNAMEm2663 P5E_CPU0_P3_TX_DP<10>                                             
P  NNAMEm2664 P5E_CPU0_P3_TX_DP<0>                                              
P  NNAMEm2665 P5E_CPU0_P3_TX_DN<9>                                              
P  NNAMEm2666 P5E_CPU0_P3_TX_DN<8>                                              
P  NNAMEm2667 P5E_CPU0_P3_TX_DN<3>                                              
P  NNAMEm2668 P5E_CPU0_P3_TX_DN<2>                                              
P  NNAMEm2669 P5E_CPU0_P3_TX_DN<1>                                              
P  NNAMEm2670 P5E_CPU0_P3_TX_DN<15>                                             
P  NNAMEm2671 P5E_CPU0_P3_TX_DN<14>                                             
P  NNAMEm2672 P5E_CPU0_P3_TX_DN<13>                                             
P  NNAMEm2673 P5E_CPU0_P3_TX_DN<12>                                             
P  NNAMEm2674 P5E_CPU0_P3_TX_DN<11>                                             
P  NNAMEm2675 P5E_CPU0_P3_TX_DN<10>                                             
P  NNAMEm2676 P5E_CPU0_P3_TX_DN<0>                                              
P  NNAMEm2677 P5E_CPU0_P3_TX_C_DP<9>                                            
P  NNAMEm2678 P5E_CPU0_P3_TX_C_DP<8>                                            
P  NNAMEm2679 P5E_CPU0_P3_TX_C_DP<7>                                            
P  NNAMEm2680 P5E_CPU0_P3_TX_C_DP<6>                                            
P  NNAMEm2681 P5E_CPU0_P3_TX_C_DP<5>                                            
P  NNAMEm2682 P5E_CPU0_P3_TX_C_DP<4>                                            
P  NNAMEm2683 P5E_CPU0_P3_TX_C_DP<3>                                            
P  NNAMEm2684 P5E_CPU0_P3_TX_C_DP<2>                                            
P  NNAMEm2685 P5E_CPU0_P3_TX_C_DP<1>                                            
P  NNAMEm2686 P5E_CPU0_P3_TX_C_DP<15>                                           
P  NNAMEm2687 P5E_CPU0_P3_TX_C_DP<14>                                           
P  NNAMEm2688 P5E_CPU0_P3_TX_C_DP<13>                                           
P  NNAMEm2689 P5E_CPU0_P3_TX_C_DP<12>                                           
P  NNAMEm2690 P5E_CPU0_P3_TX_C_DP<11>                                           
P  NNAMEm2691 P5E_CPU0_P3_TX_C_DP<10>                                           
P  NNAMEm2692 P5E_CPU0_P3_TX_C_DP<0>                                            
P  NNAMEm2693 P5E_CPU0_P3_TX_C_DN<9>                                            
P  NNAMEm2694 P5E_CPU0_P3_TX_C_DN<8>                                            
P  NNAMEm2695 P5E_CPU0_P3_TX_C_DN<7>                                            
P  NNAMEm2696 P5E_CPU0_P3_TX_C_DN<6>                                            
P  NNAMEm2697 P5E_CPU0_P3_TX_C_DN<5>                                            
P  NNAMEm2698 P5E_CPU0_P3_TX_C_DN<4>                                            
P  NNAMEm2699 P5E_CPU0_P3_TX_C_DN<3>                                            
P  NNAMEm2700 P5E_CPU0_P3_TX_C_DN<2>                                            
P  NNAMEm2701 P5E_CPU0_P3_TX_C_DN<1>                                            
P  NNAMEm2702 P5E_CPU0_P3_TX_C_DN<15>                                           
P  NNAMEm2703 P5E_CPU0_P3_TX_C_DN<14>                                           
P  NNAMEm2704 P5E_CPU0_P3_TX_C_DN<13>                                           
P  NNAMEm2705 P5E_CPU0_P3_TX_C_DN<12>                                           
P  NNAMEm2706 P5E_CPU0_P3_TX_C_DN<11>                                           
P  NNAMEm2707 P5E_CPU0_P3_TX_C_DN<10>                                           
P  NNAMEm2708 P5E_CPU0_P3_TX_C_DN<0>                                            
P  NNAMEm2709 P5E_CPU0_P3_RX_DP<3>                                              
P  NNAMEm2710 P5E_CPU0_P3_RX_DP<2>                                              
P  NNAMEm2711 P5E_CPU0_P3_RX_DP<1>                                              
P  NNAMEm2712 P5E_CPU0_P3_RX_DP<15>                                             
P  NNAMEm2713 P5E_CPU0_P3_RX_DP<14>                                             
P  NNAMEm2714 P5E_CPU0_P3_RX_DP<13>                                             
P  NNAMEm2715 P5E_CPU0_P3_RX_DP<12>                                             
P  NNAMEm2716 P5E_CPU0_P3_RX_DN<3>                                              
P  NNAMEm2717 P5E_CPU0_P3_RX_DN<2>                                              
P  NNAMEm2718 P5E_CPU0_P3_RX_DN<1>                                              
P  NNAMEm2719 P5E_CPU0_P3_RX_DN<15>                                             
P  NNAMEm2720 P5E_CPU0_P3_RX_DN<14>                                             
P  NNAMEm2721 P5E_CPU0_P3_RX_DN<13>                                             
P  NNAMEm2722 P5E_CPU0_P3_RX_DN<12>                                             
P  NNAMEm2723 P5E_CPU0_P2_TX_C_DP<9>                                            
P  NNAMEm2724 P5E_CPU0_P2_TX_C_DP<8>                                            
P  NNAMEm2725 P5E_CPU0_P2_TX_C_DP<7>                                            
P  NNAMEm2726 P5E_CPU0_P2_TX_C_DP<6>                                            
P  NNAMEm2727 P5E_CPU0_P2_TX_C_DP<5>                                            
P  NNAMEm2728 P5E_CPU0_P2_TX_C_DP<4>                                            
P  NNAMEm2729 P5E_CPU0_P2_TX_C_DP<3>                                            
P  NNAMEm2730 P5E_CPU0_P2_TX_C_DP<2>                                            
P  NNAMEm2731 P5E_CPU0_P2_TX_C_DP<1>                                            
P  NNAMEm2732 P5E_CPU0_P2_TX_C_DP<15>                                           
P  NNAMEm2733 P5E_CPU0_P2_TX_C_DP<14>                                           
P  NNAMEm2734 P5E_CPU0_P2_TX_C_DP<13>                                           
P  NNAMEm2735 P5E_CPU0_P2_TX_C_DP<12>                                           
P  NNAMEm2736 P5E_CPU0_P2_TX_C_DP<11>                                           
P  NNAMEm2737 P5E_CPU0_P2_TX_C_DP<10>                                           
P  NNAMEm2738 P5E_CPU0_P2_TX_C_DP<0>                                            
P  NNAMEm2739 P5E_CPU0_P2_TX_C_DN<9>                                            
P  NNAMEm2740 P5E_CPU0_P2_TX_C_DN<8>                                            
P  NNAMEm2741 P5E_CPU0_P2_TX_C_DN<7>                                            
P  NNAMEm2742 P5E_CPU0_P2_TX_C_DN<6>                                            
P  NNAMEm2743 P5E_CPU0_P2_TX_C_DN<5>                                            
P  NNAMEm2744 P5E_CPU0_P2_TX_C_DN<4>                                            
P  NNAMEm2745 P5E_CPU0_P2_TX_C_DN<3>                                            
P  NNAMEm2746 P5E_CPU0_P2_TX_C_DN<2>                                            
P  NNAMEm2747 P5E_CPU0_P2_TX_C_DN<1>                                            
P  NNAMEm2748 P5E_CPU0_P2_TX_C_DN<15>                                           
P  NNAMEm2749 P5E_CPU0_P2_TX_C_DN<14>                                           
P  NNAMEm2750 P5E_CPU0_P2_TX_C_DN<13>                                           
P  NNAMEm2751 P5E_CPU0_P2_TX_C_DN<12>                                           
P  NNAMEm2752 P5E_CPU0_P2_TX_C_DN<11>                                           
P  NNAMEm2753 P5E_CPU0_P2_TX_C_DN<10>                                           
P  NNAMEm2754 P5E_CPU0_P2_TX_C_DN<0>                                            
P  NNAMEm2755 P5E_CPU0_P1_TX_C_DP<9>                                            
P  NNAMEm2756 P5E_CPU0_P1_TX_C_DP<8>                                            
P  NNAMEm2757 P5E_CPU0_P1_TX_C_DP<7>                                            
P  NNAMEm2758 P5E_CPU0_P1_TX_C_DP<6>                                            
P  NNAMEm2759 P5E_CPU0_P1_TX_C_DP<5>                                            
P  NNAMEm2760 P5E_CPU0_P1_TX_C_DP<4>                                            
P  NNAMEm2761 P5E_CPU0_P1_TX_C_DP<3>                                            
P  NNAMEm2762 P5E_CPU0_P1_TX_C_DP<2>                                            
P  NNAMEm2763 P5E_CPU0_P1_TX_C_DP<1>                                            
P  NNAMEm2764 P5E_CPU0_P1_TX_C_DP<15>                                           
P  NNAMEm2765 P5E_CPU0_P1_TX_C_DP<14>                                           
P  NNAMEm2766 P5E_CPU0_P1_TX_C_DP<13>                                           
P  NNAMEm2767 P5E_CPU0_P1_TX_C_DP<12>                                           
P  NNAMEm2768 P5E_CPU0_P1_TX_C_DP<11>                                           
P  NNAMEm2769 P5E_CPU0_P1_TX_C_DP<10>                                           
P  NNAMEm2770 P5E_CPU0_P1_TX_C_DP<0>                                            
P  NNAMEm2771 P5E_CPU0_P1_TX_C_DN<9>                                            
P  NNAMEm2772 P5E_CPU0_P1_TX_C_DN<8>                                            
P  NNAMEm2773 P5E_CPU0_P1_TX_C_DN<7>                                            
P  NNAMEm2774 P5E_CPU0_P1_TX_C_DN<6>                                            
P  NNAMEm2775 P5E_CPU0_P1_TX_C_DN<5>                                            
P  NNAMEm2776 P5E_CPU0_P1_TX_C_DN<4>                                            
P  NNAMEm2777 P5E_CPU0_P1_TX_C_DN<3>                                            
P  NNAMEm2778 P5E_CPU0_P1_TX_C_DN<2>                                            
P  NNAMEm2779 P5E_CPU0_P1_TX_C_DN<1>                                            
P  NNAMEm2780 P5E_CPU0_P1_TX_C_DN<15>                                           
P  NNAMEm2781 P5E_CPU0_P1_TX_C_DN<14>                                           
P  NNAMEm2782 P5E_CPU0_P1_TX_C_DN<13>                                           
P  NNAMEm2783 P5E_CPU0_P1_TX_C_DN<12>                                           
P  NNAMEm2784 P5E_CPU0_P1_TX_C_DN<11>                                           
P  NNAMEm2785 P5E_CPU0_P1_TX_C_DN<10>                                           
P  NNAMEm2786 P5E_CPU0_P1_TX_C_DN<0>                                            
P  NNAMEm2787 P5E_CPU0_P0_TX_C_DP<9>                                            
P  NNAMEm2788 P5E_CPU0_P0_TX_C_DP<8>                                            
P  NNAMEm2789 P5E_CPU0_P0_TX_C_DP<7>                                            
P  NNAMEm2790 P5E_CPU0_P0_TX_C_DP<6>                                            
P  NNAMEm2791 P5E_CPU0_P0_TX_C_DP<5>                                            
P  NNAMEm2792 P5E_CPU0_P0_TX_C_DP<4>                                            
P  NNAMEm2793 P5E_CPU0_P0_TX_C_DP<3>                                            
P  NNAMEm2794 P5E_CPU0_P0_TX_C_DP<2>                                            
P  NNAMEm2795 P5E_CPU0_P0_TX_C_DP<1>                                            
P  NNAMEm2796 P5E_CPU0_P0_TX_C_DP<15>                                           
P  NNAMEm2797 P5E_CPU0_P0_TX_C_DP<14>                                           
P  NNAMEm2798 P5E_CPU0_P0_TX_C_DP<13>                                           
P  NNAMEm2799 P5E_CPU0_P0_TX_C_DP<12>                                           
P  NNAMEm2800 P5E_CPU0_P0_TX_C_DP<11>                                           
P  NNAMEm2801 P5E_CPU0_P0_TX_C_DP<10>                                           
P  NNAMEm2802 P5E_CPU0_P0_TX_C_DP<0>                                            
P  NNAMEm2803 P5E_CPU0_P0_TX_C_DN<9>                                            
P  NNAMEm2804 P5E_CPU0_P0_TX_C_DN<8>                                            
P  NNAMEm2805 P5E_CPU0_P0_TX_C_DN<7>                                            
P  NNAMEm2806 P5E_CPU0_P0_TX_C_DN<6>                                            
P  NNAMEm2807 P5E_CPU0_P0_TX_C_DN<5>                                            
P  NNAMEm2808 P5E_CPU0_P0_TX_C_DN<4>                                            
P  NNAMEm2809 P5E_CPU0_P0_TX_C_DN<3>                                            
P  NNAMEm2810 P5E_CPU0_P0_TX_C_DN<2>                                            
P  NNAMEm2811 P5E_CPU0_P0_TX_C_DN<1>                                            
P  NNAMEm2812 P5E_CPU0_P0_TX_C_DN<15>                                           
P  NNAMEm2813 P5E_CPU0_P0_TX_C_DN<14>                                           
P  NNAMEm2814 P5E_CPU0_P0_TX_C_DN<13>                                           
P  NNAMEm2815 P5E_CPU0_P0_TX_C_DN<12>                                           
P  NNAMEm2816 P5E_CPU0_P0_TX_C_DN<11>                                           
P  NNAMEm2817 P5E_CPU0_P0_TX_C_DN<10>                                           
P  NNAMEm2818 P5E_CPU0_P0_TX_C_DN<0>                                            
P  NNAMEm2819 P5E_CPU0_G3_TX_C_DP<9>                                            
P  NNAMEm2820 P5E_CPU0_G3_TX_C_DP<8>                                            
P  NNAMEm2821 P5E_CPU0_G3_TX_C_DP<7>                                            
P  NNAMEm2822 P5E_CPU0_G3_TX_C_DP<6>                                            
P  NNAMEm2823 P5E_CPU0_G3_TX_C_DP<5>                                            
P  NNAMEm2824 P5E_CPU0_G3_TX_C_DP<4>                                            
P  NNAMEm2825 P5E_CPU0_G3_TX_C_DP<3>                                            
P  NNAMEm2826 P5E_CPU0_G3_TX_C_DP<2>                                            
P  NNAMEm2827 P5E_CPU0_G3_TX_C_DP<1>                                            
P  NNAMEm2828 P5E_CPU0_G3_TX_C_DP<15>                                           
P  NNAMEm2829 P5E_CPU0_G3_TX_C_DP<14>                                           
P  NNAMEm2830 P5E_CPU0_G3_TX_C_DP<13>                                           
P  NNAMEm2831 P5E_CPU0_G3_TX_C_DP<12>                                           
P  NNAMEm2832 P5E_CPU0_G3_TX_C_DP<11>                                           
P  NNAMEm2833 P5E_CPU0_G3_TX_C_DP<10>                                           
P  NNAMEm2834 P5E_CPU0_G3_TX_C_DP<0>                                            
P  NNAMEm2835 P5E_CPU0_G3_TX_C_DN<9>                                            
P  NNAMEm2836 P5E_CPU0_G3_TX_C_DN<8>                                            
P  NNAMEm2837 P5E_CPU0_G3_TX_C_DN<7>                                            
P  NNAMEm2838 P5E_CPU0_G3_TX_C_DN<6>                                            
P  NNAMEm2839 P5E_CPU0_G3_TX_C_DN<5>                                            
P  NNAMEm2840 P5E_CPU0_G3_TX_C_DN<4>                                            
P  NNAMEm2841 P5E_CPU0_G3_TX_C_DN<3>                                            
P  NNAMEm2842 P5E_CPU0_G3_TX_C_DN<2>                                            
P  NNAMEm2843 P5E_CPU0_G3_TX_C_DN<1>                                            
P  NNAMEm2844 P5E_CPU0_G3_TX_C_DN<15>                                           
P  NNAMEm2845 P5E_CPU0_G3_TX_C_DN<14>                                           
P  NNAMEm2846 P5E_CPU0_G3_TX_C_DN<13>                                           
P  NNAMEm2847 P5E_CPU0_G3_TX_C_DN<12>                                           
P  NNAMEm2848 P5E_CPU0_G3_TX_C_DN<11>                                           
P  NNAMEm2849 P5E_CPU0_G3_TX_C_DN<10>                                           
P  NNAMEm2850 P5E_CPU0_G3_TX_C_DN<0>                                            
P  NNAMEm2851 P3V3_PDB_AUX_ADC                                                  
P  NNAMEm2852 P3V3_AUX_USB_HUB                                                  
P  NNAMEm2853 P3E_CPU1_P5_TX_DP<1>                                              
P  NNAMEm2854 P3E_CPU1_P5_TX_DP<0>                                              
P  NNAMEm2855 P3E_CPU1_P5_TX_DN<1>                                              
P  NNAMEm2856 P3E_CPU1_P5_TX_DN<0>                                              
P  NNAMEm2857 P3E_CPU1_P5_RX_DP<1>                                              
P  NNAMEm2858 P3E_CPU1_P5_RX_DP<0>                                              
P  NNAMEm2859 P3E_CPU1_P5_RX_DN<1>                                              
P  NNAMEm2860 P3E_CPU1_P5_RX_DN<0>                                              
P  NNAMEm2861 P3E_CPU1_P4_TX_DP<3>                                              
P  NNAMEm2862 P3E_CPU1_P4_TX_DP<2>                                              
P  NNAMEm2863 P3E_CPU1_P4_TX_DP<1>                                              
P  NNAMEm2864 P3E_CPU1_P4_TX_DP<0>                                              
P  NNAMEm2865 P3E_CPU1_P4_TX_DN<3>                                              
P  NNAMEm2866 P3E_CPU1_P4_TX_DN<2>                                              
P  NNAMEm2867 P3E_CPU1_P4_TX_DN<1>                                              
P  NNAMEm2868 P3E_CPU1_P4_TX_DN<0>                                              
P  NNAMEm2869 P3E_CPU1_P4_RX_DP<3>                                              
P  NNAMEm2870 P3E_CPU1_P4_RX_DP<2>                                              
P  NNAMEm2871 P3E_CPU1_P4_RX_DP<1>                                              
P  NNAMEm2872 P3E_CPU1_P4_RX_DP<0>                                              
P  NNAMEm2873 P3E_CPU1_P4_RX_DN<3>                                              
P  NNAMEm2874 P3E_CPU1_P4_RX_DN<2>                                              
P  NNAMEm2875 P3E_CPU1_P4_RX_DN<1>                                              
P  NNAMEm2876 P3E_CPU1_P4_RX_DN<0>                                              
P  NNAMEm2877 P3E_CPU0_P4_TX_DP<3>                                              
P  NNAMEm2878 P3E_CPU0_P4_TX_DP<2>                                              
P  NNAMEm2879 P3E_CPU0_P4_TX_DP<1>                                              
P  NNAMEm2880 P3E_CPU0_P4_TX_DP<0>                                              
P  NNAMEm2881 P3E_CPU0_P4_TX_DN<3>                                              
P  NNAMEm2882 P3E_CPU0_P4_TX_DN<2>                                              
P  NNAMEm2883 P3E_CPU0_P4_TX_DN<1>                                              
P  NNAMEm2884 P3E_CPU0_P4_TX_DN<0>                                              
P  NNAMEm2885 P3E_CPU0_P4_RX_DP<3>                                              
P  NNAMEm2886 P3E_CPU0_P4_RX_DP<2>                                              
P  NNAMEm2887 P3E_CPU0_P4_RX_DP<1>                                              
P  NNAMEm2888 P3E_CPU0_P4_RX_DP<0>                                              
P  NNAMEm2889 P3E_CPU0_P4_RX_DN<3>                                              
P  NNAMEm2890 P3E_CPU0_P4_RX_DN<2>                                              
P  NNAMEm2891 P3E_CPU0_P4_RX_DN<1>                                              
P  NNAMEm2892 P3E_CPU0_P4_RX_DN<0>                                              
P  NNAMEm2893 P2E_CPU0_P5_RX_DP                                                 
P  NNAMEm2894 P2E_CPU0_P5_RX_DN                                                 
P  NNAMEm2895 P12V_SCM_ADC_ALERT_R                                              
P  NNAMEm2896 P12V_SCM_ADC_ALERT                                                
P  NNAMEm2897 P12V_AUX_BLEEDING                                                 
P  NNAMEm2898 OCP_V3_2_P3V3_ADC_ALERT_R                                         
P  NNAMEm2899 OCP_SFF_P3V3_ADC_ALERT_R                                          
P  NNAMEm2900 NC_INA230_5_NC5                                                   
P  NNAMEm2901 NC_INA230_5_NC4                                                   
P  NNAMEm2902 NC_INA230_5_NC3                                                   
P  NNAMEm2903 NC_INA230_5_NC2                                                   
P  NNAMEm2904 NC_INA230_5_NC1                                                   
P  NNAMEm2905 NC_INA230_5_NC0                                                   
P  NNAMEm2906 NC_INA230_4_NC5                                                   
P  NNAMEm2907 NC_INA230_4_NC4                                                   
P  NNAMEm2908 NC_INA230_4_NC3                                                   
P  NNAMEm2909 NC_INA230_4_NC2                                                   
P  NNAMEm2910 NC_INA230_4_NC1                                                   
P  NNAMEm2911 NC_INA230_4_NC0                                                   
P  NNAMEm2912 NC_INA230_3_NC5                                                   
P  NNAMEm2913 NC_INA230_3_NC4                                                   
P  NNAMEm2914 NC_INA230_3_NC3                                                   
P  NNAMEm2915 NC_INA230_3_NC2                                                   
P  NNAMEm2916 NC_INA230_3_NC1                                                   
P  NNAMEm2917 NC_INA230_3_NC0                                                   
P  NNAMEm2918 NC_INA230_2_NC5                                                   
P  NNAMEm2919 NC_INA230_2_NC4                                                   
P  NNAMEm2920 NC_INA230_2_NC3                                                   
P  NNAMEm2921 NC_INA230_2_NC2                                                   
P  NNAMEm2922 NC_INA230_2_NC1                                                   
P  NNAMEm2923 NC_INA230_2_NC0                                                   
P  NNAMEm2924 NC_INA230_1_NC5                                                   
P  NNAMEm2925 NC_INA230_1_NC4                                                   
P  NNAMEm2926 NC_INA230_1_NC3                                                   
P  NNAMEm2927 NC_INA230_1_NC2                                                   
P  NNAMEm2928 NC_INA230_1_NC1                                                   
P  NNAMEm2929 NC_INA230_1_NC0                                                   
P  NNAMEm2930 MB_PDB_SMB9_R_EN                                                  
P  NNAMEm2931 M2_0_P3V3_ADC_ALERT_R                                             
P  NNAMEm2932 M2_0_P3V3_ADC_ALERT                                               
P  NNAMEm2933 HPDB_HSC_PWRGD_R                                                  
P  NNAMEm2934 HPDB_HSC_PWRGD_N                                                  
P  NNAMEm2935 HPDB_HSC_PWRGD_ISO                                                
P  NNAMEm2936 FM_THERMAL_ALERT_N                                                
P  NNAMEm2937 FM_P12V_HSC_EN_R_N                                                
P  NNAMEm2938 FM_P12V_HSC_EN_R                                                  
P  NNAMEm2939 FM_P12V_HSC_EN_N                                                  
P  NNAMEm2940 FM_LM75_3_ALERT_N                                                 
P  NNAMEm2941 FM_LM75_2_ALERT_N                                                 
P  NNAMEm2942 FM_GPU_HSC_EN_BUF_R1                                              
P  NNAMEm2943 FM_GPU_HSC_EN_BUF_R                                               
P  NNAMEm2944 FM_GPU_HSC_EN_BUF                                                 
P  NNAMEm2945 FM_G751_1_ALERT_N                                                 
P  NNAMEm2946 FM_G751_0_ALERT_N                                                 
P  NNAMEm2947 FM_FAN_PWR_EN_R                                                   
P  NNAMEm2948 E1S_0_P3V3_ADC_ALERT_R                                            
P  NNAMEm2949 XTAL_CPU1_X48M_X2                                                 
P  NNAMEm2950 XTAL_CPU1_X48M_X1                                                 
P  NNAMEm2951 XTAL_CPU1_X32K_X2                                                 
P  NNAMEm2952 XTAL_CPU1_X32K_X1                                                 
P  NNAMEm2953 XTAL_CPU1_R_X32K_X2                                               
P  NNAMEm2954 XTAL_CPU1_R_X32K_X1                                               
P  NNAMEm2955 XTAL_CPU0_X48M_X2                                                 
P  NNAMEm2956 XTAL_CPU0_X48M_X1                                                 
P  NNAMEm2957 XTAL_CPU0_X32K_X2                                                 
P  NNAMEm2958 XTAL_CPU0_X32K_X1                                                 
P  NNAMEm2959 WAFL_CPU1_TX1_CPU0_RX0_DP                                         
P  NNAMEm2960 WAFL_CPU1_TX1_CPU0_RX0_DN                                         
P  NNAMEm2961 WAFL_CPU0_TX0_CPU1_RX1_DP                                         
P  NNAMEm2962 WAFL_CPU0_TX0_CPU1_RX1_DN                                         
P  NNAMEm2963 VSENSE_VSS_SENSE_C_P1                                             
P  NNAMEm2964 VSENSE_VSS_SENSE_C_P0                                             
P  NNAMEm2965 VSENSE_VSS_SENSE_B_P1                                             
P  NNAMEm2966 VSENSE_VSS_SENSE_B_P0                                             
P  NNAMEm2967 VSENSE_VSS_SENSE_A_P1                                             
P  NNAMEm2968 VSENSE_VSS_SENSE_A_P0                                             
P  NNAMEm2969 VSENSE_PVDDIO_P1_VSEN1                                            
P  NNAMEm2970 VSENSE_PVDDIO_P1_DP                                               
P  NNAMEm2971 VSENSE_PVDDIO_P0_VSEN1                                            
P  NNAMEm2972 VSENSE_PVDDIO_P0_DP                                               
P  NNAMEm2973 VSENSE_PVDDCR_SOC_P1_VSEN1                                        
P  NNAMEm2974 VSENSE_PVDDCR_SOC_P1_DP                                           
P  NNAMEm2975 VSENSE_PVDDCR_SOC_P0_VSEN1                                        
P  NNAMEm2976 VSENSE_PVDDCR_SOC_P0_DP                                           
P  NNAMEm2977 VSENSE_PVDDCR_CPU1_P1_VSEN0                                       
P  NNAMEm2978 VSENSE_PVDDCR_CPU1_P1_DP                                          
P  NNAMEm2979 VSENSE_PVDDCR_CPU1_P0_VSEN0                                       
P  NNAMEm2980 VSENSE_PVDDCR_CPU1_P0_DP                                          
P  NNAMEm2981 VSENSE_PVDDCR_CPU0_P1_VSEN0                                       
P  NNAMEm2982 VSENSE_PVDDCR_CPU0_P1_DP                                          
P  NNAMEm2983 VSENSE_PVDDCR_CPU0_P0_VSEN0                                       
P  NNAMEm2984 VSENSE_PVDDCR_CPU0_P0_DP                                          
P  NNAMEm2985 VSENSE_PVDD18_S5_P1_DP                                            
P  NNAMEm2986 VSENSE_PVDD18_S5_P1_DN                                            
P  NNAMEm2987 VSENSE_PVDD18_S5_P0_DP                                            
P  NNAMEm2988 VSENSE_PVDD18_S5_P0_DN                                            
P  NNAMEm2989 VSENSE_PVDD11_S3_P1_R                                             
P  NNAMEm2990 VSENSE_PVDD11_S3_P1_DP                                            
P  NNAMEm2991 VSENSE_PVDD11_S3_P0_R                                             
P  NNAMEm2992 VSENSE_PVDD11_S3_P0_DP                                            
P  NNAMEm2993 VIRTUAL_RESEAT_FPGA_N                                             
P  NNAMEm2994 USB2_HUB_BUF_SWB_DP                                               
P  NNAMEm2995 USB2_HUB_BUF_SWB_DN                                               
P  NNAMEm2996 USB2_HOST_BMC_B_DP                                                
P  NNAMEm2997 USB2_HOST_BMC_B_DN                                                
P  NNAMEm2998 USB2_CPU0_P1_DP                                                   
P  NNAMEm2999 USB2_CPU0_P1_DN                                                   
P  NNAMEm3000 USB2_CPU0_P10_DP                                                  
P  NNAMEm3001 USB2_CPU0_P10_DN                                                  
P  NNAMEm3002 USB2_CPU0_P0_DP                                                   
P  NNAMEm3003 USB2_CPU0_P0_DN                                                   
P  NNAMEm3004 UART_CPU0_SCM_LVC3_UART1_RX                                       
P  NNAMEm3005 UART_CPU0_UART0_TX                                                
P  NNAMEm3006 UART_CPU0_UART0_R_TX                                              
P  NNAMEm3007 UART_CPU0_UART0_R_RX                                              
P  NNAMEm3008 UART_CPU0_UART0_RX                                                
P  NNAMEm3009 UART_CPU0_SCM_UART1_TX                                            
P  NNAMEm3010 UART_CPU0_SCM_UART1_R_TX                                          
P  NNAMEm3011 UART_CPU0_SCM_UART1_R_RX                                          
P  NNAMEm3012 UART_CPU0_SCM_UART1_RX                                            
P  NNAMEm3013 UART_CPU0_SCM_LVC3_UART1_TX                                       
P  NNAMEm3014 UART_CPU0_SCM_LVC3_UART1_R_TX                                     
P  NNAMEm3015 UART_CPU0_SCM_LVC3_UART1_R_RX                                     
P  NNAMEm3016 UART_CPU0_LVC3_UART0_TX                                           
P  NNAMEm3017 UART_CPU0_LVC3_UART0_R_TX                                         
P  NNAMEm3018 UART_CPU0_LVC3_UART0_R_RX                                         
P  NNAMEm3019 UART_CPU0_LVC3_UART0_RX                                           
P  NNAMEm3020 UART_BMC_BIC_TX                                                   
P  NNAMEm3021 UART_BMC_BIC_R_RX                                                 
P  NNAMEm3022 UART_BMC_BIC_R_BUF_RX                                             
P  NNAMEm3023 UART_BMC_BIC_RX                                                   
P  NNAMEm3024 UART_BMC_BIC_BUF_RX                                               
P  NNAMEm3025 TP_VSENSE_PVDD33_S5_P1                                            
P  NNAMEm3026 TP_VSENSE_PVDD33_S5_P0                                            
P  NNAMEm3027 TP_UART_CPU0_UART0_RTS_N                                          
P  NNAMEm3028 TP_SPI_2_PLD_IO3                                                  
P  NNAMEm3029 TP_SPI_2_PLD_IO2                                                  
P  NNAMEm3030 TP_SPI_2_PLD_IO1                                                  
P  NNAMEm3031 TP_SPI_2_PLD_IO0                                                  
P  NNAMEm3032 TP_SPI_2_PLD_CS_N                                                 
P  NNAMEm3033 TP_SPI_2_PLD_CLK                                                  
P  NNAMEm3034 TP_OCP_V3_2_B69                                                   
P  NNAMEm3035 TP_OCP_V3_2_B68                                                   
P  NNAMEm3036 TP_M_L_CPU1_SA_TEST39L                                            
P  NNAMEm3037 TP_M_L_CPU0_SA_TEST39L                                            
P  NNAMEm3038 TP_M_K_CPU1_SA_TEST39K                                            
P  NNAMEm3039 TP_M_K_CPU0_SA_TEST39K                                            
P  NNAMEm3040 TP_M_J_CPU1_SA_TEST39J                                            
P  NNAMEm3041 TP_M_J_CPU0_SA_TEST39J                                            
P  NNAMEm3042 TP_M_I_CPU1_SA_TEST39I                                            
P  NNAMEm3043 TP_M_I_CPU0_SA_TEST39I                                            
P  NNAMEm3044 TP_M_H_CPU1_SA_TEST39H                                            
P  NNAMEm3045 TP_M_H_CPU0_SA_TEST39H                                            
P  NNAMEm3046 TP_M_G_CPU1_SA_TEST39G                                            
P  NNAMEm3047 TP_M_G_CPU0_SA_TEST39G                                            
P  NNAMEm3048 TP_M_F_CPU1_SA_TEST39F                                            
P  NNAMEm3049 TP_M_F_CPU0_SA_TEST39F                                            
P  NNAMEm3050 TP_M_E_CPU1_SA_TEST39E                                            
P  NNAMEm3051 TP_M_E_CPU0_SA_TEST39E                                            
P  NNAMEm3052 TP_M_D_CPU1_SA_TEST39D                                            
P  NNAMEm3053 TP_M_D_CPU0_SA_TEST39D                                            
P  NNAMEm3054 TP_M_C_CPU1_SA_TEST39C                                            
P  NNAMEm3055 TP_M_C_CPU0_SA_TEST39C                                            
P  NNAMEm3056 TP_M_B_CPU1_SA_TEST39B                                            
P  NNAMEm3057 TP_M_B_CPU0_SA_TEST39B                                            
P  NNAMEm3058 TP_M_A_CPU1_SA_TEST40                                             
P  NNAMEm3059 TP_M_A_CPU1_SA_TEST39A                                            
P  NNAMEm3060 TP_M_A_CPU0_SA_TEST40                                             
P  NNAMEm3061 TP_M_A_CPU0_SA_TEST39A                                            
P  NNAMEm3062 TP_JTAG_SCM_SLOT3_R_TMS                                           
P  NNAMEm3063 TP_JTAG_SCM_SLOT3_R_TDO                                           
P  NNAMEm3064 TP_JTAG_SCM_SLOT3_R_TDI                                           
P  NNAMEm3065 TP_JTAG_SCM_SLOT3_R_TCK                                           
P  NNAMEm3066 TP_CPU1_UART1_RX                                                  
P  NNAMEm3067 TP_CPU1_UART0_TX                                                  
P  NNAMEm3068 TP_CPU1_UART0_RX                                                  
P  NNAMEm3069 TP_CPU1_UART0_RTS_N                                               
P  NNAMEm3070 TP_CPU1_UART0_INTR                                                
P  NNAMEm3071 TP_CPU1_UART0_CTS_N                                               
P  NNAMEm3072 TP_CPU1_TEST6_X3D5                                                
P  NNAMEm3073 TP_CPU1_TEST6_X3D4                                                
P  NNAMEm3074 TP_CPU1_TEST6_X3D3                                                
P  NNAMEm3075 TP_CPU1_TEST6_X3D2                                                
P  NNAMEm3076 TP_CPU1_TEST6_X3D1                                                
P  NNAMEm3077 TP_CPU1_TEST6_X3D0                                                
P  NNAMEm3078 TP_CPU1_TEST6_IOD                                                 
P  NNAMEm3079 TP_CPU1_TEST6_CCD3                                                
P  NNAMEm3080 TP_CPU1_TEST6_CCD2                                                
P  NNAMEm3081 TP_CPU1_TEST6_CCD1                                                
P  NNAMEm3082 TP_CPU1_TEST6_CCD0                                                
P  NNAMEm3083 TP_CPU1_TEST5_IOD                                                 
P  NNAMEm3084 TP_CPU1_TEST5_CCD9                                                
P  NNAMEm3085 TP_CPU1_TEST5_CCD8                                                
P  NNAMEm3086 TP_CPU1_TEST5_CCD7                                                
P  NNAMEm3087 TP_CPU1_TEST5_CCD6                                                
P  NNAMEm3088 TP_CPU1_TEST5_CCD5                                                
P  NNAMEm3089 TP_CPU1_TEST5_CCD4                                                
P  NNAMEm3090 TP_CPU1_TEST5_CCD3                                                
P  NNAMEm3091 TP_CPU1_TEST5_CCD2                                                
P  NNAMEm3092 TP_CPU1_TEST5_CCD11                                               
P  NNAMEm3093 TP_CPU1_TEST5_CCD10                                               
P  NNAMEm3094 TP_CPU1_TEST5_CCD1                                                
P  NNAMEm3095 TP_CPU1_TEST5_CCD0                                                
P  NNAMEm3096 TP_CPU1_TEST50_IOD                                                
P  NNAMEm3097 TP_CPU1_TEST4_IOD                                                 
P  NNAMEm3098 TP_CPU1_TEST4_CCD9                                                
P  NNAMEm3099 TP_CPU1_TEST4_CCD8                                                
P  NNAMEm3100 TP_CPU1_TEST4_CCD7                                                
P  NNAMEm3101 TP_CPU1_TEST4_CCD6                                                
P  NNAMEm3102 TP_CPU1_TEST4_CCD5                                                
P  NNAMEm3103 TP_CPU1_TEST4_CCD4                                                
P  NNAMEm3104 TP_CPU1_TEST4_CCD3                                                
P  NNAMEm3105 TP_CPU1_TEST4_CCD2                                                
P  NNAMEm3106 TP_CPU1_TEST4_CCD11                                               
P  NNAMEm3107 TP_CPU1_TEST4_CCD10                                               
P  NNAMEm3108 TP_CPU1_TEST4_CCD1                                                
P  NNAMEm3109 TP_CPU1_TEST4_CCD0                                                
P  NNAMEm3110 TP_CPU1_TEST47_IOD1                                               
P  NNAMEm3111 TP_CPU1_TEST47_IOD0                                               
P  NNAMEm3112 TP_CPU1_TEST47_CCD3                                               
P  NNAMEm3113 TP_CPU1_TEST47_CCD2                                               
P  NNAMEm3114 TP_CPU1_TEST47_CCD1                                               
P  NNAMEm3115 TP_CPU1_TEST47_CCD0                                               
P  NNAMEm3116 TP_CPU1_TEST41_IOD                                                
P  NNAMEm3117 TP_CPU0_UART0_INTR                                                
P  NNAMEm3118 TP_CPU0_TEST6_X3D5                                                
P  NNAMEm3119 TP_CPU0_TEST6_X3D4                                                
P  NNAMEm3120 TP_CPU0_TEST6_X3D3                                                
P  NNAMEm3121 TP_CPU0_TEST6_X3D2                                                
P  NNAMEm3122 TP_CPU0_TEST6_X3D1                                                
P  NNAMEm3123 TP_CPU0_TEST6_X3D0                                                
P  NNAMEm3124 TP_CPU0_TEST6_IOD                                                 
P  NNAMEm3125 TP_CPU0_TEST6_CCD3                                                
P  NNAMEm3126 TP_CPU0_TEST6_CCD2                                                
P  NNAMEm3127 TP_CPU0_TEST6_CCD1                                                
P  NNAMEm3128 TP_CPU0_TEST6_CCD0                                                
P  NNAMEm3129 TP_CPU0_TEST5_IOD                                                 
P  NNAMEm3130 TP_CPU0_TEST5_CCD9                                                
P  NNAMEm3131 TP_CPU0_TEST5_CCD8                                                
P  NNAMEm3132 TP_CPU0_TEST5_CCD7                                                
P  NNAMEm3133 TP_CPU0_TEST5_CCD6                                                
P  NNAMEm3134 TP_CPU0_TEST5_CCD5                                                
P  NNAMEm3135 TP_CPU0_TEST5_CCD4                                                
P  NNAMEm3136 TP_CPU0_TEST5_CCD3                                                
P  NNAMEm3137 TP_CPU0_TEST5_CCD2                                                
P  NNAMEm3138 TP_CPU0_TEST5_CCD11                                               
P  NNAMEm3139 TP_CPU0_TEST5_CCD10                                               
P  NNAMEm3140 TP_CPU0_TEST5_CCD1                                                
P  NNAMEm3141 TP_CPU0_TEST5_CCD0                                                
P  NNAMEm3142 TP_CPU0_TEST50_IOD                                                
P  NNAMEm3143 TP_CPU0_TEST4_IOD                                                 
P  NNAMEm3144 TP_CPU0_TEST4_CCD9                                                
P  NNAMEm3145 TP_CPU0_TEST4_CCD8                                                
P  NNAMEm3146 TP_CPU0_TEST4_CCD7                                                
P  NNAMEm3147 TP_CPU0_TEST4_CCD6                                                
P  NNAMEm3148 TP_CPU0_TEST4_CCD5                                                
P  NNAMEm3149 TP_CPU0_TEST4_CCD4                                                
P  NNAMEm3150 TP_CPU0_TEST4_CCD3                                                
P  NNAMEm3151 TP_CPU0_TEST4_CCD2                                                
P  NNAMEm3152 TP_CPU0_TEST4_CCD11                                               
P  NNAMEm3153 TP_CPU0_TEST4_CCD10                                               
P  NNAMEm3154 TP_CPU0_TEST4_CCD1                                                
P  NNAMEm3155 TP_CPU0_TEST4_CCD0                                                
P  NNAMEm3156 TP_CPU0_TEST47_IOD1                                               
P  NNAMEm3157 TP_CPU0_TEST47_IOD0                                               
P  NNAMEm3158 TP_CPU0_TEST47_CCD3                                               
P  NNAMEm3159 TP_CPU0_TEST47_CCD2                                               
P  NNAMEm3160 TP_CPU0_TEST47_CCD1                                               
P  NNAMEm3161 TP_CPU0_TEST47_CCD0                                               
P  NNAMEm3162 TP_CPU0_TEST41_IDO                                                
P  NNAMEm3163 TP_CLK_100M_E1S_0_DP                                              
P  NNAMEm3164 TP_CLK_100M_E1S_0_DN                                              
P  NNAMEm3165 SW_PVDD_33_S5_SW                                                  
P  NNAMEm3166 SW_PVDD_33_S5_BST                                                 
P  NNAMEm3167 SW_PVDDIO_P1_SW4_RC                                               
P  NNAMEm3168 SW_PVDDIO_P1_SW4                                                  
P  NNAMEm3169 SW_PVDDIO_P1_SW3_RC                                               
P  NNAMEm3170 SW_PVDDIO_P1_SW3                                                  
P  NNAMEm3171 SW_PVDDIO_P1_SW2_RC                                               
P  NNAMEm3172 SW_PVDDIO_P1_SW2                                                  
P  NNAMEm3173 SW_PVDDIO_P1_SW1_RC                                               
P  NNAMEm3174 SW_PVDDIO_P1_SW1                                                  
P  NNAMEm3175 SW_PVDDIO_P1_BOOTR4                                               
P  NNAMEm3176 SW_PVDDIO_P1_BOOTR3                                               
P  NNAMEm3177 SW_PVDDIO_P1_BOOTR2                                               
P  NNAMEm3178 SW_PVDDIO_P1_BOOTR1                                               
P  NNAMEm3179 SW_PVDDIO_P1_BOOT4_R                                              
P  NNAMEm3180 SW_PVDDIO_P1_BOOT4                                                
P  NNAMEm3181 SW_PVDDIO_P1_BOOT3_R                                              
P  NNAMEm3182 SW_PVDDIO_P1_BOOT3                                                
P  NNAMEm3183 SW_PVDDIO_P1_BOOT2_R                                              
P  NNAMEm3184 SW_PVDDIO_P1_BOOT2                                                
P  NNAMEm3185 SW_PVDDIO_P1_BOOT1_R                                              
P  NNAMEm3186 SW_PVDDIO_P1_BOOT1                                                
P  NNAMEm3187 SW_PVDDIO_P0_SW4_RC                                               
P  NNAMEm3188 SW_PVDDIO_P0_SW4                                                  
P  NNAMEm3189 SW_PVDDIO_P0_SW3_RC                                               
P  NNAMEm3190 SW_PVDDIO_P0_SW3                                                  
P  NNAMEm3191 SW_PVDDIO_P0_SW2_RC                                               
P  NNAMEm3192 SW_PVDDIO_P0_SW2                                                  
P  NNAMEm3193 SW_PVDDIO_P0_SW1_RC                                               
P  NNAMEm3194 SW_PVDDIO_P0_SW1                                                  
P  NNAMEm3195 SW_PVDDIO_P0_BOOTR4                                               
P  NNAMEm3196 SW_PVDDIO_P0_BOOTR3                                               
P  NNAMEm3197 SW_PVDDIO_P0_BOOTR2                                               
P  NNAMEm3198 SW_PVDDIO_P0_BOOTR1                                               
P  NNAMEm3199 SW_PVDDIO_P0_BOOT4_R                                              
P  NNAMEm3200 SW_PVDDIO_P0_BOOT4                                                
P  NNAMEm3201 SW_PVDDIO_P0_BOOT3_R                                              
P  NNAMEm3202 SW_PVDDIO_P0_BOOT3                                                
P  NNAMEm3203 SW_PVDDIO_P0_BOOT2_R                                              
P  NNAMEm3204 SW_PVDDIO_P0_BOOT2                                                
P  NNAMEm3205 SW_PVDDIO_P0_BOOT1_R                                              
P  NNAMEm3206 SW_PVDDIO_P0_BOOT1                                                
P  NNAMEm3207 SW_PVDDCR_SOC_P1_SW3_RC                                           
P  NNAMEm3208 SW_PVDDCR_SOC_P1_SW3                                              
P  NNAMEm3209 SW_PVDDCR_SOC_P1_SW2_RC                                           
P  NNAMEm3210 SW_PVDDCR_SOC_P1_SW2                                              
P  NNAMEm3211 SW_PVDDCR_SOC_P1_SW1_RC                                           
P  NNAMEm3212 SW_PVDDCR_SOC_P1_SW1                                              
P  NNAMEm3213 SW_PVDDCR_SOC_P1_PH3                                              
P  NNAMEm3214 SW_PVDDCR_SOC_P1_PH2                                              
P  NNAMEm3215 SW_PVDDCR_SOC_P1_PH1                                              
P  NNAMEm3216 SW_PVDDCR_SOC_P1_BOOT3_RC                                         
P  NNAMEm3217 SW_PVDDCR_SOC_P1_BOOT3                                            
P  NNAMEm3218 SW_PVDDCR_SOC_P1_BOOT2_RC                                         
P  NNAMEm3219 SW_PVDDCR_SOC_P1_BOOT2                                            
P  NNAMEm3220 SW_PVDDCR_SOC_P1_BOOT1_RC                                         
P  NNAMEm3221 SW_PVDDCR_SOC_P1_BOOT1                                            
P  NNAMEm3222 SW_PVDDCR_SOC_P0_SW3_RC                                           
P  NNAMEm3223 SW_PVDDCR_SOC_P0_SW3                                              
P  NNAMEm3224 SW_PVDDCR_SOC_P0_SW2_RC                                           
P  NNAMEm3225 SW_PVDDCR_SOC_P0_SW2                                              
P  NNAMEm3226 SW_PVDDCR_SOC_P0_SW1_RC                                           
P  NNAMEm3227 SW_PVDDCR_SOC_P0_SW1                                              
P  NNAMEm3228 SW_PVDDCR_SOC_P0_PH3                                              
P  NNAMEm3229 SW_PVDDCR_SOC_P0_PH2                                              
P  NNAMEm3230 SW_PVDDCR_SOC_P0_PH1                                              
P  NNAMEm3231 SW_PVDDCR_SOC_P0_BOOT3_RC                                         
P  NNAMEm3232 SW_PVDDCR_SOC_P0_BOOT3                                            
P  NNAMEm3233 SW_PVDDCR_SOC_P0_BOOT2_RC                                         
P  NNAMEm3234 SW_PVDDCR_SOC_P0_BOOT2                                            
P  NNAMEm3235 SW_PVDDCR_SOC_P0_BOOT1_RC                                         
P  NNAMEm3236 SW_PVDDCR_SOC_P0_BOOT1                                            
P  NNAMEm3237 SW_PVDDCR_CPU1_P1_SW6_RC                                          
P  NNAMEm3238 SW_PVDDCR_CPU1_P1_SW6                                             
P  NNAMEm3239 SW_PVDDCR_CPU1_P1_SW5_RC                                          
P  NNAMEm3240 SW_PVDDCR_CPU1_P1_SW5                                             
P  NNAMEm3241 SW_PVDDCR_CPU1_P1_SW4_RC                                          
P  NNAMEm3242 SW_PVDDCR_CPU1_P1_SW4                                             
P  NNAMEm3243 SW_PVDDCR_CPU1_P1_SW3_RC                                          
P  NNAMEm3244 SW_PVDDCR_CPU1_P1_SW3                                             
P  NNAMEm3245 SW_PVDDCR_CPU1_P1_SW2_RC                                          
P  NNAMEm3246 SW_PVDDCR_CPU1_P1_SW2                                             
P  NNAMEm3247 SW_PVDDCR_CPU1_P1_SW1_RC                                          
P  NNAMEm3248 SW_PVDDCR_CPU1_P1_SW1                                             
P  NNAMEm3249 SW_PVDDCR_CPU1_P1_BOOTR6                                          
P  NNAMEm3250 SW_PVDDCR_CPU1_P1_BOOTR5                                          
P  NNAMEm3251 SW_PVDDCR_CPU1_P1_BOOTR4                                          
P  NNAMEm3252 SW_PVDDCR_CPU1_P1_BOOTR3                                          
P  NNAMEm3253 SW_PVDDCR_CPU1_P1_BOOTR2                                          
P  NNAMEm3254 SW_PVDDCR_CPU1_P1_BOOTR1                                          
P  NNAMEm3255 SW_PVDDCR_CPU1_P1_BOOT6_R                                         
P  NNAMEm3256 SW_PVDDCR_CPU1_P1_BOOT6                                           
P  NNAMEm3257 SW_PVDDCR_CPU1_P1_BOOT5_R                                         
P  NNAMEm3258 SW_PVDDCR_CPU1_P1_BOOT5                                           
P  NNAMEm3259 SW_PVDDCR_CPU1_P1_BOOT4_R                                         
P  NNAMEm3260 SW_PVDDCR_CPU1_P1_BOOT4                                           
P  NNAMEm3261 SW_PVDDCR_CPU1_P1_BOOT3_R                                         
P  NNAMEm3262 SW_PVDDCR_CPU1_P1_BOOT3                                           
P  NNAMEm3263 SW_PVDDCR_CPU1_P1_BOOT2_R                                         
P  NNAMEm3264 SW_PVDDCR_CPU1_P1_BOOT2                                           
P  NNAMEm3265 SW_PVDDCR_CPU1_P1_BOOT1_R                                         
P  NNAMEm3266 SW_PVDDCR_CPU1_P1_BOOT1                                           
P  NNAMEm3267 SW_PVDDCR_CPU1_P0_SW6_RC                                          
P  NNAMEm3268 SW_PVDDCR_CPU1_P0_SW6                                             
P  NNAMEm3269 SW_PVDDCR_CPU1_P0_SW5_RC                                          
P  NNAMEm3270 SW_PVDDCR_CPU1_P0_SW5                                             
P  NNAMEm3271 SW_PVDDCR_CPU1_P0_SW4_RC                                          
P  NNAMEm3272 SW_PVDDCR_CPU1_P0_SW4                                             
P  NNAMEm3273 SW_PVDDCR_CPU1_P0_SW3_RC                                          
P  NNAMEm3274 SW_PVDDCR_CPU1_P0_SW3                                             
P  NNAMEm3275 SW_PVDDCR_CPU1_P0_SW2_RC                                          
P  NNAMEm3276 SW_PVDDCR_CPU1_P0_SW2                                             
P  NNAMEm3277 SW_PVDDCR_CPU1_P0_SW1_RC                                          
P  NNAMEm3278 SW_PVDDCR_CPU1_P0_SW1                                             
P  NNAMEm3279 SW_PVDDCR_CPU1_P0_BOOTR6                                          
P  NNAMEm3280 SW_PVDDCR_CPU1_P0_BOOTR5                                          
P  NNAMEm3281 SW_PVDDCR_CPU1_P0_BOOTR4                                          
P  NNAMEm3282 SW_PVDDCR_CPU1_P0_BOOTR3                                          
P  NNAMEm3283 SW_PVDDCR_CPU1_P0_BOOTR2                                          
P  NNAMEm3284 SW_PVDDCR_CPU1_P0_BOOTR1                                          
P  NNAMEm3285 SW_PVDDCR_CPU1_P0_BOOT6_R                                         
P  NNAMEm3286 SW_PVDDCR_CPU1_P0_BOOT6                                           
P  NNAMEm3287 SW_PVDDCR_CPU1_P0_BOOT5_R                                         
P  NNAMEm3288 SW_PVDDCR_CPU1_P0_BOOT5                                           
P  NNAMEm3289 SW_PVDDCR_CPU1_P0_BOOT4_R                                         
P  NNAMEm3290 SW_PVDDCR_CPU1_P0_BOOT4                                           
P  NNAMEm3291 SW_PVDDCR_CPU1_P0_BOOT3_R                                         
P  NNAMEm3292 SW_PVDDCR_CPU1_P0_BOOT3                                           
P  NNAMEm3293 SW_PVDDCR_CPU1_P0_BOOT2_R                                         
P  NNAMEm3294 SW_PVDDCR_CPU1_P0_BOOT2                                           
P  NNAMEm3295 SW_PVDDCR_CPU1_P0_BOOT1_R                                         
P  NNAMEm3296 SW_PVDDCR_CPU1_P0_BOOT1                                           
P  NNAMEm3297 SW_PVDDCR_CPU0_P1_SW6_RC                                          
P  NNAMEm3298 SW_PVDDCR_CPU0_P1_SW6                                             
P  NNAMEm3299 SW_PVDDCR_CPU0_P1_SW5_RC                                          
P  NNAMEm3300 SW_PVDDCR_CPU0_P1_SW5                                             
P  NNAMEm3301 SW_PVDDCR_CPU0_P1_SW4_RC                                          
P  NNAMEm3302 SW_PVDDCR_CPU0_P1_SW4                                             
P  NNAMEm3303 SW_PVDDCR_CPU0_P1_SW3_RC                                          
P  NNAMEm3304 SW_PVDDCR_CPU0_P1_SW3                                             
P  NNAMEm3305 SW_PVDDCR_CPU0_P1_SW2_RC                                          
P  NNAMEm3306 SW_PVDDCR_CPU0_P1_SW2                                             
P  NNAMEm3307 SW_PVDDCR_CPU0_P1_SW1_RC                                          
P  NNAMEm3308 SW_PVDDCR_CPU0_P1_SW1                                             
P  NNAMEm3309 SW_PVDDCR_CPU0_P1_PH6                                             
P  NNAMEm3310 SW_PVDDCR_CPU0_P1_PH5                                             
P  NNAMEm3311 SW_PVDDCR_CPU0_P1_PH4                                             
P  NNAMEm3312 SW_PVDDCR_CPU0_P1_PH3                                             
P  NNAMEm3313 SW_PVDDCR_CPU0_P1_PH2                                             
P  NNAMEm3314 SW_PVDDCR_CPU0_P1_PH1                                             
P  NNAMEm3315 SW_PVDDCR_CPU0_P1_BOOT6_RC                                        
P  NNAMEm3316 SW_PVDDCR_CPU0_P1_BOOT6                                           
P  NNAMEm3317 SW_PVDDCR_CPU0_P1_BOOT5_RC                                        
P  NNAMEm3318 SW_PVDDCR_CPU0_P1_BOOT5                                           
P  NNAMEm3319 SW_PVDDCR_CPU0_P1_BOOT4_RC                                        
P  NNAMEm3320 SW_PVDDCR_CPU0_P1_BOOT4                                           
P  NNAMEm3321 SW_PVDDCR_CPU0_P1_BOOT3_RC                                        
P  NNAMEm3322 SW_PVDDCR_CPU0_P1_BOOT3                                           
P  NNAMEm3323 SW_PVDDCR_CPU0_P1_BOOT2_RC                                        
P  NNAMEm3324 SW_PVDDCR_CPU0_P1_BOOT2                                           
P  NNAMEm3325 SW_PVDDCR_CPU0_P1_BOOT1_RC                                        
P  NNAMEm3326 SW_PVDDCR_CPU0_P1_BOOT1                                           
P  NNAMEm3327 SW_PVDDCR_CPU0_P0_SW6_RC                                          
P  NNAMEm3328 SW_PVDDCR_CPU0_P0_SW6                                             
P  NNAMEm3329 SW_PVDDCR_CPU0_P0_SW5_RC                                          
P  NNAMEm3330 SW_PVDDCR_CPU0_P0_SW5                                             
P  NNAMEm3331 SW_PVDDCR_CPU0_P0_SW4_RC                                          
P  NNAMEm3332 SW_PVDDCR_CPU0_P0_SW4                                             
P  NNAMEm3333 SW_PVDDCR_CPU0_P0_SW3_RC                                          
P  NNAMEm3334 SW_PVDDCR_CPU0_P0_SW3                                             
P  NNAMEm3335 SW_PVDDCR_CPU0_P0_SW2_RC                                          
P  NNAMEm3336 SW_PVDDCR_CPU0_P0_SW2                                             
P  NNAMEm3337 SW_PVDDCR_CPU0_P0_SW1_RC                                          
P  NNAMEm3338 SW_PVDDCR_CPU0_P0_SW1                                             
P  NNAMEm3339 SW_PVDDCR_CPU0_P0_PH6                                             
P  NNAMEm3340 SW_PVDDCR_CPU0_P0_PH5                                             
P  NNAMEm3341 SW_PVDDCR_CPU0_P0_PH4                                             
P  NNAMEm3342 SW_PVDDCR_CPU0_P0_PH3                                             
P  NNAMEm3343 SW_PVDDCR_CPU0_P0_PH2                                             
P  NNAMEm3344 SW_PVDDCR_CPU0_P0_PH1                                             
P  NNAMEm3345 SW_PVDDCR_CPU0_P0_BOOT6_RC                                        
P  NNAMEm3346 SW_PVDDCR_CPU0_P0_BOOT6                                           
P  NNAMEm3347 SW_PVDDCR_CPU0_P0_BOOT5_RC                                        
P  NNAMEm3348 SW_PVDDCR_CPU0_P0_BOOT5                                           
P  NNAMEm3349 SW_PVDDCR_CPU0_P0_BOOT4_RC                                        
P  NNAMEm3350 SW_PVDDCR_CPU0_P0_BOOT4                                           
P  NNAMEm3351 SW_PVDDCR_CPU0_P0_BOOT3_RC                                        
P  NNAMEm3352 SW_PVDDCR_CPU0_P0_BOOT3                                           
P  NNAMEm3353 SW_PVDDCR_CPU0_P0_BOOT2_RC                                        
P  NNAMEm3354 SW_PVDDCR_CPU0_P0_BOOT2                                           
P  NNAMEm3355 SW_PVDDCR_CPU0_P0_BOOT1_RC                                        
P  NNAMEm3356 SW_PVDDCR_CPU0_P0_BOOT1                                           
P  NNAMEm3357 SW_PVDD18_S5_P1_SW                                                
P  NNAMEm3358 SW_PVDD18_S5_P1_BST                                               
P  NNAMEm3359 SW_PVDD18_S5_P0_SW                                                
P  NNAMEm3360 SW_PVDD18_S5_P0_BST                                               
P  NNAMEm3361 SW_PVDD11_S3_P1_SW2_RC                                            
P  NNAMEm3362 SW_PVDD11_S3_P1_SW2                                               
P  NNAMEm3363 SW_PVDD11_S3_P1_SW1_RC                                            
P  NNAMEm3364 SW_PVDD11_S3_P1_SW1                                               
P  NNAMEm3365 SW_PVDD11_S3_P1_PH2                                               
P  NNAMEm3366 SW_PVDD11_S3_P1_PH1                                               
P  NNAMEm3367 SW_PVDD11_S3_P1_BOOT2_RC                                          
P  NNAMEm3368 SW_PVDD11_S3_P1_BOOT2                                             
P  NNAMEm3369 SW_PVDD11_S3_P1_BOOT1_RC                                          
P  NNAMEm3370 SW_PVDD11_S3_P1_BOOT1                                             
P  NNAMEm3371 SW_PVDD11_S3_P0_SW2_RC                                            
P  NNAMEm3372 SW_PVDD11_S3_P0_SW2                                               
P  NNAMEm3373 SW_PVDD11_S3_P0_SW1_RC                                            
P  NNAMEm3374 SW_PVDD11_S3_P0_SW1                                               
P  NNAMEm3375 SW_PVDD11_S3_P0_PH2                                               
P  NNAMEm3376 SW_PVDD11_S3_P0_PH1                                               
P  NNAMEm3377 SW_PVDD11_S3_P0_BOOT2_RC                                          
P  NNAMEm3378 SW_PVDD11_S3_P0_BOOT2                                             
P  NNAMEm3379 SW_PVDD11_S3_P0_BOOT1_RC                                          
P  NNAMEm3380 SW_PVDD11_S3_P0_BOOT1                                             
P  NNAMEm3381 SW_P3V3_AUX_FLT                                                   
P  NNAMEm3382 SW_P3V3_AUX_BOOT_R                                                
P  NNAMEm3383 SW_P3V3_AUX_BOOTR                                                 
P  NNAMEm3384 SW_P3V3_AUX_BOOT                                                  
P  NNAMEm3385 SW_P12V_AUX_PVDD_33_S5_FLT                                        
P  NNAMEm3386 SW_P12V_AUX_PVDDIO_P1_FLT                                         
P  NNAMEm3387 SW_P12V_AUX_PVDDIO_P0_FLT                                         
P  NNAMEm3388 SW_P12V_AUX_PVDDCR_SOC_P1_FLT                                     
P  NNAMEm3389 SW_P12V_AUX_PVDDCR_SOC_P0_FLT                                     
P  NNAMEm3390 SW_P12V_AUX_PVDDCR_CPU1_P1_FLT                                    
P  NNAMEm3391 SW_P12V_AUX_PVDDCR_CPU1_P0_FLT                                    
P  NNAMEm3392 SW_P12V_AUX_PVDDCR_CPU0_P1_FLT                                    
P  NNAMEm3393 SW_P12V_AUX_PVDDCR_CPU0_P0_FLT                                    
P  NNAMEm3394 SW_P12V_AUX_PVDD18_S5_P1_FLT                                      
P  NNAMEm3395 SW_P12V_AUX_PVDD18_S5_P0_FLT                                      
P  NNAMEm3396 SW_P12V_AUX_PVDD11_S3_P1_FLT                                      
P  NNAMEm3397 SW_P12V_AUX_PVDD11_S3_P0_FLT                                      
P  NNAMEm3398 SWB_HSC_PWRGD_N                                                   
P  NNAMEm3399 SWB_HSC_PWRGD_ISO                                                 
P  NNAMEm3400 SWB_HSC_EN_BUF_R                                                  
P  NNAMEm3401 SVID_PVDDCR_CPU1_P1_SVTO_R                                        
P  NNAMEm3402 SVID_PVDDCR_CPU1_P1_SVTO                                          
P  NNAMEm3403 SVID_PVDDCR_CPU1_P1_SVTI_R                                        
P  NNAMEm3404 SVID_PVDDCR_CPU1_P1_SVTI                                          
P  NNAMEm3405 SVID_PVDDCR_CPU1_P1_SVD_R                                         
P  NNAMEm3406 SVID_PVDDCR_CPU1_P1_SVD                                           
P  NNAMEm3407 SVID_PVDDCR_CPU1_P1_SVC_R                                         
P  NNAMEm3408 SVID_PVDDCR_CPU1_P1_SVC                                           
P  NNAMEm3409 SVID_PVDDCR_CPU1_P0_SVTO_R                                        
P  NNAMEm3410 SVID_PVDDCR_CPU1_P0_SVTO                                          
P  NNAMEm3411 SVID_PVDDCR_CPU1_P0_SVTI_R                                        
P  NNAMEm3412 SVID_PVDDCR_CPU1_P0_SVTI                                          
P  NNAMEm3413 SVID_PVDDCR_CPU1_P0_SVD_R                                         
P  NNAMEm3414 SVID_PVDDCR_CPU1_P0_SVD                                           
P  NNAMEm3415 SVID_PVDDCR_CPU1_P0_SVC_R                                         
P  NNAMEm3416 SVID_PVDDCR_CPU1_P0_SVC                                           
P  NNAMEm3417 SVID_PVDDCR_CPU0_P1_SVTO_R                                        
P  NNAMEm3418 SVID_PVDDCR_CPU0_P1_SVTO                                          
P  NNAMEm3419 SVID_PVDDCR_CPU0_P1_SVTI_R                                        
P  NNAMEm3420 SVID_PVDDCR_CPU0_P1_SVTI                                          
P  NNAMEm3421 SVID_PVDDCR_CPU0_P1_SVD_R                                         
P  NNAMEm3422 SVID_PVDDCR_CPU0_P1_SVD                                           
P  NNAMEm3423 SVID_PVDDCR_CPU0_P1_SVC_R                                         
P  NNAMEm3424 SVID_PVDDCR_CPU0_P1_SVC                                           
P  NNAMEm3425 SVID_PVDDCR_CPU0_P0_SVTO_R                                        
P  NNAMEm3426 SVID_PVDDCR_CPU0_P0_SVTO                                          
P  NNAMEm3427 SVID_PVDDCR_CPU0_P0_SVTI_R                                        
P  NNAMEm3428 SVID_PVDDCR_CPU0_P0_SVTI                                          
P  NNAMEm3429 SVID_PVDDCR_CPU0_P0_SVD_R                                         
P  NNAMEm3430 SVID_PVDDCR_CPU0_P0_SVD                                           
P  NNAMEm3431 SVID_PVDDCR_CPU0_P0_SVC_R                                         
P  NNAMEm3432 SVID_PVDDCR_CPU0_P0_SVC                                           
P  NNAMEm3433 SPI_CPU0_TPM_CS_N                                                 
P  NNAMEm3434 SPI_CPU0_R_TPM_CS_N                                               
P  NNAMEm3435 SPI_CPU0_R_CS1_N                                                  
P  NNAMEm3436 SPI_CPU0_R_CS0_N                                                  
P  NNAMEm3437 SPI_CPU0_LVC3_TPM_CS_N                                            
P  NNAMEm3438 SPI_CPU0_LVC3_SCM_D3                                              
P  NNAMEm3439 SPI_CPU0_LVC3_SCM_D2                                              
P  NNAMEm3440 SPI_CPU0_LVC3_SCM_D1                                              
P  NNAMEm3441 SPI_CPU0_LVC3_SCM_D0                                              
P  NNAMEm3442 SPI_CPU0_LVC3_SCM_CS1_N                                           
P  NNAMEm3443 SPI_CPU0_LVC3_SCM_CS0_N                                           
P  NNAMEm3444 SPI_CPU0_LVC3_SCM_CLK                                             
P  NNAMEm3445 SPI_CPU0_LVC3_R_TPM_CS_N                                          
P  NNAMEm3446 SPI_CPU0_LVC3_D3                                                  
P  NNAMEm3447 SPI_CPU0_LVC3_D2                                                  
P  NNAMEm3448 SPI_CPU0_LVC3_D1                                                  
P  NNAMEm3449 SPI_CPU0_LVC3_D0                                                  
P  NNAMEm3450 SPI_CPU0_LVC3_CS1_N                                               
P  NNAMEm3451 SPI_CPU0_LVC3_CS0_N                                               
P  NNAMEm3452 SPI_CPU0_LVC3_CLK                                                 
P  NNAMEm3453 SMB_VR_SENSOR_3V3AUX_SDA                                          
P  NNAMEm3454 SMB_VR_SENSOR_3V3AUX_SCL                                          
P  NNAMEm3455 SMB_VR_3V3STBY_SDA                                                
P  NNAMEm3456 SMB_VR_3V3STBY_SCL                                                
P  NNAMEm3457 SMB_VR_3V3AUX_SDA_R0                                              
P  NNAMEm3458 SMB_VR_3V3AUX_SDA                                                 
P  NNAMEm3459 SMB_VR_3V3AUX_SCL_R0                                              
P  NNAMEm3460 SMB_VR_3V3AUX_SCL                                                 
P  NNAMEm3461 SMB_SML1_PMBUS_HSC_SDA                                            
P  NNAMEm3462 SMB_SML1_PMBUS_HSC_SCL                                            
P  NNAMEm3463 SMB_SML1_PMBUS_HSC_R_SDA                                          
P  NNAMEm3464 SMB_SML1_PMBUS_HSC_L_SCL                                          
P  NNAMEm3465 SMB_PMBUS_3V3AUX_SDA_R0                                           
P  NNAMEm3466 SMB_PMBUS_3V3AUX_SCL_R0                                           
P  NNAMEm3467 SMB_SENSOR_M2_P1_3V3AUX_SDA                                       
P  NNAMEm3468 SMB_SENSOR_M2_P1_3V3AUX_SCL                                       
P  NNAMEm3469 SMB_SENSOR_E1S_3V3AUX_SDA                                         
P  NNAMEm3470 SMB_SENSOR_E1S_3V3AUX_SCL                                         
P  NNAMEm3471 SMB_SCM_2_R2_SDA                                                  
P  NNAMEm3472 SMB_SCM_2_R2_SCL                                                  
P  NNAMEm3473 SMB_SCM_2_R1_SDA                                                  
P  NNAMEm3474 SMB_SCM_2_R1_SCL                                                  
P  NNAMEm3475 SMB_2_PLD_3V3AUX_SDA_R2                                           
P  NNAMEm3476 SMB_2_PLD_3V3AUX_SCL_R2                                           
P  NNAMEm3477 SMB_CPU0_CPU1_SEC_SDA_R2                                          
P  NNAMEm3478 SMB_CPU0_CPU1_SEC_SCL_R2                                          
P  NNAMEm3479 SMB_CPU0_CPU1_SEC_SDA_R1                                          
P  NNAMEm3480 SMB_CPU0_CPU1_SEC_SCL_R1                                          
P  NNAMEm3481 SMB_CPU0_CPU1_APML_SDA_R2                                         
P  NNAMEm3482 SMB_CPU0_CPU1_APML_SCL_R2                                         
P  NNAMEm3483 SMB_CPU0_CPU1_APML_BUF1_SDA_R1                                    
P  NNAMEm3484 SMB_CPU0_CPU1_APML_BUF1_SCL_R1                                    
P  NNAMEm3485 SMB_1_PLD_3V3AUX_SDA_R2                                           
P  NNAMEm3486 SMB_1_PLD_3V3AUX_SCL_R2                                           
P  NNAMEm3487 SMB_HOST_CLK_3V3AUX_SDA_R0                                        
P  NNAMEm3488 SMB_HOST_CLK_3V3AUX_SCL_R0                                        
P  NNAMEm3489 SMB_PCIE_M2_0_EN                                                  
P  NNAMEm3490 SMB_PCIE_E1S_ISO_EN_R2                                            
P  NNAMEm3491 SMB_PCIE_E1S_ISO_EN_R                                             
P  NNAMEm3492 SMB_PCIE_E1S_ISO_EN                                               
P  NNAMEm3493 SMB_PCIE3_3V3AUX_SDA_R                                            
P  NNAMEm3494 SMB_PCIE3_3V3AUX_SCL_R                                            
P  NNAMEm3495 SMB_PCIE2_3V3AUX_SDA_R0                                           
P  NNAMEm3496 SMB_PCIE2_3V3AUX_SCL_R0                                           
P  NNAMEm3497 SMB_PCIE0_3V3AUX_SDA                                              
P  NNAMEm3498 SMB_PCIE0_3V3AUX_SCL                                              
P  NNAMEm3499 SMB_OCP_V3_2_3V3AUX_SDA_R0                                        
P  NNAMEm3500 SMB_OCP_V3_2_3V3AUX_SDA                                           
P  NNAMEm3501 SMB_OCP_V3_2_3V3AUX_SCL_R0                                        
P  NNAMEm3502 SMB_OCP_V3_2_3V3AUX_SCL                                           
P  NNAMEm3503 SMB_OCP_V3_2_3V3AUX_BUF_SDA                                       
P  NNAMEm3504 SMB_OCP_V3_2_3V3AUX_BUF_SCL                                       
P  NNAMEm3505 SMB_OCP_V3_2_3V3AUX_BUF_R_SDA                                     
P  NNAMEm3506 SMB_OCP_V3_2_3V3AUX_BUF_R_SCL                                     
P  NNAMEm3507 SMB_OCP_SFF_3V3AUX_SDA_R0                                         
P  NNAMEm3508 SMB_OCP_SFF_3V3AUX_SDA                                            
P  NNAMEm3509 SMB_OCP_SFF_3V3AUX_SCL_R0                                         
P  NNAMEm3510 SMB_OCP_SFF_3V3AUX_SCL                                            
P  NNAMEm3511 SMB_OCP_SFF_3V3AUX_BUF_SDA                                        
P  NNAMEm3512 SMB_OCP_SFF_3V3AUX_BUF_SCL                                        
P  NNAMEm3513 SMB_OCP_SFF_3V3AUX_BUF_R_SDA                                      
P  NNAMEm3514 SMB_OCP_SFF_3V3AUX_BUF_R_SCL                                      
P  NNAMEm3515 SMB_M2_P1_1V8AUX_SDA_R                                            
P  NNAMEm3516 SMB_M2_P1_1V8AUX_SDA                                              
P  NNAMEm3517 SMB_M2_P1_1V8AUX_SCL_R                                            
P  NNAMEm3518 SMB_M2_P1_1V8AUX_SCL                                              
P  NNAMEm3519 SMB_HOST_CLK_GEN2_3V3AUX_SDA                                      
P  NNAMEm3520 SMB_HOST_CLK_GEN2_3V3AUX_SCL                                      
P  NNAMEm3521 SMB_CPU0_CPU1_APML_SDA_R                                          
P  NNAMEm3522 SMB_CPU0_CPU1_APML_SCL_R                                          
P  NNAMEm3523 SMB_FAN_3V3AUX_SDA                                                
P  NNAMEm3524 SMB_FAN_3V3AUX_SCL                                                
P  NNAMEm3525 SMB_E1S_3V3AUX_ISO_SDA_R                                          
P  NNAMEm3526 SMB_E1S_3V3AUX_ISO_SDA                                            
P  NNAMEm3527 SMB_E1S_3V3AUX_ISO_SCL_R                                          
P  NNAMEm3528 SMB_E1S_3V3AUX_ISO_SCL                                            
P  NNAMEm3529 SMB_DIO_PVDDCR_CPU1_P1_R                                          
P  NNAMEm3530 SMB_DIO_PVDDCR_CPU1_P0_R                                          
P  NNAMEm3531 SMB_CPU_5_R_SDA                                                   
P  NNAMEm3532 SMB_CPU_5_R_SCL                                                   
P  NNAMEm3533 SMB_CPU_5_R1_SDA                                                  
P  NNAMEm3534 SMB_CPU_5_R1_SCL                                                  
P  NNAMEm3535 SMB_CPU1_SEC_SDA                                                  
P  NNAMEm3536 SMB_CPU1_SEC_SCL                                                  
P  NNAMEm3537 SMB_CPU1_SEC_R_SDA                                                
P  NNAMEm3538 SMB_CPU1_SEC_R_SCL                                                
P  NNAMEm3539 SMB_CPU0_SEC_SDA                                                  
P  NNAMEm3540 SMB_CPU0_SEC_SCL                                                  
P  NNAMEm3541 SMB_APML_CPU1_R_SDA                                               
P  NNAMEm3542 SMB_APML_CPU1_R_SCL                                               
P  NNAMEm3543 SMB_CPU0_4_XLTR_SDA                                               
P  NNAMEm3544 SMB_CPU0_4_XLTR_SCL                                               
P  NNAMEm3545 SMB_CPU0_4_XLTR_R_SDA                                             
P  NNAMEm3546 SMB_CPU0_4_XLTR_R_SCL                                             
P  NNAMEm3547 SMB_CPU0_4_R_SDA                                                  
P  NNAMEm3548 SMB_CPU0_4_R_SCL                                                  
P  NNAMEm3549 SMB_CPU0_3_R_SDA                                                  
P  NNAMEm3550 SMB_CPU0_3_R_SCL                                                  
P  NNAMEm3551 SMB_CPU0_2_R_SDA                                                  
P  NNAMEm3552 SMB_CPU0_2_R_SCL                                                  
P  NNAMEm3553 SMB_CLK_PVDDCR_CPU1_P1_R                                          
P  NNAMEm3554 SMB_CLK_PVDDCR_CPU1_P0_R                                          
P  NNAMEm3555 SMB_BMC_SWB_BUF_SDA                                               
P  NNAMEm3556 SMB_BMC_SWB_BUF_SCL                                               
P  NNAMEm3557 SMB_APML_CPU1_SDA                                                 
P  NNAMEm3558 SMB_APML_CPU1_SCL                                                 
P  NNAMEm3559 SMB_CPU0_SEC_R_SCL                                                
P  NNAMEm3560 SMB_APML_CPU0_SDA                                                 
P  NNAMEm3561 SMB_APML_CPU0_SCL                                                 
P  NNAMEm3562 SMB_APML_CPU0_R_SDA                                               
P  NNAMEm3563 SMB_APML_CPU0_R_SCL                                               
P  NNAMEm3564 SMB_2_PLD_3V3AUX_SDA_R1                                           
P  NNAMEm3565 SMB_2_PLD_3V3AUX_SCL_R1                                           
P  NNAMEm3566 SMB_2_BMC_GPU_SDA                                                 
P  NNAMEm3567 SMB_2_BMC_GPU_SCL                                                 
P  NNAMEm3568 SMB_2_BMC_GPU_BUF_SDA                                             
P  NNAMEm3569 SMB_2_BMC_GPU_BUF_SCL                                             
P  NNAMEm3570 SMB_1_PLD_3V3AUX_SDA_R3                                           
P  NNAMEm3571 SMB_1_PLD_3V3AUX_SDA_R1                                           
P  NNAMEm3572 SMB_1_PLD_3V3AUX_SDA                                              
P  NNAMEm3573 SMB_1_PLD_3V3AUX_SCL_R3                                           
P  NNAMEm3574 SMB_1_PLD_3V3AUX_SCL_R1                                           
P  NNAMEm3575 SMB_1_PLD_3V3AUX_SCL                                              
P  NNAMEm3576 SMB_1_BMC_GPU_SDA                                                 
P  NNAMEm3577 SMB_1_BMC_GPU_SCL                                                 
P  NNAMEm3578 SMB_1_BMC_GPU_BUF_SDA                                             
P  NNAMEm3579 SMB_1_BMC_GPU_BUF_SCL                                             
P  NNAMEm3580 SGPIO_SCM_RESET_N                                                 
P  NNAMEm3581 SGPIO_SCM_LD_<1>                                                  
P  NNAMEm3582 SGPIO_SCM_LD_<0>                                                  
P  NNAMEm3583 SGPIO_SCM_INTR_R_N                                                
P  NNAMEm3584 SGPIO_SCM_INTR_N                                                  
P  NNAMEm3585 SGPIO_SCM_DO_<1>                                                  
P  NNAMEm3586 SGPIO_SCM_DO_<0>                                                  
P  NNAMEm3587 SGPIO_SCM_DI_R<1>                                                 
P  NNAMEm3588 SGPIO_SCM_DI_R<0>                                                 
P  NNAMEm3589 SGPIO_SCM_DI_<1>                                                  
P  NNAMEm3590 SGPIO_SCM_DI_<0>                                                  
P  NNAMEm3591 SGPIO_OCP_V3_2_LD_N                                               
P  NNAMEm3592 SGPIO_OCP_V3_2_DATAOUT                                            
P  NNAMEm3593 SGPIO_OCP_V3_2_DATAIN                                             
P  NNAMEm3594 SGPIO_OCP_V3_2_CLK                                                
P  NNAMEm3595 SGPIO_OCP_SFF_LD_N                                                
P  NNAMEm3596 SGPIO_OCP_SFF_DATAOUT                                             
P  NNAMEm3597 SGPIO_OCP_SFF_DATAIN                                              
P  NNAMEm3598 SGPIO_OCP_SFF_CLK                                                 
P  NNAMEm3599 SCM_USB_OC_BU_R_N                                                 
P  NNAMEm3600 SCM_USB_OC_BUF_N                                                  
P  NNAMEm3601 SCM_SYS_PWROK_R                                                   
P  NNAMEm3602 SCM_SYS_PWRBTN_N                                                  
P  NNAMEm3603 SCM_ROT_CPU_RST_R_N                                               
P  NNAMEm3604 SCM_JTAG_MUX_S1                                                   
P  NNAMEm3605 SCM_JTAG_MUX_S0                                                   
P  NNAMEm3606 SCM_JTAG_MUX_R_S1                                                 
P  NNAMEm3607 SCM_JTAG_MUX_R_S0                                                 
P  NNAMEm3608 SCM_IRQ_1V8_R_N                                                   
P  NNAMEm3609 RST_SWB_BIC_R_N                                                   
P  NNAMEm3610 RST_SWB_BIC_BUF_R_N                                               
P  NNAMEm3611 RST_SWB_BIC_BUF_N                                                 
P  NNAMEm3612 RST_SMB_SWITCH_N                                                  
P  NNAMEm3613 RST_SMB_OCP_V3_2_N                                                
P  NNAMEm3614 RST_SMB_OCP_SFF_N                                                 
P  NNAMEm3615 RST_SMB_E1S_0_N                                                   
P  NNAMEm3616 RST_SMB_BUF_E1S_0_N                                               
P  NNAMEm3617 RST_PERST_OCP_SFF_N                                               
P  NNAMEm3618 RST_PERST_M2_0_R_N                                                
P  NNAMEm3619 RST_PERST_E1S_0_R_N                                               
P  NNAMEm3620 RST_PERST_1_SWB_BUF_R_N                                           
P  NNAMEm3621 RST_PERST_2_SWB_BUF_N                                             
P  NNAMEm3622 RST_PERST_2_SWB_BUF_R_N                                           
P  NNAMEm3623 RST_PERST_1_SWB_BUF_N                                             
P  NNAMEm3624 RST_PERST_0_SWB_BUF_R_N                                           
P  NNAMEm3625 RST_PERST_0_SWB_BUF_N                                             
P  NNAMEm3626 RST_PERST3_OCP_V3_2_N                                             
P  NNAMEm3627 RST_PERST3_OCP_SFF_N                                              
P  NNAMEm3628 RST_PERST2_OCP_V3_2_N                                             
P  NNAMEm3629 RST_PERST2_OCP_SFF_N                                              
P  NNAMEm3630 RST_PERST1_OCP_V3_2_N                                             
P  NNAMEm3631 RST_PERST1_OCP_SFF_N                                              
P  NNAMEm3632 RST_PERST0_OCP_V3_2_N                                             
P  NNAMEm3633 RST_PERST0_OCP_SFF_N                                              
P  NNAMEm3634 RST_PCIE_E1S_PERST_N                                              
P  NNAMEm3635 RST_PERST_BUF_M2_0_N                                              
P  NNAMEm3636 RST_PERST_BUF_M2_0_R_N                                            
P  NNAMEm3637 RST_HP_OCP_V3_2_R_N                                               
P  NNAMEm3638 RST_HP_OCP_SFF_R_N                                                
P  NNAMEm3639 RST_ESPI_CPU0_R_RSTOUT_N                                          
P  NNAMEm3640 RST_ESPI_CPU0_RSTOUT_R_N                                          
P  NNAMEm3641 RST_ESPI_CPU0_RSTOUT_N                                            
P  NNAMEm3642 RST_CPU1_RSMRST_N                                                 
P  NNAMEm3643 RST_CPU1_RESETL_N                                                 
P  NNAMEm3644 RST_CPU1_PERST1_R_N                                               
P  NNAMEm3645 RST_CPU1_PERST1_N                                                 
P  NNAMEm3646 RST_CPU1_PERST0_R_N                                               
P  NNAMEm3647 RST_CPU1_PERST0_N                                                 
P  NNAMEm3648 RST_CPU0_RSMRST_N                                                 
P  NNAMEm3649 RST_CPU0_RESETL_N                                                 
P  NNAMEm3650 RST_CPU0_PERST1_R_N                                               
P  NNAMEm3651 RST_CPU0_PERST1_N                                                 
P  NNAMEm3652 RST_CPU0_PERST0_R_N                                               
P  NNAMEm3653 RST_CPU0_PERST0_N                                                 
P  NNAMEm3654 RST_CPU0_KBRST_R_N                                                
P  NNAMEm3655 RST_CPU0_KBRST_N                                                  
P  NNAMEm3656 RST_BMC_FROM_SWB_N                                                
P  NNAMEm3657 RST_BMC_FROM_SWB_ISO_N                                            
P  NNAMEm3658 RST_BMC_FROM_SWB                                                  
P  NNAMEm3659 SCM_ROT_CPU_RST_N                                                 
P  NNAMEm3660 RMII_OCP_BMC_RXD_1                                                
P  NNAMEm3661 RMII_OCP_BMC_RXD_0                                                
P  NNAMEm3662 RMII_OCP_BMC_CRSDV                                                
P  NNAMEm3663 RMII_BMC_OCP_TX_EN                                                
P  NNAMEm3664 RMII_BMC_OCP_TXD_1                                                
P  NNAMEm3665 RMII_BMC_OCP_TXD_0                                                
P  NNAMEm3666 RMII_BMC_OCP_RX_ER                                                
P  NNAMEm3667 PWRGD_PVDDIO_P1_R                                                 
P  NNAMEm3668 PWRGD_PVDDIO_P1                                                   
P  NNAMEm3669 PWRGD_PVDDIO_P0_R                                                 
P  NNAMEm3670 PWRGD_PVDDIO_P0                                                   
P  NNAMEm3671 PWRGD_PVDDCR_SOC_P1_R                                             
P  NNAMEm3672 PWRGD_PVDDCR_SOC_P1                                               
P  NNAMEm3673 PWRGD_PVDDCR_SOC_P0_R                                             
P  NNAMEm3674 PWRGD_PVDDCR_SOC_P0                                               
P  NNAMEm3675 PWRGD_PVDDCR_CPU1_P1_R                                            
P  NNAMEm3676 PWRGD_PVDDCR_CPU1_P1                                              
P  NNAMEm3677 PWRGD_PVDDCR_CPU1_P0_R                                            
P  NNAMEm3678 PWRGD_PVDDCR_CPU1_P0                                              
P  NNAMEm3679 PWRGD_PVDDCR_CPU0_P1_R                                            
P  NNAMEm3680 PWRGD_PVDDCR_CPU0_P1                                              
P  NNAMEm3681 PWRGD_PVDDCR_CPU0_P0_R                                            
P  NNAMEm3682 PWRGD_PVDDCR_CPU0_P0                                              
P  NNAMEm3683 PWRGD_PVDD33_S5                                                   
P  NNAMEm3684 PWRGD_PVDD18_S5_R_P1                                              
P  NNAMEm3685 PWRGD_PVDD18_S5_P1                                                
P  NNAMEm3686 PWRGD_PVDD18_S5_P0                                                
P  NNAMEm3687 PWRGD_PVDD11_S3_P1_R                                              
P  NNAMEm3688 PWRGD_PVDD11_S3_P1                                                
P  NNAMEm3689 PWRGD_PVDD11_S3_P0_R                                              
P  NNAMEm3690 PWRGD_PVDD11_S3_P0                                                
P  NNAMEm3691 PWRGD_PS_PWROK_R                                                  
P  NNAMEm3692 PWRGD_P5V_AUX_R                                                   
P  NNAMEm3693 TP_PWRGD_P12V_FAN_DR_R                                            
P  NNAMEm3694 PWRGD_CPU1_PWROK                                                  
P  NNAMEm3695 PWRGD_CPU0_PWROK                                                  
P  NNAMEm3696 PWRGD_CHL_CPU1_DIMM                                               
P  NNAMEm3697 PWRGD_CHL_CPU0_DIMM                                               
P  NNAMEm3698 PWRGD_CHK_CPU1_DIMM                                               
P  NNAMEm3699 PWRGD_CHK_CPU0_DIMM                                               
P  NNAMEm3700 PWRGD_CHJ_CPU1_DIMM                                               
P  NNAMEm3701 PWRGD_CHJ_CPU0_DIMM                                               
P  NNAMEm3702 PWRGD_CHI_CPU1_DIMM                                               
P  NNAMEm3703 PWRGD_CHI_CPU0_DIMM                                               
P  NNAMEm3704 PWRGD_CHH_CPU1_DIMM                                               
P  NNAMEm3705 PWRGD_CHH_CPU0_DIMM                                               
P  NNAMEm3706 PWRGD_CHG_CPU1_DIMM0                                              
P  NNAMEm3707 PWRGD_CHG_CPU0_DIMM0                                              
P  NNAMEm3708 PWRGD_CHGL_CPU1                                                   
P  NNAMEm3709 PWRGD_CHGL_CPU0                                                   
P  NNAMEm3710 PWRGD_CHF_CPU1_DIMM                                               
P  NNAMEm3711 PWRGD_CHF_CPU0_DIMM                                               
P  NNAMEm3712 PWRGD_CHE_CPU1_DIMM                                               
P  NNAMEm3713 PWRGD_CHE_CPU0_DIMM                                               
P  NNAMEm3714 PWRGD_CHD_CPU1_DIMM                                               
P  NNAMEm3715 PWRGD_CHD_CPU0_DIMM                                               
P  NNAMEm3716 PWRGD_CHC_CPU1_DIMM                                               
P  NNAMEm3717 PWRGD_CHC_CPU0_DIMM                                               
P  NNAMEm3718 PWRGD_CHB_CPU1_DIMM                                               
P  NNAMEm3719 PWRGD_CHB_CPU0_DIMM                                               
P  NNAMEm3720 PWRGD_CHA_CPU1_DIMM0                                              
P  NNAMEm3721 PWRGD_CHA_CPU0_DIMM0                                              
P  NNAMEm3722 PWRGD_CHAF_CPU1                                                   
P  NNAMEm3723 PWRGD_CHAF_CPU0                                                   
P  NNAMEm3724 PVDDIO_P1_TEMP1                                                   
P  NNAMEm3725 PVDDIO_P1_LSET4                                                   
P  NNAMEm3726 PVDDIO_P1_LSET3                                                   
P  NNAMEm3727 PVDDIO_P1_LSET2                                                   
P  NNAMEm3728 PVDDIO_P1_LSET1                                                   
P  NNAMEm3729 PVDDIO_P1_IMON4                                                   
P  NNAMEm3730 PVDDIO_P1_IMON3                                                   
P  NNAMEm3731 PVDDIO_P1_IMON2                                                   
P  NNAMEm3732 PVDDIO_P1_IMON1                                                   
P  NNAMEm3733 PVDDIO_P0_TEMP1                                                   
P  NNAMEm3734 PVDDIO_P0_LSET4                                                   
P  NNAMEm3735 PVDDIO_P0_LSET3                                                   
P  NNAMEm3736 PVDDIO_P0_LSET2                                                   
P  NNAMEm3737 PVDDIO_P0_LSET1                                                   
P  NNAMEm3738 PVDDIO_P0_IMON4                                                   
P  NNAMEm3739 PVDDIO_P0_IMON3                                                   
P  NNAMEm3740 PVDDIO_P0_IMON2                                                   
P  NNAMEm3741 PVDDIO_P0_IMON1                                                   
P  NNAMEm3742 PVDDCR_SOC_P1_VOS3                                                
P  NNAMEm3743 PVDDCR_SOC_P1_VOS2                                                
P  NNAMEm3744 PVDDCR_SOC_P1_VOS1                                                
P  NNAMEm3745 PVDDCR_SOC_P1_VCC3                                                
P  NNAMEm3746 PVDDCR_SOC_P1_VCC2                                                
P  NNAMEm3747 PVDDCR_SOC_P1_VCC1                                                
P  NNAMEm3748 PVDDCR_SOC_P1_TEMP1                                               
P  NNAMEm3749 PVDDCR_SOC_P1_PWM3                                                
P  NNAMEm3750 PVDDCR_SOC_P1_PWM2                                                
P  NNAMEm3751 PVDDCR_SOC_P1_PWM1                                                
P  NNAMEm3752 PVDDCR_SOC_P1_LSET3                                               
P  NNAMEm3753 PVDDCR_SOC_P1_LSET2                                               
P  NNAMEm3754 PVDDCR_SOC_P1_LSET1                                               
P  NNAMEm3755 PVDDCR_SOC_P1_IMON3                                               
P  NNAMEm3756 PVDDCR_SOC_P1_IMON2                                               
P  NNAMEm3757 PVDDCR_SOC_P1_IMON1                                               
P  NNAMEm3758 PVDDCR_SOC_P1_EN_RC                                               
P  NNAMEm3759 PVDDCR_SOC_P1_EN_GD                                               
P  NNAMEm3760 PVDDCR_SOC_P1_EN//ADDR_CFG                                        
P  NNAMEm3761 PVDDCR_SOC_P1_EN                                                  
P  NNAMEm3762 PVDDCR_SOC_P0_VOS3                                                
P  NNAMEm3763 PVDDCR_SOC_P0_VOS2                                                
P  NNAMEm3764 PVDDCR_SOC_P0_VOS1                                                
P  NNAMEm3765 PVDDCR_SOC_P0_VCC3                                                
P  NNAMEm3766 PVDDCR_SOC_P0_VCC2                                                
P  NNAMEm3767 PVDDCR_SOC_P0_VCC1                                                
P  NNAMEm3768 PVDDCR_SOC_P0_TEMP1                                               
P  NNAMEm3769 PVDDCR_SOC_P0_PWM3                                                
P  NNAMEm3770 PVDDCR_SOC_P0_PWM2                                                
P  NNAMEm3771 PVDDCR_SOC_P0_PWM1                                                
P  NNAMEm3772 PVDDCR_SOC_P0_LSET3                                               
P  NNAMEm3773 PVDDCR_SOC_P0_LSET2                                               
P  NNAMEm3774 PVDDCR_SOC_P0_LSET1                                               
P  NNAMEm3775 PVDDCR_SOC_P0_IMON3                                               
P  NNAMEm3776 PVDDCR_SOC_P0_IMON2                                               
P  NNAMEm3777 PVDDCR_SOC_P0_IMON1                                               
P  NNAMEm3778 PVDDCR_SOC_P0_EN_RC                                               
P  NNAMEm3779 PVDDCR_SOC_P0_EN_GD                                               
P  NNAMEm3780 PVDDCR_SOC_P0_EN//ADDR_CFG                                        
P  NNAMEm3781 PVDDCR_SOC_P0_EN                                                  
P  NNAMEm3782 PVDDCR_CPU1_P1_VOS6                                               
P  NNAMEm3783 PVDDCR_CPU1_P1_VOS5                                               
P  NNAMEm3784 PVDDCR_CPU1_P1_VOS4                                               
P  NNAMEm3785 PVDDCR_CPU1_P1_VOS3                                               
P  NNAMEm3786 PVDDCR_CPU1_P1_VOS2                                               
P  NNAMEm3787 PVDDCR_CPU1_P1_VOS1                                               
P  NNAMEm3788 PVDDCR_CPU1_P1_VMON                                               
P  NNAMEm3789 PVDDCR_CPU1_P1_VINSEN                                             
P  NNAMEm3790 PVDDCR_CPU1_P1_VCCS                                               
P  NNAMEm3791 PVDDCR_CPU1_P1_VCC6                                               
P  NNAMEm3792 PVDDCR_CPU1_P1_VCC5                                               
P  NNAMEm3793 PVDDCR_CPU1_P1_VCC4                                               
P  NNAMEm3794 PVDDCR_CPU1_P1_VCC3                                               
P  NNAMEm3795 PVDDCR_CPU1_P1_VCC2                                               
P  NNAMEm3796 PVDDCR_CPU1_P1_VCC1                                               
P  NNAMEm3797 PVDDCR_CPU1_P1_VCC                                                
P  NNAMEm3798 PVDDCR_CPU1_P1_TEMP0                                              
P  NNAMEm3799 PVDDCR_CPU1_P1_SMB_ALERT_R                                        
P  NNAMEm3800 PVDDCR_CPU1_P1_SMB_ALERT                                          
P  NNAMEm3801 PVDDCR_CPU1_P1_RESET_N_R                                          
P  NNAMEm3802 PVDDCR_CPU1_P1_RESET_N                                            
P  NNAMEm3803 PVDDCR_CPU1_P1_PWM6                                               
P  NNAMEm3804 PVDDCR_CPU1_P1_PWM5                                               
P  NNAMEm3805 PVDDCR_CPU1_P1_PWM4                                               
P  NNAMEm3806 PVDDCR_CPU1_P1_PWM3                                               
P  NNAMEm3807 PVDDCR_CPU1_P1_PWM2                                               
P  NNAMEm3808 PVDDCR_CPU1_P1_PWM1                                               
P  NNAMEm3809 PVDDCR_CPU1_P1_PVCC                                               
P  NNAMEm3810 PVDDCR_CPU1_P1_OCP_N_R                                            
P  NNAMEm3811 PVDDCR_CPU1_P1_OCP_N                                              
P  NNAMEm3812 PVDDCR_CPU1_P1_LSET6                                              
P  NNAMEm3813 PVDDCR_CPU1_P1_LSET5                                              
P  NNAMEm3814 PVDDCR_CPU1_P1_LSET4                                              
P  NNAMEm3815 PVDDCR_CPU1_P1_LSET3                                              
P  NNAMEm3816 PVDDCR_CPU1_P1_LSET2                                              
P  NNAMEm3817 PVDDCR_CPU1_P1_LSET1                                              
P  NNAMEm3818 PVDDCR_CPU1_P1_IMON6                                              
P  NNAMEm3819 PVDDCR_CPU1_P1_IMON5                                              
P  NNAMEm3820 PVDDCR_CPU1_P1_IMON4                                              
P  NNAMEm3821 PVDDCR_CPU1_P1_IMON3                                              
P  NNAMEm3822 PVDDCR_CPU1_P1_IMON2                                              
P  NNAMEm3823 PVDDCR_CPU1_P1_IMON1                                              
P  NNAMEm3824 PVDDCR_CPU1_P1_EN_R                                               
P  NNAMEm3825 PVDDCR_CPU1_P1_EN1_ADDR_CFG                                       
P  NNAMEm3826 PVDDCR_CPU1_P0_VOS6                                               
P  NNAMEm3827 PVDDCR_CPU1_P0_VOS5                                               
P  NNAMEm3828 PVDDCR_CPU1_P0_VOS4                                               
P  NNAMEm3829 PVDDCR_CPU1_P0_VOS3                                               
P  NNAMEm3830 PVDDCR_CPU1_P0_VOS2                                               
P  NNAMEm3831 PVDDCR_CPU1_P0_VOS1                                               
P  NNAMEm3832 PVDDCR_CPU1_P0_VMON                                               
P  NNAMEm3833 PVDDCR_CPU1_P0_VINSEN                                             
P  NNAMEm3834 PVDDCR_CPU1_P0_VCCS                                               
P  NNAMEm3835 PVDDCR_CPU1_P0_VCC6                                               
P  NNAMEm3836 PVDDCR_CPU1_P0_VCC5                                               
P  NNAMEm3837 PVDDCR_CPU1_P0_VCC4                                               
P  NNAMEm3838 PVDDCR_CPU1_P0_VCC3                                               
P  NNAMEm3839 PVDDCR_CPU1_P0_VCC2                                               
P  NNAMEm3840 PVDDCR_CPU1_P0_VCC1                                               
P  NNAMEm3841 PVDDCR_CPU1_P0_VCC                                                
P  NNAMEm3842 PVDDCR_CPU1_P0_TEMP0                                              
P  NNAMEm3843 PVDDCR_CPU1_P0_SMB_ALERT_R                                        
P  NNAMEm3844 PVDDCR_CPU1_P0_SMB_ALERT                                          
P  NNAMEm3845 PVDDCR_CPU1_P0_RESET_N_R                                          
P  NNAMEm3846 PVDDCR_CPU1_P0_RESET_N                                            
P  NNAMEm3847 PVDDCR_CPU1_P0_PWM6                                               
P  NNAMEm3848 PVDDCR_CPU1_P0_PWM5                                               
P  NNAMEm3849 PVDDCR_CPU1_P0_PWM4                                               
P  NNAMEm3850 PVDDCR_CPU1_P0_PWM3                                               
P  NNAMEm3851 PVDDCR_CPU1_P0_PWM2                                               
P  NNAMEm3852 PVDDCR_CPU1_P0_PWM1                                               
P  NNAMEm3853 PVDDCR_CPU1_P0_PVCC                                               
P  NNAMEm3854 PVDDCR_CPU1_P0_OCP_N_R                                            
P  NNAMEm3855 PVDDCR_CPU1_P0_OCP_N                                              
P  NNAMEm3856 PVDDCR_CPU1_P0_LSET6                                              
P  NNAMEm3857 PVDDCR_CPU1_P0_LSET5                                              
P  NNAMEm3858 PVDDCR_CPU1_P0_LSET4                                              
P  NNAMEm3859 PVDDCR_CPU1_P0_LSET3                                              
P  NNAMEm3860 PVDDCR_CPU1_P0_LSET2                                              
P  NNAMEm3861 PVDDCR_CPU1_P0_LSET1                                              
P  NNAMEm3862 PVDDCR_CPU1_P0_IMON6                                              
P  NNAMEm3863 PVDDCR_CPU1_P0_IMON5                                              
P  NNAMEm3864 PVDDCR_CPU1_P0_IMON4                                              
P  NNAMEm3865 PVDDCR_CPU1_P0_IMON3                                              
P  NNAMEm3866 PVDDCR_CPU1_P0_IMON2                                              
P  NNAMEm3867 PVDDCR_CPU1_P0_IMON1                                              
P  NNAMEm3868 PVDDCR_CPU1_P0_EN_R                                               
P  NNAMEm3869 PVDDCR_CPU1_P0_EN1_ADDR_CFG                                       
P  NNAMEm3870 PVDDCR_CPU0_P1_VOS6                                               
P  NNAMEm3871 PVDDCR_CPU0_P1_VOS5                                               
P  NNAMEm3872 PVDDCR_CPU0_P1_VOS4                                               
P  NNAMEm3873 PVDDCR_CPU0_P1_VOS3                                               
P  NNAMEm3874 PVDDCR_CPU0_P1_VOS2                                               
P  NNAMEm3875 PVDDCR_CPU0_P1_VOS1                                               
P  NNAMEm3876 PVDDCR_CPU0_P1_VMON                                               
P  NNAMEm3877 PVDDCR_CPU0_P1_VINSEN                                             
P  NNAMEm3878 PVDDCR_CPU0_P1_VCCS                                               
P  NNAMEm3879 PVDDCR_CPU0_P1_VCC6                                               
P  NNAMEm3880 PVDDCR_CPU0_P1_VCC5                                               
P  NNAMEm3881 PVDDCR_CPU0_P1_VCC4                                               
P  NNAMEm3882 PVDDCR_CPU0_P1_VCC3                                               
P  NNAMEm3883 PVDDCR_CPU0_P1_VCC2                                               
P  NNAMEm3884 PVDDCR_CPU0_P1_VCC1                                               
P  NNAMEm3885 PVDDCR_CPU0_P1_VCC                                                
P  NNAMEm3886 PVDDCR_CPU0_P1_TEMP0                                              
P  NNAMEm3887 PVDDCR_CPU0_P1_RESET_N_R                                          
P  NNAMEm3888 PVDDCR_CPU0_P1_RESET_N                                            
P  NNAMEm3889 PVDDCR_CPU0_P1_PWM6                                               
P  NNAMEm3890 PVDDCR_CPU0_P1_PWM5                                               
P  NNAMEm3891 PVDDCR_CPU0_P1_PWM4                                               
P  NNAMEm3892 PVDDCR_CPU0_P1_PWM3                                               
P  NNAMEm3893 PVDDCR_CPU0_P1_PWM2                                               
P  NNAMEm3894 PVDDCR_CPU0_P1_PWM1                                               
P  NNAMEm3895 PVDDCR_CPU0_P1_PVCC                                               
P  NNAMEm3896 PVDDCR_CPU0_P1_PMSDA_R                                            
P  NNAMEm3897 PVDDCR_CPU0_P1_PMSCL_R                                            
P  NNAMEm3898 PVDDCR_CPU0_P1_PMALERT_R                                          
P  NNAMEm3899 PVDDCR_CPU0_P1_PMALERT                                            
P  NNAMEm3900 PVDDCR_CPU0_P1_OCP_N_R                                            
P  NNAMEm3901 PVDDCR_CPU0_P1_OCP_N                                              
P  NNAMEm3902 PVDDCR_CPU0_P1_LSET6                                              
P  NNAMEm3903 PVDDCR_CPU0_P1_LSET5                                              
P  NNAMEm3904 PVDDCR_CPU0_P1_LSET4                                              
P  NNAMEm3905 PVDDCR_CPU0_P1_LSET3                                              
P  NNAMEm3906 PVDDCR_CPU0_P1_LSET2                                              
P  NNAMEm3907 PVDDCR_CPU0_P1_LSET1                                              
P  NNAMEm3908 PVDDCR_CPU0_P1_IMON6                                              
P  NNAMEm3909 PVDDCR_CPU0_P1_IMON5                                              
P  NNAMEm3910 PVDDCR_CPU0_P1_IMON4                                              
P  NNAMEm3911 PVDDCR_CPU0_P1_IMON3                                              
P  NNAMEm3912 PVDDCR_CPU0_P1_IMON2                                              
P  NNAMEm3913 PVDDCR_CPU0_P1_IMON1                                              
P  NNAMEm3914 PVDDCR_CPU0_P1_EN_R                                               
P  NNAMEm3915 PVDDCR_CPU0_P1_EN                                                 
P  NNAMEm3916 PVDDCR_CPU0_P0_VOS6                                               
P  NNAMEm3917 PVDDCR_CPU0_P0_VOS5                                               
P  NNAMEm3918 PVDDCR_CPU0_P0_VOS4                                               
P  NNAMEm3919 PVDDCR_CPU0_P0_VOS3                                               
P  NNAMEm3920 PVDDCR_CPU0_P0_VOS2                                               
P  NNAMEm3921 PVDDCR_CPU0_P0_VOS1                                               
P  NNAMEm3922 PVDDCR_CPU0_P0_VMON                                               
P  NNAMEm3923 PVDDCR_CPU0_P0_VINSEN                                             
P  NNAMEm3924 PVDDCR_CPU0_P0_VCCS                                               
P  NNAMEm3925 PVDDCR_CPU0_P0_VCC6                                               
P  NNAMEm3926 PVDDCR_CPU0_P0_VCC5                                               
P  NNAMEm3927 PVDDCR_CPU0_P0_VCC4                                               
P  NNAMEm3928 PVDDCR_CPU0_P0_VCC3                                               
P  NNAMEm3929 PVDDCR_CPU0_P0_VCC2                                               
P  NNAMEm3930 PVDDCR_CPU0_P0_VCC1                                               
P  NNAMEm3931 PVDDCR_CPU0_P0_VCC                                                
P  NNAMEm3932 PVDDCR_CPU0_P0_TEMP0                                              
P  NNAMEm3933 PVDDCR_CPU0_P0_RESET_N_R                                          
P  NNAMEm3934 PVDDCR_CPU0_P0_RESET_N                                            
P  NNAMEm3935 PVDDCR_CPU0_P0_PWM6                                               
P  NNAMEm3936 PVDDCR_CPU0_P0_PWM5                                               
P  NNAMEm3937 PVDDCR_CPU0_P0_PWM4                                               
P  NNAMEm3938 PVDDCR_CPU0_P0_PWM3                                               
P  NNAMEm3939 PVDDCR_CPU0_P0_PWM2                                               
P  NNAMEm3940 PVDDCR_CPU0_P0_PWM1                                               
P  NNAMEm3941 PVDDCR_CPU0_P0_PVCC                                               
P  NNAMEm3942 PVDDCR_CPU0_P0_PMSDA_R                                            
P  NNAMEm3943 PVDDCR_CPU0_P0_PMSCL_R                                            
P  NNAMEm3944 PVDDCR_CPU0_P0_PMALERT_R                                          
P  NNAMEm3945 PVDDCR_CPU0_P0_PMALERT                                            
P  NNAMEm3946 PVDDCR_CPU0_P0_OCP_N_R                                            
P  NNAMEm3947 PVDDCR_CPU0_P0_OCP_N                                              
P  NNAMEm3948 PVDDCR_CPU0_P0_LSET6                                              
P  NNAMEm3949 PVDDCR_CPU0_P0_LSET5                                              
P  NNAMEm3950 PVDDCR_CPU0_P0_LSET4                                              
P  NNAMEm3951 PVDDCR_CPU0_P0_LSET3                                              
P  NNAMEm3952 PVDDCR_CPU0_P0_LSET2                                              
P  NNAMEm3953 PVDDCR_CPU0_P0_LSET1                                              
P  NNAMEm3954 PVDDCR_CPU0_P0_IMON6                                              
P  NNAMEm3955 PVDDCR_CPU0_P0_IMON5                                              
P  NNAMEm3956 PVDDCR_CPU0_P0_IMON4                                              
P  NNAMEm3957 PVDDCR_CPU0_P0_IMON3                                              
P  NNAMEm3958 PVDDCR_CPU0_P0_IMON2                                              
P  NNAMEm3959 PVDDCR_CPU0_P0_IMON1                                              
P  NNAMEm3960 PVDDCR_CPU0_P0_EN_R                                               
P  NNAMEm3961 PVDDCR_CPU0_P0_EN                                                 
P  NNAMEm3962 PVDD18_SS_P1_RGND                                                 
P  NNAMEm3963 PVDD18_S5_P1_VCC                                                  
P  NNAMEm3964 PVDD18_S5_P1_R_EN                                                 
P  NNAMEm3965 PVDD18_S5_P1_REF                                                  
P  NNAMEm3966 PVDD18_S5_P1_MODE                                                 
P  NNAMEm3967 PVDD18_S5_P1_FB_RC                                                
P  NNAMEm3968 PVDD18_S5_P1_FB                                                   
P  NNAMEm3969 PVDD18_S5_P1_EN                                                   
P  NNAMEm3970 PVDD18_S5_P1_CS                                                   
P  NNAMEm3971 PVDD18_S5_P0_VCC                                                  
P  NNAMEm3972 PVDD18_S5_P0_RGND                                                 
P  NNAMEm3973 PVDD18_S5_P0_REF                                                  
P  NNAMEm3974 PVDD18_S5_P0_MODE                                                 
P  NNAMEm3975 PVDD18_S5_P0_FB_RC                                                
P  NNAMEm3976 PVDD18_S5_P0_FB                                                   
P  NNAMEm3977 PVDD18_S5_P0_EN                                                   
P  NNAMEm3978 PVDD18_S5_P0_CS                                                   
P  NNAMEm3979 PVDD11_S3_P1_VOS2                                                 
P  NNAMEm3980 PVDD11_S3_P1_VOS1                                                 
P  NNAMEm3981 PVDD11_S3_P1_VMON                                                 
P  NNAMEm3982 PVDD11_S3_P1_VINSEN                                               
P  NNAMEm3983 PVDD11_S3_P1_VDDIO                                                
P  NNAMEm3984 PVDD11_S3_P1_VCCS                                                 
P  NNAMEm3985 PVDD11_S3_P1_VCC2                                                 
P  NNAMEm3986 PVDD11_S3_P1_VCC1                                                 
P  NNAMEm3987 PVDD11_S3_P1_VCC                                                  
P  NNAMEm3988 PVDD11_S3_P1_TEMP1                                                
P  NNAMEm3989 PVDD11_S3_P1_TEMP0                                                
P  NNAMEm3990 PVDD11_S3_P1_RESET_N_R                                            
P  NNAMEm3991 PVDD11_S3_P1_RESET_N                                              
P  NNAMEm3992 PVDD11_S3_P1_PWM2                                                 
P  NNAMEm3993 PVDD11_S3_P1_PWM1                                                 
P  NNAMEm3994 PVDD11_S3_P1_PVCC                                                 
P  NNAMEm3995 PVDD11_S3_P1_PMSDA_R                                              
P  NNAMEm3996 PVDD11_S3_P1_PMSCL_R                                              
P  NNAMEm3997 PVDD11_S3_P1_PMALERT_R                                            
P  NNAMEm3998 PVDD11_S3_P1_PMALERT                                              
P  NNAMEm3999 PVDD11_S3_P1_OCP_N_R                                              
P  NNAMEm4000 PVDD11_S3_P1_OCP_N                                                
P  NNAMEm4001 PVDD11_S3_P1_LSET2                                                
P  NNAMEm4002 PVDD11_S3_P1_LSET1                                                
P  NNAMEm4003 PVDD11_S3_P1_IMON2                                                
P  NNAMEm4004 PVDD11_S3_P1_IMON1                                                
P  NNAMEm4005 PVDD11_S3_P1_EN_R                                                 
P  NNAMEm4006 PVDD11_S3_P1_EN                                                   
P  NNAMEm4007 PVDD11_S3_P1_ADDR_CFG                                             
P  NNAMEm4008 PVDD11_S3_P0_VOS2                                                 
P  NNAMEm4009 PVDD11_S3_P0_VOS1                                                 
P  NNAMEm4010 PVDD11_S3_P0_VMON                                                 
P  NNAMEm4011 PVDD11_S3_P0_VINSEN                                               
P  NNAMEm4012 PVDD11_S3_P0_VDDIO                                                
P  NNAMEm4013 PVDD11_S3_P0_VCCS                                                 
P  NNAMEm4014 PVDD11_S3_P0_VCC2                                                 
P  NNAMEm4015 PVDD11_S3_P0_VCC1                                                 
P  NNAMEm4016 PVDD11_S3_P0_VCC                                                  
P  NNAMEm4017 PVDD11_S3_P0_TEMP1                                                
P  NNAMEm4018 PVDD11_S3_P0_TEMP0                                                
P  NNAMEm4019 PVDD11_S3_P0_RESET_N_R                                            
P  NNAMEm4020 PVDD11_S3_P0_RESET_N                                              
P  NNAMEm4021 PVDD11_S3_P0_PWM2                                                 
P  NNAMEm4022 PVDD11_S3_P0_PWM1                                                 
P  NNAMEm4023 PVDD11_S3_P0_PVCC                                                 
P  NNAMEm4024 PVDD11_S3_P0_PMSDA_R                                              
P  NNAMEm4025 PVDD11_S3_P0_PMSCL_R                                              
P  NNAMEm4026 PVDD11_S3_P0_PMALERT_R                                            
P  NNAMEm4027 PVDD11_S3_P0_PMALERT                                              
P  NNAMEm4028 PVDD11_S3_P0_OCP_N_R                                              
P  NNAMEm4029 PVDD11_S3_P0_OCP_N                                                
P  NNAMEm4030 PVDD11_S3_P0_LSET2                                                
P  NNAMEm4031 PVDD11_S3_P0_LSET1                                                
P  NNAMEm4032 PVDD11_S3_P0_IMON2                                                
P  NNAMEm4033 PVDD11_S3_P0_IMON1                                                
P  NNAMEm4034 PVDD11_S3_P0_EN_R                                                 
P  NNAMEm4035 PVDD11_S3_P0_EN                                                   
P  NNAMEm4036 PVDD11_S3_P0_ADDR_CFG                                             
P  NNAMEm4037 PU_P12V_ALL_PWROK_LED                                             
P  NNAMEm4038 PU_OCP_V3_2_WAKE_OE                                               
P  NNAMEm4039 PU_OCP_SFF_WAKE_OE                                                
P  NNAMEm4040 PU_E1S_0_DUALPORT_EN_N                                            
P  NNAMEm4041 PU_BUFFER_HDD_ACTIVITY                                            
P  NNAMEm4042 PU_BOOT_RDY_LED                                                   
P  NNAMEm4043 PU_BIOS_USB_RECOVERY                                              
P  NNAMEm4044 PD_ESPI_CPU1_CLK2                                                 
P  NNAMEm4045 PD_ESPI_CPU0_CLK2                                                 
P  NNAMEm4046 PD_CHL_CPU1_DIMM_SAA                                              
P  NNAMEm4047 PD_CHL_CPU0_DIMM_SAA                                              
P  NNAMEm4048 PD_CHK_CPU1_DIMM_SAA                                              
P  NNAMEm4049 PD_CHK_CPU0_DIMM_SAA                                              
P  NNAMEm4050 PD_CHJ_CPU1_DIMM_SAA                                              
P  NNAMEm4051 PD_CHJ_CPU0_DIMM_SAA                                              
P  NNAMEm4052 PD_CHI_CPU1_DIMM_SAA                                              
P  NNAMEm4053 PD_CHI_CPU0_DIMM_SAA                                              
P  NNAMEm4054 PD_CHH_CPU1_DIMM_SAA                                              
P  NNAMEm4055 PD_CHH_CPU0_DIMM_SAA                                              
P  NNAMEm4056 PD_CHG_CPU1_DIMM0_SAA                                             
P  NNAMEm4057 PD_CHG_CPU0_DIMM0_SAA                                             
P  NNAMEm4058 PD_CHF_CPU1_DIMM_SAA                                              
P  NNAMEm4059 PD_CHF_CPU0_DIMM_SAA                                              
P  NNAMEm4060 PD_CHE_CPU1_DIMM_SAA                                              
P  NNAMEm4061 PD_CHE_CPU0_DIMM_SAA                                              
P  NNAMEm4062 PD_CHD_CPU1_DIMM_SAA                                              
P  NNAMEm4063 PD_CHD_CPU0_DIMM_SAA                                              
P  NNAMEm4064 PD_CHC_CPU1_DIMM_SAA                                              
P  NNAMEm4065 PD_CHC_CPU0_DIMM_SAA                                              
P  NNAMEm4066 PD_CHB_CPU1_DIMM_SAA                                              
P  NNAMEm4067 PD_CHB_CPU0_DIMM_SAA                                              
P  NNAMEm4068 PD_CHA_CPU1_DIMM0_SAA                                             
P  NNAMEm4069 PD_CHA_CPU0_DIMM0_SAA                                             
P  NNAMEm4070 PD_BIOS_DEBUG_MODE                                                
P  NNAMEm4071 PCIE_M2_SSD0_PRSNT_N                                              
P  NNAMEm4072 P5V_STBY_PWR_LED                                                  
P  NNAMEm4073 P5E_CPU1_P3_TX_DP<9>                                              
P  NNAMEm4074 P5E_CPU1_P3_TX_DP<8>                                              
P  NNAMEm4075 P5E_CPU1_P3_TX_DP<7>                                              
P  NNAMEm4076 P5E_CPU1_P3_TX_DP<6>                                              
P  NNAMEm4077 P5E_CPU1_P3_TX_DP<5>                                              
P  NNAMEm4078 P5E_CPU1_P3_TX_DP<4>                                              
P  NNAMEm4079 P5E_CPU1_P3_TX_DP<3>                                              
P  NNAMEm4080 P5E_CPU1_P3_TX_DP<2>                                              
P  NNAMEm4081 P5E_CPU1_P3_TX_DP<1>                                              
P  NNAMEm4082 P5E_CPU1_P3_TX_DP<15>                                             
P  NNAMEm4083 P5E_CPU1_P3_TX_DP<14>                                             
P  NNAMEm4084 P5E_CPU1_P3_TX_DP<13>                                             
P  NNAMEm4085 P5E_CPU1_P3_TX_DP<12>                                             
P  NNAMEm4086 P5E_CPU1_P3_TX_DP<11>                                             
P  NNAMEm4087 P5E_CPU1_P3_TX_DP<10>                                             
P  NNAMEm4088 P5E_CPU1_P3_TX_DP<0>                                              
P  NNAMEm4089 P5E_CPU1_P3_TX_DN<9>                                              
P  NNAMEm4090 P5E_CPU1_P3_TX_DN<8>                                              
P  NNAMEm4091 P5E_CPU1_P3_TX_DN<7>                                              
P  NNAMEm4092 P5E_CPU1_P3_TX_DN<6>                                              
P  NNAMEm4093 P5E_CPU1_P3_TX_DN<5>                                              
P  NNAMEm4094 P5E_CPU1_P3_TX_DN<4>                                              
P  NNAMEm4095 P5E_CPU1_P3_TX_DN<3>                                              
P  NNAMEm4096 P5E_CPU1_P3_TX_DN<2>                                              
P  NNAMEm4097 P5E_CPU1_P3_TX_DN<1>                                              
P  NNAMEm4098 P5E_CPU1_P3_TX_DN<15>                                             
P  NNAMEm4099 P5E_CPU1_P3_TX_DN<14>                                             
P  NNAMEm4100 P5E_CPU1_P3_TX_DN<13>                                             
P  NNAMEm4101 P5E_CPU1_P3_TX_DN<12>                                             
P  NNAMEm4102 P5E_CPU1_P3_TX_DN<11>                                             
P  NNAMEm4103 P5E_CPU1_P3_TX_DN<10>                                             
P  NNAMEm4104 P5E_CPU1_P3_TX_DN<0>                                              
P  NNAMEm4105 P5E_CPU1_P3_RX_DP<9>                                              
P  NNAMEm4106 P5E_CPU1_P3_RX_DP<8>                                              
P  NNAMEm4107 P5E_CPU1_P3_RX_DP<7>                                              
P  NNAMEm4108 P5E_CPU1_P3_RX_DP<6>                                              
P  NNAMEm4109 P5E_CPU1_P3_RX_DP<5>                                              
P  NNAMEm4110 P5E_CPU1_P3_RX_DP<4>                                              
P  NNAMEm4111 P5E_CPU1_P3_RX_DP<3>                                              
P  NNAMEm4112 P5E_CPU1_P3_RX_DP<2>                                              
P  NNAMEm4113 P5E_CPU1_P3_RX_DP<1>                                              
P  NNAMEm4114 P5E_CPU1_P3_RX_DP<15>                                             
P  NNAMEm4115 P5E_CPU1_P3_RX_DP<14>                                             
P  NNAMEm4116 P5E_CPU1_P3_RX_DP<13>                                             
P  NNAMEm4117 P5E_CPU1_P3_RX_DP<12>                                             
P  NNAMEm4118 P5E_CPU1_P3_RX_DP<11>                                             
P  NNAMEm4119 P5E_CPU1_P3_RX_DP<10>                                             
P  NNAMEm4120 P5E_CPU1_P3_RX_DP<0>                                              
P  NNAMEm4121 P5E_CPU1_P3_RX_DN<9>                                              
P  NNAMEm4122 P5E_CPU1_P3_RX_DN<8>                                              
P  NNAMEm4123 P5E_CPU1_P3_RX_DN<7>                                              
P  NNAMEm4124 P5E_CPU1_P3_RX_DN<6>                                              
P  NNAMEm4125 P5E_CPU1_P3_RX_DN<5>                                              
P  NNAMEm4126 P5E_CPU1_P3_RX_DN<4>                                              
P  NNAMEm4127 P5E_CPU1_P3_RX_DN<3>                                              
P  NNAMEm4128 P5E_CPU1_P3_RX_DN<2>                                              
P  NNAMEm4129 P5E_CPU1_P3_RX_DN<1>                                              
P  NNAMEm4130 P5E_CPU1_P3_RX_DN<15>                                             
P  NNAMEm4131 P5E_CPU1_P3_RX_DN<14>                                             
P  NNAMEm4132 P5E_CPU1_P3_RX_DN<13>                                             
P  NNAMEm4133 P5E_CPU1_P3_RX_DN<12>                                             
P  NNAMEm4134 P5E_CPU1_P3_RX_DN<11>                                             
P  NNAMEm4135 P5E_CPU1_P3_RX_DN<10>                                             
P  NNAMEm4136 P5E_CPU1_P3_RX_DN<0>                                              
P  NNAMEm4137 P5E_CPU1_P2_TX_DP<9>                                              
P  NNAMEm4138 P5E_CPU1_P2_TX_DP<8>                                              
P  NNAMEm4139 P5E_CPU1_P2_TX_DP<7>                                              
P  NNAMEm4140 P5E_CPU1_P2_TX_DP<6>                                              
P  NNAMEm4141 P5E_CPU1_P2_TX_DP<5>                                              
P  NNAMEm4142 P5E_CPU1_P2_TX_DP<4>                                              
P  NNAMEm4143 P5E_CPU1_P2_TX_DP<3>                                              
P  NNAMEm4144 P5E_CPU1_P2_TX_DP<2>                                              
P  NNAMEm4145 P5E_CPU1_P2_TX_DP<1>                                              
P  NNAMEm4146 P5E_CPU1_P2_TX_DP<15>                                             
P  NNAMEm4147 P5E_CPU1_P2_TX_DP<14>                                             
P  NNAMEm4148 P5E_CPU1_P2_TX_DP<13>                                             
P  NNAMEm4149 P5E_CPU1_P2_TX_DP<12>                                             
P  NNAMEm4150 P5E_CPU1_P2_TX_DP<11>                                             
P  NNAMEm4151 P5E_CPU1_P2_TX_DP<10>                                             
P  NNAMEm4152 P5E_CPU1_P2_TX_DP<0>                                              
P  NNAMEm4153 P5E_CPU1_P2_TX_DN<9>                                              
P  NNAMEm4154 P5E_CPU1_P2_TX_DN<8>                                              
P  NNAMEm4155 P5E_CPU1_P2_TX_DN<7>                                              
P  NNAMEm4156 P5E_CPU1_P2_TX_DN<6>                                              
P  NNAMEm4157 P5E_CPU1_P2_TX_DN<5>                                              
P  NNAMEm4158 P5E_CPU1_P2_TX_DN<4>                                              
P  NNAMEm4159 P5E_CPU1_P2_TX_DN<3>                                              
P  NNAMEm4160 P5E_CPU1_P2_TX_DN<2>                                              
P  NNAMEm4161 P5E_CPU1_P2_TX_DN<1>                                              
P  NNAMEm4162 P5E_CPU1_P2_TX_DN<15>                                             
P  NNAMEm4163 P5E_CPU1_P2_TX_DN<14>                                             
P  NNAMEm4164 P5E_CPU1_P2_TX_DN<13>                                             
P  NNAMEm4165 P5E_CPU1_P2_TX_DN<12>                                             
P  NNAMEm4166 P5E_CPU1_P2_TX_DN<11>                                             
P  NNAMEm4167 P5E_CPU1_P2_TX_DN<10>                                             
P  NNAMEm4168 P5E_CPU1_P2_TX_DN<0>                                              
P  NNAMEm4169 P5E_CPU1_P2_RX_DP<9>                                              
P  NNAMEm4170 P5E_CPU1_P2_RX_DP<8>                                              
P  NNAMEm4171 P5E_CPU1_P2_RX_DP<7>                                              
P  NNAMEm4172 P5E_CPU1_P2_RX_DP<6>                                              
P  NNAMEm4173 P5E_CPU1_P2_RX_DP<5>                                              
P  NNAMEm4174 P5E_CPU1_P2_RX_DP<4>                                              
P  NNAMEm4175 P5E_CPU1_P2_RX_DP<3>                                              
P  NNAMEm4176 P5E_CPU1_P2_RX_DP<2>                                              
P  NNAMEm4177 P5E_CPU1_P2_RX_DP<1>                                              
P  NNAMEm4178 P5E_CPU1_P2_RX_DP<15>                                             
P  NNAMEm4179 P5E_CPU1_P2_RX_DP<14>                                             
P  NNAMEm4180 P5E_CPU1_P2_RX_DP<13>                                             
P  NNAMEm4181 P5E_CPU1_P2_RX_DP<12>                                             
P  NNAMEm4182 P5E_CPU1_P2_RX_DP<11>                                             
P  NNAMEm4183 P5E_CPU1_P2_RX_DP<10>                                             
P  NNAMEm4184 P5E_CPU1_P2_RX_DP<0>                                              
P  NNAMEm4185 P5E_CPU1_P2_RX_DN<9>                                              
P  NNAMEm4186 P5E_CPU1_P2_RX_DN<8>                                              
P  NNAMEm4187 P5E_CPU1_P2_RX_DN<7>                                              
P  NNAMEm4188 P5E_CPU1_P2_RX_DN<6>                                              
P  NNAMEm4189 P5E_CPU1_P2_RX_DN<5>                                              
P  NNAMEm4190 P5E_CPU1_P2_RX_DN<4>                                              
P  NNAMEm4191 P5E_CPU1_P2_RX_DN<3>                                              
P  NNAMEm4192 P5E_CPU1_P2_RX_DN<2>                                              
P  NNAMEm4193 P5E_CPU1_P2_RX_DN<1>                                              
P  NNAMEm4194 P5E_CPU1_P2_RX_DN<15>                                             
P  NNAMEm4195 P5E_CPU1_P2_RX_DN<14>                                             
P  NNAMEm4196 P5E_CPU1_P2_RX_DN<13>                                             
P  NNAMEm4197 P5E_CPU1_P2_RX_DN<12>                                             
P  NNAMEm4198 P5E_CPU1_P2_RX_DN<11>                                             
P  NNAMEm4199 P5E_CPU1_P2_RX_DN<10>                                             
P  NNAMEm4200 P5E_CPU1_P2_RX_DN<0>                                              
P  NNAMEm4201 P5E_CPU1_P1_TX_DP<9>                                              
P  NNAMEm4202 P5E_CPU1_P1_TX_DP<8>                                              
P  NNAMEm4203 P5E_CPU1_P1_TX_DP<7>                                              
P  NNAMEm4204 P5E_CPU1_P1_TX_DP<6>                                              
P  NNAMEm4205 P5E_CPU1_P1_TX_DP<5>                                              
P  NNAMEm4206 P5E_CPU1_P1_TX_DP<4>                                              
P  NNAMEm4207 P5E_CPU1_P1_TX_DP<3>                                              
P  NNAMEm4208 P5E_CPU1_P1_TX_DP<2>                                              
P  NNAMEm4209 P5E_CPU1_P1_TX_DP<1>                                              
P  NNAMEm4210 P5E_CPU1_P1_TX_DP<15>                                             
P  NNAMEm4211 P5E_CPU1_P1_TX_DP<14>                                             
P  NNAMEm4212 P5E_CPU1_P1_TX_DP<13>                                             
P  NNAMEm4213 P5E_CPU1_P1_TX_DP<12>                                             
P  NNAMEm4214 P5E_CPU1_P1_TX_DP<11>                                             
P  NNAMEm4215 P5E_CPU1_P1_TX_DP<10>                                             
P  NNAMEm4216 P5E_CPU1_P1_TX_DP<0>                                              
P  NNAMEm4217 P5E_CPU1_P1_TX_DN<9>                                              
P  NNAMEm4218 P5E_CPU1_P1_TX_DN<8>                                              
P  NNAMEm4219 P5E_CPU1_P1_TX_DN<7>                                              
P  NNAMEm4220 P5E_CPU1_P1_TX_DN<6>                                              
P  NNAMEm4221 P5E_CPU1_P1_TX_DN<5>                                              
P  NNAMEm4222 P5E_CPU1_P1_TX_DN<4>                                              
P  NNAMEm4223 P5E_CPU1_P1_TX_DN<3>                                              
P  NNAMEm4224 P5E_CPU1_P1_TX_DN<2>                                              
P  NNAMEm4225 P5E_CPU1_P1_TX_DN<1>                                              
P  NNAMEm4226 P5E_CPU1_P1_TX_DN<15>                                             
P  NNAMEm4227 P5E_CPU1_P1_TX_DN<14>                                             
P  NNAMEm4228 P5E_CPU1_P1_TX_DN<13>                                             
P  NNAMEm4229 P5E_CPU1_P1_TX_DN<12>                                             
P  NNAMEm4230 P5E_CPU1_P1_TX_DN<11>                                             
P  NNAMEm4231 P5E_CPU1_P1_TX_DN<10>                                             
P  NNAMEm4232 P5E_CPU1_P1_TX_DN<0>                                              
P  NNAMEm4233 P5E_CPU1_P1_RX_DP<9>                                              
P  NNAMEm4234 P5E_CPU1_P1_RX_DP<8>                                              
P  NNAMEm4235 P5E_CPU1_P1_RX_DP<7>                                              
P  NNAMEm4236 P5E_CPU1_P1_RX_DP<6>                                              
P  NNAMEm4237 P5E_CPU1_P1_RX_DP<5>                                              
P  NNAMEm4238 P5E_CPU1_P1_RX_DP<4>                                              
P  NNAMEm4239 P5E_CPU1_P1_RX_DP<3>                                              
P  NNAMEm4240 P5E_CPU1_P1_RX_DP<2>                                              
P  NNAMEm4241 P5E_CPU1_P1_RX_DP<1>                                              
P  NNAMEm4242 P5E_CPU1_P1_RX_DP<15>                                             
P  NNAMEm4243 P5E_CPU1_P1_RX_DP<14>                                             
P  NNAMEm4244 P5E_CPU1_P1_RX_DP<13>                                             
P  NNAMEm4245 P5E_CPU1_P1_RX_DP<12>                                             
P  NNAMEm4246 P5E_CPU1_P1_RX_DP<11>                                             
P  NNAMEm4247 P5E_CPU1_P1_RX_DP<10>                                             
P  NNAMEm4248 P5E_CPU1_P1_RX_DP<0>                                              
P  NNAMEm4249 P5E_CPU1_P1_RX_DN<9>                                              
P  NNAMEm4250 P5E_CPU1_P1_RX_DN<8>                                              
P  NNAMEm4251 P5E_CPU1_P1_RX_DN<7>                                              
P  NNAMEm4252 P5E_CPU1_P1_RX_DN<6>                                              
P  NNAMEm4253 P5E_CPU1_P1_RX_DN<5>                                              
P  NNAMEm4254 P5E_CPU1_P1_RX_DN<4>                                              
P  NNAMEm4255 P5E_CPU1_P1_RX_DN<3>                                              
P  NNAMEm4256 P5E_CPU1_P1_RX_DN<2>                                              
P  NNAMEm4257 P5E_CPU1_P1_RX_DN<1>                                              
P  NNAMEm4258 P5E_CPU1_P1_RX_DN<15>                                             
P  NNAMEm4259 P5E_CPU1_P1_RX_DN<14>                                             
P  NNAMEm4260 P5E_CPU1_P1_RX_DN<13>                                             
P  NNAMEm4261 P5E_CPU1_P1_RX_DN<12>                                             
P  NNAMEm4262 P5E_CPU1_P1_RX_DN<11>                                             
P  NNAMEm4263 P5E_CPU1_P1_RX_DN<10>                                             
P  NNAMEm4264 P5E_CPU1_P1_RX_DN<0>                                              
P  NNAMEm4265 P5E_CPU1_P0_TX_DP<9>                                              
P  NNAMEm4266 P5E_CPU1_P0_TX_DP<8>                                              
P  NNAMEm4267 P5E_CPU1_P0_TX_DP<7>                                              
P  NNAMEm4268 P5E_CPU1_P0_TX_DP<6>                                              
P  NNAMEm4269 P5E_CPU1_P0_TX_DP<5>                                              
P  NNAMEm4270 P5E_CPU1_P0_TX_DP<4>                                              
P  NNAMEm4271 P5E_CPU1_P0_TX_DP<3>                                              
P  NNAMEm4272 P5E_CPU1_P0_TX_DP<2>                                              
P  NNAMEm4273 P5E_CPU1_P0_TX_DP<1>                                              
P  NNAMEm4274 P5E_CPU1_P0_TX_DP<15>                                             
P  NNAMEm4275 P5E_CPU1_P0_TX_DP<14>                                             
P  NNAMEm4276 P5E_CPU1_P0_TX_DP<13>                                             
P  NNAMEm4277 P5E_CPU1_P0_TX_DP<12>                                             
P  NNAMEm4278 P5E_CPU1_P0_TX_DP<11>                                             
P  NNAMEm4279 P5E_CPU1_P0_TX_DP<10>                                             
P  NNAMEm4280 P5E_CPU1_P0_TX_DP<0>                                              
P  NNAMEm4281 P5E_CPU1_P0_TX_DN<9>                                              
P  NNAMEm4282 P5E_CPU1_P0_TX_DN<8>                                              
P  NNAMEm4283 P5E_CPU1_P0_TX_DN<7>                                              
P  NNAMEm4284 P5E_CPU1_P0_TX_DN<6>                                              
P  NNAMEm4285 P5E_CPU1_P0_TX_DN<5>                                              
P  NNAMEm4286 P5E_CPU1_P0_TX_DN<4>                                              
P  NNAMEm4287 P5E_CPU1_P0_TX_DN<3>                                              
P  NNAMEm4288 P5E_CPU1_P0_TX_DN<2>                                              
P  NNAMEm4289 P5E_CPU1_P0_TX_DN<1>                                              
P  NNAMEm4290 P5E_CPU1_P0_TX_DN<15>                                             
P  NNAMEm4291 P5E_CPU1_P0_TX_DN<14>                                             
P  NNAMEm4292 P5E_CPU1_P0_TX_DN<13>                                             
P  NNAMEm4293 P5E_CPU1_P0_TX_DN<12>                                             
P  NNAMEm4294 P5E_CPU1_P0_TX_DN<11>                                             
P  NNAMEm4295 P5E_CPU1_P0_TX_DN<10>                                             
P  NNAMEm4296 P5E_CPU1_P0_TX_DN<0>                                              
P  NNAMEm4297 P5E_CPU1_P0_RX_DP<9>                                              
P  NNAMEm4298 P5E_CPU1_P0_RX_DP<8>                                              
P  NNAMEm4299 P5E_CPU1_P0_RX_DP<7>                                              
P  NNAMEm4300 P5E_CPU1_P0_RX_DP<6>                                              
P  NNAMEm4301 P5E_CPU1_P0_RX_DP<5>                                              
P  NNAMEm4302 P5E_CPU1_P0_RX_DP<4>                                              
P  NNAMEm4303 P5E_CPU1_P0_RX_DP<3>                                              
P  NNAMEm4304 P5E_CPU1_P0_RX_DP<2>                                              
P  NNAMEm4305 P5E_CPU1_P0_RX_DP<1>                                              
P  NNAMEm4306 P5E_CPU1_P0_RX_DP<15>                                             
P  NNAMEm4307 P5E_CPU1_P0_RX_DP<14>                                             
P  NNAMEm4308 P5E_CPU1_P0_RX_DP<13>                                             
P  NNAMEm4309 P5E_CPU1_P0_RX_DP<12>                                             
P  NNAMEm4310 P5E_CPU1_P0_RX_DP<11>                                             
P  NNAMEm4311 P5E_CPU1_P0_RX_DP<10>                                             
P  NNAMEm4312 P5E_CPU1_P0_RX_DP<0>                                              
P  NNAMEm4313 P5E_CPU1_P0_RX_DN<9>                                              
P  NNAMEm4314 P5E_CPU1_P0_RX_DN<8>                                              
P  NNAMEm4315 P5E_CPU1_P0_RX_DN<7>                                              
P  NNAMEm4316 P5E_CPU1_P0_RX_DN<6>                                              
P  NNAMEm4317 P5E_CPU1_P0_RX_DN<5>                                              
P  NNAMEm4318 P5E_CPU1_P0_RX_DN<4>                                              
P  NNAMEm4319 P5E_CPU1_P0_RX_DN<3>                                              
P  NNAMEm4320 P5E_CPU1_P0_RX_DN<2>                                              
P  NNAMEm4321 P5E_CPU1_P0_RX_DN<1>                                              
P  NNAMEm4322 P5E_CPU1_P0_RX_DN<15>                                             
P  NNAMEm4323 P5E_CPU1_P0_RX_DN<14>                                             
P  NNAMEm4324 P5E_CPU1_P0_RX_DN<13>                                             
P  NNAMEm4325 P5E_CPU1_P0_RX_DN<12>                                             
P  NNAMEm4326 P5E_CPU1_P0_RX_DN<11>                                             
P  NNAMEm4327 P5E_CPU1_P0_RX_DN<10>                                             
P  NNAMEm4328 P5E_CPU1_P0_RX_DN<0>                                              
P  NNAMEm4329 P5E_CPU0_P3_TX_DP<7>                                              
P  NNAMEm4330 P5E_CPU0_P3_TX_DP<6>                                              
P  NNAMEm4331 P5E_CPU0_P3_TX_DP<5>                                              
P  NNAMEm4332 P5E_CPU0_P3_TX_DP<4>                                              
P  NNAMEm4333 P5E_CPU0_P3_TX_DN<7>                                              
P  NNAMEm4334 P5E_CPU0_P3_TX_DN<6>                                              
P  NNAMEm4335 P5E_CPU0_P3_TX_DN<5>                                              
P  NNAMEm4336 P5E_CPU0_P3_TX_DN<4>                                              
P  NNAMEm4337 P5E_CPU0_P3_RX_DP<7>                                              
P  NNAMEm4338 P5E_CPU0_P3_RX_DP<6>                                              
P  NNAMEm4339 P5E_CPU0_P3_RX_DP<5>                                              
P  NNAMEm4340 P5E_CPU0_P3_RX_DP<4>                                              
P  NNAMEm4341 P5E_CPU0_P3_RX_DN<7>                                              
P  NNAMEm4342 P5E_CPU0_P3_RX_DN<6>                                              
P  NNAMEm4343 P5E_CPU0_P3_RX_DN<5>                                              
P  NNAMEm4344 P5E_CPU0_P3_RX_DN<4>                                              
P  NNAMEm4345 P5E_CPU0_P2_TX_DP<9>                                              
P  NNAMEm4346 P5E_CPU0_P2_TX_DP<8>                                              
P  NNAMEm4347 P5E_CPU0_P2_TX_DP<7>                                              
P  NNAMEm4348 P5E_CPU0_P2_TX_DP<6>                                              
P  NNAMEm4349 P5E_CPU0_P2_TX_DP<5>                                              
P  NNAMEm4350 P5E_CPU0_P2_TX_DP<4>                                              
P  NNAMEm4351 P5E_CPU0_P2_TX_DP<3>                                              
P  NNAMEm4352 P5E_CPU0_P2_TX_DP<2>                                              
P  NNAMEm4353 P5E_CPU0_P2_TX_DP<1>                                              
P  NNAMEm4354 P5E_CPU0_P2_TX_DP<15>                                             
P  NNAMEm4355 P5E_CPU0_P2_TX_DP<14>                                             
P  NNAMEm4356 P5E_CPU0_P2_TX_DP<13>                                             
P  NNAMEm4357 P5E_CPU0_P2_TX_DP<12>                                             
P  NNAMEm4358 P5E_CPU0_P2_TX_DP<11>                                             
P  NNAMEm4359 P5E_CPU0_P2_TX_DP<10>                                             
P  NNAMEm4360 P5E_CPU0_P2_TX_DP<0>                                              
P  NNAMEm4361 P5E_CPU0_P2_TX_DN<9>                                              
P  NNAMEm4362 P5E_CPU0_P2_TX_DN<8>                                              
P  NNAMEm4363 P5E_CPU0_P2_TX_DN<7>                                              
P  NNAMEm4364 P5E_CPU0_P2_TX_DN<6>                                              
P  NNAMEm4365 P5E_CPU0_P2_TX_DN<5>                                              
P  NNAMEm4366 P5E_CPU0_P2_TX_DN<4>                                              
P  NNAMEm4367 P5E_CPU0_P2_TX_DN<3>                                              
P  NNAMEm4368 P5E_CPU0_P2_TX_DN<2>                                              
P  NNAMEm4369 P5E_CPU0_P2_TX_DN<1>                                              
P  NNAMEm4370 P5E_CPU0_P2_TX_DN<15>                                             
P  NNAMEm4371 P5E_CPU0_P2_TX_DN<14>                                             
P  NNAMEm4372 P5E_CPU0_P2_TX_DN<13>                                             
P  NNAMEm4373 P5E_CPU0_P2_TX_DN<12>                                             
P  NNAMEm4374 P5E_CPU0_P2_TX_DN<11>                                             
P  NNAMEm4375 P5E_CPU0_P2_TX_DN<10>                                             
P  NNAMEm4376 P5E_CPU0_P2_TX_DN<0>                                              
P  NNAMEm4377 P5E_CPU0_P2_RX_DP<9>                                              
P  NNAMEm4378 P5E_CPU0_P2_RX_DP<8>                                              
P  NNAMEm4379 P5E_CPU0_P2_RX_DP<7>                                              
P  NNAMEm4380 P5E_CPU0_P2_RX_DP<6>                                              
P  NNAMEm4381 P5E_CPU0_P2_RX_DP<5>                                              
P  NNAMEm4382 P5E_CPU0_P2_RX_DP<4>                                              
P  NNAMEm4383 P5E_CPU0_P2_RX_DP<3>                                              
P  NNAMEm4384 P5E_CPU0_P2_RX_DP<2>                                              
P  NNAMEm4385 P5E_CPU0_P2_RX_DP<1>                                              
P  NNAMEm4386 P5E_CPU0_P2_RX_DP<15>                                             
P  NNAMEm4387 P5E_CPU0_P2_RX_DP<14>                                             
P  NNAMEm4388 P5E_CPU0_P2_RX_DP<13>                                             
P  NNAMEm4389 P5E_CPU0_P2_RX_DP<12>                                             
P  NNAMEm4390 P5E_CPU0_P2_RX_DP<11>                                             
P  NNAMEm4391 P5E_CPU0_P2_RX_DP<10>                                             
P  NNAMEm4392 P5E_CPU0_P2_RX_DP<0>                                              
P  NNAMEm4393 P5E_CPU0_P2_RX_DN<9>                                              
P  NNAMEm4394 P5E_CPU0_P2_RX_DN<8>                                              
P  NNAMEm4395 P5E_CPU0_P2_RX_DN<7>                                              
P  NNAMEm4396 P5E_CPU0_P2_RX_DN<6>                                              
P  NNAMEm4397 P5E_CPU0_P2_RX_DN<5>                                              
P  NNAMEm4398 P5E_CPU0_P2_RX_DN<4>                                              
P  NNAMEm4399 P5E_CPU0_P2_RX_DN<3>                                              
P  NNAMEm4400 P5E_CPU0_P2_RX_DN<2>                                              
P  NNAMEm4401 P5E_CPU0_P2_RX_DN<1>                                              
P  NNAMEm4402 P5E_CPU0_P2_RX_DN<15>                                             
P  NNAMEm4403 P5E_CPU0_P2_RX_DN<14>                                             
P  NNAMEm4404 P5E_CPU0_P2_RX_DN<13>                                             
P  NNAMEm4405 P5E_CPU0_P2_RX_DN<12>                                             
P  NNAMEm4406 P5E_CPU0_P2_RX_DN<11>                                             
P  NNAMEm4407 P5E_CPU0_P2_RX_DN<10>                                             
P  NNAMEm4408 P5E_CPU0_P2_RX_DN<0>                                              
P  NNAMEm4409 P5E_CPU0_P1_TX_DP<9>                                              
P  NNAMEm4410 P5E_CPU0_P1_TX_DP<8>                                              
P  NNAMEm4411 P5E_CPU0_P1_TX_DP<7>                                              
P  NNAMEm4412 P5E_CPU0_P1_TX_DP<6>                                              
P  NNAMEm4413 P5E_CPU0_P1_TX_DP<5>                                              
P  NNAMEm4414 P5E_CPU0_P1_TX_DP<4>                                              
P  NNAMEm4415 P5E_CPU0_P1_TX_DP<3>                                              
P  NNAMEm4416 P5E_CPU0_P1_TX_DP<2>                                              
P  NNAMEm4417 P5E_CPU0_P1_TX_DP<1>                                              
P  NNAMEm4418 P5E_CPU0_P1_TX_DP<15>                                             
P  NNAMEm4419 P5E_CPU0_P1_TX_DP<14>                                             
P  NNAMEm4420 P5E_CPU0_P1_TX_DP<13>                                             
P  NNAMEm4421 P5E_CPU0_P1_TX_DP<12>                                             
P  NNAMEm4422 P5E_CPU0_P1_TX_DP<11>                                             
P  NNAMEm4423 P5E_CPU0_P1_TX_DP<10>                                             
P  NNAMEm4424 P5E_CPU0_P1_TX_DP<0>                                              
P  NNAMEm4425 P5E_CPU0_P1_TX_DN<9>                                              
P  NNAMEm4426 P5E_CPU0_P1_TX_DN<8>                                              
P  NNAMEm4427 P5E_CPU0_P1_TX_DN<7>                                              
P  NNAMEm4428 P5E_CPU0_P1_TX_DN<6>                                              
P  NNAMEm4429 P5E_CPU0_P1_TX_DN<5>                                              
P  NNAMEm4430 P5E_CPU0_P1_TX_DN<4>                                              
P  NNAMEm4431 P5E_CPU0_P1_TX_DN<3>                                              
P  NNAMEm4432 P5E_CPU0_P1_TX_DN<2>                                              
P  NNAMEm4433 P5E_CPU0_P1_TX_DN<1>                                              
P  NNAMEm4434 P5E_CPU0_P1_TX_DN<15>                                             
P  NNAMEm4435 P5E_CPU0_P1_TX_DN<14>                                             
P  NNAMEm4436 P5E_CPU0_P1_TX_DN<13>                                             
P  NNAMEm4437 P5E_CPU0_P1_TX_DN<12>                                             
P  NNAMEm4438 P5E_CPU0_P1_TX_DN<11>                                             
P  NNAMEm4439 P5E_CPU0_P1_TX_DN<10>                                             
P  NNAMEm4440 P5E_CPU0_P1_TX_DN<0>                                              
P  NNAMEm4441 P5E_CPU0_P1_RX_DP<9>                                              
P  NNAMEm4442 P5E_CPU0_P1_RX_DP<8>                                              
P  NNAMEm4443 P5E_CPU0_P1_RX_DP<7>                                              
P  NNAMEm4444 P5E_CPU0_P1_RX_DP<6>                                              
P  NNAMEm4445 P5E_CPU0_P1_RX_DP<5>                                              
P  NNAMEm4446 P5E_CPU0_P1_RX_DP<4>                                              
P  NNAMEm4447 P5E_CPU0_P1_RX_DP<3>                                              
P  NNAMEm4448 P5E_CPU0_P1_RX_DP<2>                                              
P  NNAMEm4449 P5E_CPU0_P1_RX_DP<1>                                              
P  NNAMEm4450 P5E_CPU0_P1_RX_DP<15>                                             
P  NNAMEm4451 P5E_CPU0_P1_RX_DP<14>                                             
P  NNAMEm4452 P5E_CPU0_P1_RX_DP<13>                                             
P  NNAMEm4453 P5E_CPU0_P1_RX_DP<12>                                             
P  NNAMEm4454 P5E_CPU0_P1_RX_DP<11>                                             
P  NNAMEm4455 P5E_CPU0_P1_RX_DP<10>                                             
P  NNAMEm4456 P5E_CPU0_P1_RX_DP<0>                                              
P  NNAMEm4457 P5E_CPU0_P1_RX_DN<9>                                              
P  NNAMEm4458 P5E_CPU0_P1_RX_DN<8>                                              
P  NNAMEm4459 P5E_CPU0_P1_RX_DN<7>                                              
P  NNAMEm4460 P5E_CPU0_P1_RX_DN<6>                                              
P  NNAMEm4461 P5E_CPU0_P1_RX_DN<5>                                              
P  NNAMEm4462 P5E_CPU0_P1_RX_DN<4>                                              
P  NNAMEm4463 P5E_CPU0_P1_RX_DN<3>                                              
P  NNAMEm4464 P5E_CPU0_P1_RX_DN<2>                                              
P  NNAMEm4465 P5E_CPU0_P1_RX_DN<1>                                              
P  NNAMEm4466 P5E_CPU0_P1_RX_DN<15>                                             
P  NNAMEm4467 P5E_CPU0_P1_RX_DN<14>                                             
P  NNAMEm4468 P5E_CPU0_P1_RX_DN<13>                                             
P  NNAMEm4469 P5E_CPU0_P1_RX_DN<12>                                             
P  NNAMEm4470 P5E_CPU0_P1_RX_DN<11>                                             
P  NNAMEm4471 P5E_CPU0_P1_RX_DN<10>                                             
P  NNAMEm4472 P5E_CPU0_P1_RX_DN<0>                                              
P  NNAMEm4473 P5E_CPU0_P0_TX_DP<9>                                              
P  NNAMEm4474 P5E_CPU0_P0_TX_DP<8>                                              
P  NNAMEm4475 P5E_CPU0_P0_TX_DP<7>                                              
P  NNAMEm4476 P5E_CPU0_P0_TX_DP<6>                                              
P  NNAMEm4477 P5E_CPU0_P0_TX_DP<5>                                              
P  NNAMEm4478 P5E_CPU0_P0_TX_DP<4>                                              
P  NNAMEm4479 P5E_CPU0_P0_TX_DP<3>                                              
P  NNAMEm4480 P5E_CPU0_P0_TX_DP<2>                                              
P  NNAMEm4481 P5E_CPU0_P0_TX_DP<1>                                              
P  NNAMEm4482 P5E_CPU0_P0_TX_DP<15>                                             
P  NNAMEm4483 P5E_CPU0_P0_TX_DP<14>                                             
P  NNAMEm4484 P5E_CPU0_P0_TX_DP<13>                                             
P  NNAMEm4485 P5E_CPU0_P0_TX_DP<12>                                             
P  NNAMEm4486 P5E_CPU0_P0_TX_DP<11>                                             
P  NNAMEm4487 P5E_CPU0_P0_TX_DP<10>                                             
P  NNAMEm4488 P5E_CPU0_P0_TX_DP<0>                                              
P  NNAMEm4489 P5E_CPU0_P0_TX_DN<9>                                              
P  NNAMEm4490 P5E_CPU0_P0_TX_DN<8>                                              
P  NNAMEm4491 P5E_CPU0_P0_TX_DN<7>                                              
P  NNAMEm4492 P5E_CPU0_P0_TX_DN<6>                                              
P  NNAMEm4493 P5E_CPU0_P0_TX_DN<5>                                              
P  NNAMEm4494 P5E_CPU0_P0_TX_DN<4>                                              
P  NNAMEm4495 P5E_CPU0_P0_TX_DN<3>                                              
P  NNAMEm4496 P5E_CPU0_P0_TX_DN<2>                                              
P  NNAMEm4497 P5E_CPU0_P0_TX_DN<1>                                              
P  NNAMEm4498 P5E_CPU0_P0_TX_DN<15>                                             
P  NNAMEm4499 P5E_CPU0_P0_TX_DN<14>                                             
P  NNAMEm4500 P5E_CPU0_P0_TX_DN<13>                                             
P  NNAMEm4501 P5E_CPU0_P0_TX_DN<12>                                             
P  NNAMEm4502 P5E_CPU0_P0_TX_DN<11>                                             
P  NNAMEm4503 P5E_CPU0_P0_TX_DN<10>                                             
P  NNAMEm4504 P5E_CPU0_P0_TX_DN<0>                                              
P  NNAMEm4505 P5E_CPU0_P0_RX_DP<9>                                              
P  NNAMEm4506 P5E_CPU0_P0_RX_DP<8>                                              
P  NNAMEm4507 P5E_CPU0_P0_RX_DP<7>                                              
P  NNAMEm4508 P5E_CPU0_P0_RX_DP<6>                                              
P  NNAMEm4509 P5E_CPU0_P0_RX_DP<5>                                              
P  NNAMEm4510 P5E_CPU0_P0_RX_DP<4>                                              
P  NNAMEm4511 P5E_CPU0_P0_RX_DP<3>                                              
P  NNAMEm4512 P5E_CPU0_P0_RX_DP<2>                                              
P  NNAMEm4513 P5E_CPU0_P0_RX_DP<1>                                              
P  NNAMEm4514 P5E_CPU0_P0_RX_DP<15>                                             
P  NNAMEm4515 P5E_CPU0_P0_RX_DP<14>                                             
P  NNAMEm4516 P5E_CPU0_P0_RX_DP<13>                                             
P  NNAMEm4517 P5E_CPU0_P0_RX_DP<12>                                             
P  NNAMEm4518 P5E_CPU0_P0_RX_DP<11>                                             
P  NNAMEm4519 P5E_CPU0_P0_RX_DP<10>                                             
P  NNAMEm4520 P5E_CPU0_P0_RX_DP<0>                                              
P  NNAMEm4521 P5E_CPU0_P0_RX_DN<9>                                              
P  NNAMEm4522 P5E_CPU0_P0_RX_DN<8>                                              
P  NNAMEm4523 P5E_CPU0_P0_RX_DN<7>                                              
P  NNAMEm4524 P5E_CPU0_P0_RX_DN<6>                                              
P  NNAMEm4525 P5E_CPU0_P0_RX_DN<5>                                              
P  NNAMEm4526 P5E_CPU0_P0_RX_DN<4>                                              
P  NNAMEm4527 P5E_CPU0_P0_RX_DN<3>                                              
P  NNAMEm4528 P5E_CPU0_P0_RX_DN<2>                                              
P  NNAMEm4529 P5E_CPU0_P0_RX_DN<1>                                              
P  NNAMEm4530 P5E_CPU0_P0_RX_DN<15>                                             
P  NNAMEm4531 P5E_CPU0_P0_RX_DN<14>                                             
P  NNAMEm4532 P5E_CPU0_P0_RX_DN<13>                                             
P  NNAMEm4533 P5E_CPU0_P0_RX_DN<12>                                             
P  NNAMEm4534 P5E_CPU0_P0_RX_DN<11>                                             
P  NNAMEm4535 P5E_CPU0_P0_RX_DN<10>                                             
P  NNAMEm4536 P5E_CPU0_P0_RX_DN<0>                                              
P  NNAMEm4537 P5E_CPU0_G3_TX_DP<9>                                              
P  NNAMEm4538 P5E_CPU0_G3_TX_DP<8>                                              
P  NNAMEm4539 P5E_CPU0_G3_TX_DP<7>                                              
P  NNAMEm4540 P5E_CPU0_G3_TX_DP<6>                                              
P  NNAMEm4541 P5E_CPU0_G3_TX_DP<5>                                              
P  NNAMEm4542 P5E_CPU0_G3_TX_DP<4>                                              
P  NNAMEm4543 P5E_CPU0_G3_TX_DP<3>                                              
P  NNAMEm4544 P5E_CPU0_G3_TX_DP<2>                                              
P  NNAMEm4545 P5E_CPU0_G3_TX_DP<1>                                              
P  NNAMEm4546 P5E_CPU0_G3_TX_DP<15>                                             
P  NNAMEm4547 P5E_CPU0_G3_TX_DP<14>                                             
P  NNAMEm4548 P5E_CPU0_G3_TX_DP<13>                                             
P  NNAMEm4549 P5E_CPU0_G3_TX_DP<12>                                             
P  NNAMEm4550 P5E_CPU0_G3_TX_DP<11>                                             
P  NNAMEm4551 P5E_CPU0_G3_TX_DP<10>                                             
P  NNAMEm4552 P5E_CPU0_G3_TX_DP<0>                                              
P  NNAMEm4553 P5E_CPU0_G3_TX_DN<9>                                              
P  NNAMEm4554 P5E_CPU0_G3_TX_DN<8>                                              
P  NNAMEm4555 P5E_CPU0_G3_TX_DN<7>                                              
P  NNAMEm4556 P5E_CPU0_G3_TX_DN<6>                                              
P  NNAMEm4557 P5E_CPU0_G3_TX_DN<5>                                              
P  NNAMEm4558 P5E_CPU0_G3_TX_DN<4>                                              
P  NNAMEm4559 P5E_CPU0_G3_TX_DN<3>                                              
P  NNAMEm4560 P5E_CPU0_G3_TX_DN<2>                                              
P  NNAMEm4561 P5E_CPU0_G3_TX_DN<1>                                              
P  NNAMEm4562 P5E_CPU0_G3_TX_DN<15>                                             
P  NNAMEm4563 P5E_CPU0_G3_TX_DN<14>                                             
P  NNAMEm4564 P5E_CPU0_G3_TX_DN<13>                                             
P  NNAMEm4565 P5E_CPU0_G3_TX_DN<12>                                             
P  NNAMEm4566 P5E_CPU0_G3_TX_DN<11>                                             
P  NNAMEm4567 P5E_CPU0_G3_TX_DN<10>                                             
P  NNAMEm4568 P5E_CPU0_G3_TX_DN<0>                                              
P  NNAMEm4569 P5E_CPU0_G3_RX_DP<9>                                              
P  NNAMEm4570 P5E_CPU0_G3_RX_DP<8>                                              
P  NNAMEm4571 P5E_CPU0_G3_RX_DP<7>                                              
P  NNAMEm4572 P5E_CPU0_G3_RX_DP<6>                                              
P  NNAMEm4573 P5E_CPU0_G3_RX_DP<5>                                              
P  NNAMEm4574 P5E_CPU0_G3_RX_DP<4>                                              
P  NNAMEm4575 P5E_CPU0_G3_RX_DP<3>                                              
P  NNAMEm4576 P5E_CPU0_G3_RX_DP<2>                                              
P  NNAMEm4577 P5E_CPU0_G3_RX_DP<1>                                              
P  NNAMEm4578 P5E_CPU0_G3_RX_DP<15>                                             
P  NNAMEm4579 P5E_CPU0_G3_RX_DP<14>                                             
P  NNAMEm4580 P5E_CPU0_G3_RX_DP<13>                                             
P  NNAMEm4581 P5E_CPU0_G3_RX_DP<12>                                             
P  NNAMEm4582 P5E_CPU0_G3_RX_DP<11>                                             
P  NNAMEm4583 P5E_CPU0_G3_RX_DP<10>                                             
P  NNAMEm4584 P5E_CPU0_G3_RX_DP<0>                                              
P  NNAMEm4585 P5E_CPU0_G3_RX_DN<9>                                              
P  NNAMEm4586 P5E_CPU0_G3_RX_DN<8>                                              
P  NNAMEm4587 P5E_CPU0_G3_RX_DN<7>                                              
P  NNAMEm4588 P5E_CPU0_G3_RX_DN<6>                                              
P  NNAMEm4589 P5E_CPU0_G3_RX_DN<5>                                              
P  NNAMEm4590 P5E_CPU0_G3_RX_DN<4>                                              
P  NNAMEm4591 P5E_CPU0_G3_RX_DN<3>                                              
P  NNAMEm4592 P5E_CPU0_G3_RX_DN<2>                                              
P  NNAMEm4593 P5E_CPU0_G3_RX_DN<1>                                              
P  NNAMEm4594 P5E_CPU0_G3_RX_DN<15>                                             
P  NNAMEm4595 P5E_CPU0_G3_RX_DN<14>                                             
P  NNAMEm4596 P5E_CPU0_G3_RX_DN<13>                                             
P  NNAMEm4597 P5E_CPU0_G3_RX_DN<12>                                             
P  NNAMEm4598 P5E_CPU0_G3_RX_DN<11>                                             
P  NNAMEm4599 P5E_CPU0_G3_RX_DN<10>                                             
P  NNAMEm4600 P5E_CPU0_G3_RX_DN<0>                                              
P  NNAMEm4601 P5E_CPU0_P3_RX_DP<9>                                              
P  NNAMEm4602 P5E_CPU0_P3_RX_DP<8>                                              
P  NNAMEm4603 P5E_CPU0_P3_RX_DP<11>                                             
P  NNAMEm4604 P5E_CPU0_P3_RX_DP<10>                                             
P  NNAMEm4605 P5E_CPU0_P3_RX_DN<9>                                              
P  NNAMEm4606 P5E_CPU0_P3_RX_DN<8>                                              
P  NNAMEm4607 P5E_CPU0_P3_RX_DN<11>                                             
P  NNAMEm4608 P5E_CPU0_P3_RX_DN<10>                                             
P  NNAMEm4609 P3V3_OCP_V3_2_R                                                   
P  NNAMEm4610 P3V3_OCP_UV_2_R1                                                  
P  NNAMEm4611 P3V3_OCP_UV_1_R1                                                  
P  NNAMEm4612 P3V3_OCP_SENSE_2                                                  
P  NNAMEm4613 P3V3_OCP_SENSE_1                                                  
P  NNAMEm4614 P3V3_OCP_PWRGD_2                                                  
P  NNAMEm4615 P3V3_OCP_PWRGD_1                                                  
P  NNAMEm4616 P3V3_OCP_MODE_2                                                   
P  NNAMEm4617 P3V3_OCP_MODE_1                                                   
P  NNAMEm4618 P3V3_OCP_ILIMIT_2                                                 
P  NNAMEm4619 P3V3_OCP_ILIMIT_1                                                 
P  NNAMEm4620 P3V3_OCP_GATE_PU207_2                                             
P  NNAMEm4621 P3V3_OCP_GATE_PU202_1                                             
P  NNAMEm4622 P3V3_OCP_GATE_2                                                   
P  NNAMEm4623 P3V3_OCP_GATE_1                                                   
P  NNAMEm4624 P3V3_OCP_FAULT_2                                                  
P  NNAMEm4625 P3V3_OCP_FAULT_1                                                  
P  NNAMEm4626 P3V3_OCP_EN_2_R                                                   
P  NNAMEm4627 P3V3_OCP_EN_1_R2                                                  
P  NNAMEm4628 P3V3_OCP_EN_1_R                                                   
P  NNAMEm4629 P3V3_OCP_SFF_EN                                                   
P  NNAMEm4630 P3V3_OCP_DVDT_2                                                   
P  NNAMEm4631 P3V3_OCP_DVDT_1                                                   
P  NNAMEm4632 P3V3_OCP_2_EN_G                                                   
P  NNAMEm4633 P3V3_OCP_1_EN_G                                                   
P  NNAMEm4634 P3V3_E1S_UV_0_R                                                   
P  NNAMEm4635 P3V3_E1S_SENSE_0                                                  
P  NNAMEm4636 P3V3_E1S_PWRGD_0                                                  
P  NNAMEm4637 P3V3_E1S_MODE_0                                                   
P  NNAMEm4638 P3V3_E1S_ILIMIT_0                                                 
P  NNAMEm4639 P3V3_E1S_GATE_0_PU293                                             
P  NNAMEm4640 P3V3_E1S_GATE_0                                                   
P  NNAMEm4641 P3V3_E1S_FAULT_0                                                  
P  NNAMEm4642 P3V3_E1S_EN_0_R2                                                  
P  NNAMEm4643 P3V3_E1S_DVDT_0                                                   
P  NNAMEm4644 P3V3_E1S_0_EN_R                                                   
P  NNAMEm4645 P3V3_E1S_0_EN_G                                                   
P  NNAMEm4646 P5E_CPU0_P3_RX_DN<0>                                              
P  NNAMEm4647 P5E_CPU0_P3_RX_DP<0>                                              
P  NNAMEm4648 P2E_MB_BMC_TX_C_DP<0>                                             
P  NNAMEm4649 P2E_MB_BMC_TX_C_DN<0>                                             
P  NNAMEm4650 P2E_MB_BMC_TX_BUF_C_DP<0>                                         
P  NNAMEm4651 P2E_MB_BMC_TX_BUF_C_DN<0>                                         
P  NNAMEm4652 P2E_MB_BMC_RX_DP<0>                                               
P  NNAMEm4653 P2E_MB_BMC_RX_DN<0>                                               
P  NNAMEm4654 P2E_MB_BMC_RX_BUF_DP<0>                                           
P  NNAMEm4655 P2E_MB_BMC_RX_BUF_DN<0>                                           
P  NNAMEm4656 P12V_SCM_ISET_R                                                   
P  NNAMEm4657 P12V_SCM_AVIN_PD                                                  
P  NNAMEm4658 P12V_OCP_V3_2_ISENSE_MPS_TIC                                      
P  NNAMEm4659 P12V_OCP_V3_2_ISENSE_MPS_MAM                                      
P  NNAMEm4660 P12V_OCP_V3_2_ISENSE_MAM_TIC                                      
P  NNAMEm4661 P12V_OCP_V3_2_ISENSE_MAM_MAM                                      
P  NNAMEm4662 P12V_OCP_V3_2_EN_2_R3                                             
P  NNAMEm4663 P12V_OCP_UV_2_R                                                   
P  NNAMEm4664 P12V_OCP_UV_1_R                                                   
P  NNAMEm4665 P12V_OCP_TIMER_2                                                  
P  NNAMEm4666 P12V_OCP_TIMER_1                                                  
P  NNAMEm4667 P12V_OCP_SFF_ISENSE_MPS_TIC                                       
P  NNAMEm4668 P12V_OCP_SFF_ISENSE_MPS_MAM                                       
P  NNAMEm4669 P12V_OCP_SFF_ISENSE_MAM_TIC                                       
P  NNAMEm4670 P12V_OCP_SFF_ISENSE_MAM_MAM                                       
P  NNAMEm4671 P12V_OCP_SENSE_2                                                  
P  NNAMEm4672 P12V_OCP_SENSE_1                                                  
P  NNAMEm4673 P12V_OCP_PWRGD_2                                                  
P  NNAMEm4674 P12V_OCP_PWRGD_1                                                  
P  NNAMEm4675 P12V_OCP_OV_FB_2                                                  
P  NNAMEm4676 P12V_OCP_OV_FB_1                                                  
P  NNAMEm4677 P12V_OCP_ISET_2                                                   
P  NNAMEm4678 P12V_OCP_ISET_1                                                   
P  NNAMEm4679 P12V_OCP_IMON_2                                                   
P  NNAMEm4680 P12V_OCP_IMON_1                                                   
P  NNAMEm4681 P12V_OCP_GATE_2                                                   
P  NNAMEm4682 P12V_OCP_GATE_1                                                   
P  NNAMEm4683 P12V_OCP_FLTB_2                                                   
P  NNAMEm4684 P12V_OCP_FLTB_1                                                   
P  NNAMEm4685 P12V_OCP_FAULT_2                                                  
P  NNAMEm4686 P12V_OCP_FAULT_1                                                  
P  NNAMEm4687 P12V_OCP_EN_2_R                                                   
P  NNAMEm4688 P12V_OCP_EN_1_R2                                                  
P  NNAMEm4689 P12V_OCP_EN_1_R                                                   
P  NNAMEm4690 P12V_OCP_SFF_EN                                                   
P  NNAMEm4691 P12V_OCP_AVIN_PD_2                                                
P  NNAMEm4692 P12V_OCP_AVIN_PD_1                                                
P  NNAMEm4693 P12V_OCP_2_EN_G                                                   
P  NNAMEm4694 P12V_OCP_1_EN_G                                                   
P  NNAMEm4695 P12V_E1S_UV_0_R                                                   
P  NNAMEm4696 P12V_E1S_TIMER_0                                                  
P  NNAMEm4697 P12V_E1S_SENSE_0                                                  
P  NNAMEm4698 P12V_E1S_PWRGD_0                                                  
P  NNAMEm4699 P12V_E1S_OV_FB_0                                                  
P  NNAMEm4700 P12V_E1S_ISET_0_R                                                 
P  NNAMEm4701 P12V_E1S_ISET_0                                                   
P  NNAMEm4702 P12V_E1S_IMON_0                                                   
P  NNAMEm4703 P12V_E1S_GATE_0                                                   
P  NNAMEm4704 P12V_E1S_FLTB_0                                                   
P  NNAMEm4705 P12V_E1S_FAULT_0                                                  
P  NNAMEm4706 P12V_E1S_EN_0_R2                                                  
P  NNAMEm4707 P12V_E1S_EN_0_R                                                   
P  NNAMEm4708 P12V_E1S_AVIN_PD_0                                                
P  NNAMEm4709 P12V_E1S_0_ISENSE_MPS_TIC                                         
P  NNAMEm4710 P12V_E1S_0_ISENSE_MPS_MAM                                         
P  NNAMEm4711 P12V_E1S_0_ISENSE_MAM_TIC                                         
P  NNAMEm4712 P12V_E1S_0_ISENSE_MAM_MAM                                         
P  NNAMEm4713 P12V_E1S_0_EN_G                                                   
P  NNAMEm4714 P12V_ALL_PWROK_R                                                  
P  NNAMEm4715 P12V_ALL_PWROK_N                                                  
P  NNAMEm4716 OCP_V3_2_WAKE_BUFF_R_N                                            
P  NNAMEm4717 OCP_V3_2_WAKE_BUFF_N                                              
P  NNAMEm4718 OCP_V3_2_RBT_ARB_OUT                                              
P  NNAMEm4719 OCP_V3_2_RBT_ARB_IN_R                                             
P  NNAMEm4720 OCP_V3_2_RBT_ARB_IN                                               
P  NNAMEm4721 OCP_V3_2_PWRBRK_N                                                 
P  NNAMEm4722 OCP_V3_2_PWRBRK_BUFF_N                                            
P  NNAMEm4723 OCP_V3_2_PRSNT_ALL_R_N                                            
P  NNAMEm4724 OCP_V3_2_PRSNT_ALL_R3_N                                           
P  NNAMEm4725 OCP_V3_2_PRSNT_ALL_R1_N                                           
P  NNAMEm4726 OCP_V3_2_PRSNT3_R_N                                               
P  NNAMEm4727 OCP_V3_2_PRSNT2_R_N                                               
P  NNAMEm4728 OCP_V3_2_PRSNT23_R_N                                              
P  NNAMEm4729 OCP_V3_2_PRSNT1_R_N                                               
P  NNAMEm4730 OCP_V3_2_PRSNT0_R_N                                               
P  NNAMEm4731 OCP_V3_2_PRSNT01_R_N                                              
P  NNAMEm4732 OCP_V3_2_P3V3_PWRGD                                               
P  NNAMEm4733 OCP_V3_2_NOT_PRSNT_RBT_ARB_IN                                     
P  NNAMEm4734 OCP_V3_2_MAIN_PWR_EN_R                                            
P  NNAMEm4735 OCP_V3_2_MAIN_PWR_EN                                              
P  NNAMEm4736 OCP_V3_2_ISO_BIF2_EN                                              
P  NNAMEm4737 OCP_V3_2_ISO_BIF1_EN                                              
P  NNAMEm4738 OCP_V3_2_ISO_BIF0_EN                                              
P  NNAMEm4739 OCP_V3_2_ISO2_RBT_ARB_OUT                                         
P  NNAMEm4740 OCP_V3_2_ISO1_RBT_ARB_IN                                          
P  NNAMEm4741 OCP_V3_2_BIF2_R_N                                                 
P  NNAMEm4742 OCP_V3_2_BIF1_R_N                                                 
P  NNAMEm4743 OCP_V3_2_BIF0_R_N                                                 
P  NNAMEm4744 OCP_V3_2_AUX_PWR_EN_R3                                            
P  NNAMEm4745 OCP_V3_2_AUX_PWR_EN_R1                                            
P  NNAMEm4746 OCP_V3_2_AUX_PWR_EN_R                                             
P  NNAMEm4747 OCP_V3_2_AUX_PWR_EN                                               
P  NNAMEm4748 OCP_V3_2_PRSNTA_R_N                                               
P  NNAMEm4749 OCP_V3_1_P3V3_PWRGD                                               
P  NNAMEm4750 OCP_SFF_WAKE_BUFF_R_N                                             
P  NNAMEm4751 OCP_SFF_WAKE_BUFF_N                                               
P  NNAMEm4752 OCP_SFF_RBT_ARB_OUT                                               
P  NNAMEm4753 OCP_SFF_RBT_ARB_IN_R                                              
P  NNAMEm4754 OCP_SFF_RBT_ARB_IN_MUX2_R                                         
P  NNAMEm4755 OCP_SFF_RBT_ARB_IN_MUX2                                           
P  NNAMEm4756 OCP_SFF_RBT_ARB_IN_MUX1_R                                         
P  NNAMEm4757 OCP_SFF_RBT_ARB_IN_MUX1                                           
P  NNAMEm4758 OCP_SFF_RBT_ARB_IN                                                
P  NNAMEm4759 OCP_SFF_PWRBRK_N                                                  
P  NNAMEm4760 OCP_SFF_PWRBRK_BUFF_N                                             
P  NNAMEm4761 OCP_SFF_PRSNT_ALL_R_N                                             
P  NNAMEm4762 OCP_SFF_PRSNT_ALL_R3_N                                            
P  NNAMEm4763 OCP_SFF_PRSNT_ALL_R1_N                                            
P  NNAMEm4764 OCP_SFF_PRSNTA_R_N                                                
P  NNAMEm4765 OCP_SFF_PRSNT3_R_N                                                
P  NNAMEm4766 OCP_SFF_PRSNT2_R_N                                                
P  NNAMEm4767 OCP_SFF_PRSNT23_R_N                                               
P  NNAMEm4768 OCP_SFF_PRSNT1_R_N                                                
P  NNAMEm4769 OCP_SFF_PRSNT0_R_N                                                
P  NNAMEm4770 OCP_SFF_PRSNT01_R_N                                               
P  NNAMEm4771 OCP_SFF_NOT_PRSNT_RBT_ARB_IN                                      
P  NNAMEm4772 OCP_SFF_MAIN_PWR_EN_R                                             
P  NNAMEm4773 OCP_SFF_MAIN_PWR_EN                                               
P  NNAMEm4774 OCP_SFF_ISO_BIF2_EN                                               
P  NNAMEm4775 OCP_SFF_ISO_BIF1_EN                                               
P  NNAMEm4776 OCP_SFF_ISO_BIF0_EN                                               
P  NNAMEm4777 OCP_SFF_ISO2_RBT_ARB_OUT                                          
P  NNAMEm4778 OCP_SFF_ISO1_RBT_ARB_IN                                           
P  NNAMEm4779 OCP_SFF_BIF2_R_N                                                  
P  NNAMEm4780 OCP_SFF_BIF1_R_N                                                  
P  NNAMEm4781 OCP_SFF_BIF0_R_N                                                  
P  NNAMEm4782 OCP_SFF_AUX_PWR_EN_R1                                             
P  NNAMEm4783 OCP_SFF_AUX_PWR_EN_R                                              
P  NNAMEm4784 OCP_SFF_AUX_PWR_EN                                                
P  NNAMEm4785 NC_PVDDIO_P1_GL2_4                                                
P  NNAMEm4786 NC_PVDDIO_P1_GL2_3                                                
P  NNAMEm4787 NC_PVDDIO_P1_GL2_2                                                
P  NNAMEm4788 NC_PVDDIO_P1_GL2_1                                                
P  NNAMEm4789 NC_PVDDIO_P1_GL1_4                                                
P  NNAMEm4790 NC_PVDDIO_P1_GL1_3                                                
P  NNAMEm4791 NC_PVDDIO_P1_GL1_2                                                
P  NNAMEm4792 NC_PVDDIO_P1_GL1_1                                                
P  NNAMEm4793 NC_PVDDIO_P1_DNC4                                                 
P  NNAMEm4794 NC_PVDDIO_P1_DNC3                                                 
P  NNAMEm4795 NC_PVDDIO_P1_DNC2                                                 
P  NNAMEm4796 NC_PVDDIO_P1_DNC1                                                 
P  NNAMEm4797 NC_PVDDIO_P0_GL2_4                                                
P  NNAMEm4798 NC_PVDDIO_P0_GL2_3                                                
P  NNAMEm4799 NC_PVDDIO_P0_GL2_2                                                
P  NNAMEm4800 NC_PVDDIO_P0_GL2_1                                                
P  NNAMEm4801 NC_PVDDIO_P0_GL1_4                                                
P  NNAMEm4802 NC_PVDDIO_P0_GL1_3                                                
P  NNAMEm4803 NC_PVDDIO_P0_GL1_2                                                
P  NNAMEm4804 NC_PVDDIO_P0_GL1_1                                                
P  NNAMEm4805 NC_PVDDIO_P0_DNC4                                                 
P  NNAMEm4806 NC_PVDDIO_P0_DNC3                                                 
P  NNAMEm4807 NC_PVDDIO_P0_DNC2                                                 
P  NNAMEm4808 NC_PVDDIO_P0_DNC1                                                 
P  NNAMEm4809 NC_PVDDCR_SOC_P1_GL2_3                                            
P  NNAMEm4810 NC_PVDDCR_SOC_P1_GL2_2                                            
P  NNAMEm4811 NC_PVDDCR_SOC_P1_GL2_1                                            
P  NNAMEm4812 NC_PVDDCR_SOC_P1_GL1_3                                            
P  NNAMEm4813 NC_PVDDCR_SOC_P1_GL1_2                                            
P  NNAMEm4814 NC_PVDDCR_SOC_P1_GL1_1                                            
P  NNAMEm4815 NC_PVDDCR_SOC_P1_DNC3                                             
P  NNAMEm4816 NC_PVDDCR_SOC_P1_DNC2                                             
P  NNAMEm4817 NC_PVDDCR_SOC_P1_DNC1                                             
P  NNAMEm4818 NC_PVDDCR_SOC_P0_GL2_3                                            
P  NNAMEm4819 NC_PVDDCR_SOC_P0_GL2_2                                            
P  NNAMEm4820 NC_PVDDCR_SOC_P0_GL2_1                                            
P  NNAMEm4821 NC_PVDDCR_SOC_P0_GL1_3                                            
P  NNAMEm4822 NC_PVDDCR_SOC_P0_GL1_2                                            
P  NNAMEm4823 NC_PVDDCR_SOC_P0_GL1_1                                            
P  NNAMEm4824 NC_PVDDCR_SOC_P0_DNC3                                             
P  NNAMEm4825 NC_PVDDCR_SOC_P0_DNC2                                             
P  NNAMEm4826 NC_PVDDCR_SOC_P0_DNC1                                             
P  NNAMEm4827 NC_PVDDCR_CPU1_P1_PWM8                                            
P  NNAMEm4828 NC_PVDDCR_CPU1_P1_PWM7                                            
P  NNAMEm4829 NC_PVDDCR_CPU1_P1_IMON8                                           
P  NNAMEm4830 NC_PVDDCR_CPU1_P1_IMON7                                           
P  NNAMEm4831 NC_PVDDCR_CPU1_P1_GL2_6                                           
P  NNAMEm4832 NC_PVDDCR_CPU1_P1_GL2_5                                           
P  NNAMEm4833 NC_PVDDCR_CPU1_P1_GL2_4                                           
P  NNAMEm4834 NC_PVDDCR_CPU1_P1_GL2_3                                           
P  NNAMEm4835 NC_PVDDCR_CPU1_P1_GL2_2                                           
P  NNAMEm4836 NC_PVDDCR_CPU1_P1_GL2_1                                           
P  NNAMEm4837 NC_PVDDCR_CPU1_P1_GL1_6                                           
P  NNAMEm4838 NC_PVDDCR_CPU1_P1_GL1_5                                           
P  NNAMEm4839 NC_PVDDCR_CPU1_P1_GL1_4                                           
P  NNAMEm4840 NC_PVDDCR_CPU1_P1_GL1_3                                           
P  NNAMEm4841 NC_PVDDCR_CPU1_P1_GL1_2                                           
P  NNAMEm4842 NC_PVDDCR_CPU1_P1_GL1_1                                           
P  NNAMEm4843 NC_PVDDCR_CPU1_P1_DNC6                                            
P  NNAMEm4844 NC_PVDDCR_CPU1_P1_DNC5                                            
P  NNAMEm4845 NC_PVDDCR_CPU1_P1_DNC4                                            
P  NNAMEm4846 NC_PVDDCR_CPU1_P1_DNC3                                            
P  NNAMEm4847 NC_PVDDCR_CPU1_P1_DNC2                                            
P  NNAMEm4848 NC_PVDDCR_CPU1_P1_DNC1                                            
P  NNAMEm4849 NC_PVDDCR_CPU1_P0_PWM8                                            
P  NNAMEm4850 NC_PVDDCR_CPU1_P0_PWM7                                            
P  NNAMEm4851 NC_PVDDCR_CPU1_P0_IMON8                                           
P  NNAMEm4852 NC_PVDDCR_CPU1_P0_IMON7                                           
P  NNAMEm4853 NC_PVDDCR_CPU1_P0_GL2_6                                           
P  NNAMEm4854 NC_PVDDCR_CPU1_P0_GL2_5                                           
P  NNAMEm4855 NC_PVDDCR_CPU1_P0_GL2_4                                           
P  NNAMEm4856 NC_PVDDCR_CPU1_P0_GL2_3                                           
P  NNAMEm4857 NC_PVDDCR_CPU1_P0_GL2_2                                           
P  NNAMEm4858 NC_PVDDCR_CPU1_P0_GL2_1                                           
P  NNAMEm4859 NC_PVDDCR_CPU1_P0_GL1_6                                           
P  NNAMEm4860 NC_PVDDCR_CPU1_P0_GL1_5                                           
P  NNAMEm4861 NC_PVDDCR_CPU1_P0_GL1_4                                           
P  NNAMEm4862 NC_PVDDCR_CPU1_P0_GL1_3                                           
P  NNAMEm4863 NC_PVDDCR_CPU1_P0_GL1_2                                           
P  NNAMEm4864 NC_PVDDCR_CPU1_P0_GL1_1                                           
P  NNAMEm4865 NC_PVDDCR_CPU1_P0_DNC6                                            
P  NNAMEm4866 NC_PVDDCR_CPU1_P0_DNC5                                            
P  NNAMEm4867 NC_PVDDCR_CPU1_P0_DNC4                                            
P  NNAMEm4868 NC_PVDDCR_CPU1_P0_DNC3                                            
P  NNAMEm4869 NC_PVDDCR_CPU1_P0_DNC2                                            
P  NNAMEm4870 NC_PVDDCR_CPU1_P0_DNC1                                            
P  NNAMEm4871 NC_PVDDCR_CPU0_P1_PWM9                                            
P  NNAMEm4872 NC_PVDDCR_CPU0_P1_PWM8                                            
P  NNAMEm4873 NC_PVDDCR_CPU0_P1_PWM7                                            
P  NNAMEm4874 NC_PVDDCR_CPU0_P1_IMON9                                           
P  NNAMEm4875 NC_PVDDCR_CPU0_P1_IMON8                                           
P  NNAMEm4876 NC_PVDDCR_CPU0_P1_IMON7                                           
P  NNAMEm4877 NC_PVDDCR_CPU0_P1_GL2_6                                           
P  NNAMEm4878 NC_PVDDCR_CPU0_P1_GL2_5                                           
P  NNAMEm4879 NC_PVDDCR_CPU0_P1_GL2_4                                           
P  NNAMEm4880 NC_PVDDCR_CPU0_P1_GL2_3                                           
P  NNAMEm4881 NC_PVDDCR_CPU0_P1_GL2_2                                           
P  NNAMEm4882 NC_PVDDCR_CPU0_P1_GL2_1                                           
P  NNAMEm4883 NC_PVDDCR_CPU0_P1_GL1_6                                           
P  NNAMEm4884 NC_PVDDCR_CPU0_P1_GL1_5                                           
P  NNAMEm4885 NC_PVDDCR_CPU0_P1_GL1_4                                           
P  NNAMEm4886 NC_PVDDCR_CPU0_P1_GL1_3                                           
P  NNAMEm4887 NC_PVDDCR_CPU0_P1_GL1_2                                           
P  NNAMEm4888 NC_PVDDCR_CPU0_P1_GL1_1                                           
P  NNAMEm4889 NC_PVDDCR_CPU0_P1_DNC6                                            
P  NNAMEm4890 NC_PVDDCR_CPU0_P1_DNC5                                            
P  NNAMEm4891 NC_PVDDCR_CPU0_P1_DNC4                                            
P  NNAMEm4892 NC_PVDDCR_CPU0_P1_DNC3                                            
P  NNAMEm4893 NC_PVDDCR_CPU0_P1_DNC2                                            
P  NNAMEm4894 NC_PVDDCR_CPU0_P1_DNC1                                            
P  NNAMEm4895 NC_PVDDCR_CPU0_P0_PWM9                                            
P  NNAMEm4896 NC_PVDDCR_CPU0_P0_PWM8                                            
P  NNAMEm4897 NC_PVDDCR_CPU0_P0_PWM7                                            
P  NNAMEm4898 NC_PVDDCR_CPU0_P0_IMON9                                           
P  NNAMEm4899 NC_PVDDCR_CPU0_P0_IMON8                                           
P  NNAMEm4900 NC_PVDDCR_CPU0_P0_IMON7                                           
P  NNAMEm4901 NC_PVDDCR_CPU0_P0_GL2_6                                           
P  NNAMEm4902 NC_PVDDCR_CPU0_P0_GL2_5                                           
P  NNAMEm4903 NC_PVDDCR_CPU0_P0_GL2_4                                           
P  NNAMEm4904 NC_PVDDCR_CPU0_P0_GL2_3                                           
P  NNAMEm4905 NC_PVDDCR_CPU0_P0_GL2_2                                           
P  NNAMEm4906 NC_PVDDCR_CPU0_P0_GL2_1                                           
P  NNAMEm4907 NC_PVDDCR_CPU0_P0_GL1_6                                           
P  NNAMEm4908 NC_PVDDCR_CPU0_P0_GL1_5                                           
P  NNAMEm4909 NC_PVDDCR_CPU0_P0_GL1_4                                           
P  NNAMEm4910 NC_PVDDCR_CPU0_P0_GL1_3                                           
P  NNAMEm4911 NC_PVDDCR_CPU0_P0_GL1_2                                           
P  NNAMEm4912 NC_PVDDCR_CPU0_P0_GL1_1                                           
P  NNAMEm4913 NC_PVDDCR_CPU0_P0_DNC6                                            
P  NNAMEm4914 NC_PVDDCR_CPU0_P0_DNC5                                            
P  NNAMEm4915 NC_PVDDCR_CPU0_P0_DNC4                                            
P  NNAMEm4916 NC_PVDDCR_CPU0_P0_DNC3                                            
P  NNAMEm4917 NC_PVDDCR_CPU0_P0_DNC2                                            
P  NNAMEm4918 NC_PVDDCR_CPU0_P0_DNC1                                            
P  NNAMEm4919 NC_PVDD11_S3_P1_SVTO                                              
P  NNAMEm4920 NC_PVDD11_S3_P1_PWM8                                              
P  NNAMEm4921 NC_PVDD11_S3_P1_PWM7                                              
P  NNAMEm4922 NC_PVDD11_S3_P1_PWM6                                              
P  NNAMEm4923 NC_PVDD11_S3_P1_PWM5                                              
P  NNAMEm4924 NC_PVDD11_S3_P1_PWM4                                              
P  NNAMEm4925 NC_PVDD11_S3_P1_PWM3                                              
P  NNAMEm4926 NC_PVDD11_S3_P1_PG1                                               
P  NNAMEm4927 NC_PVDD11_S3_P1_IMON8                                             
P  NNAMEm4928 NC_PVDD11_S3_P1_IMON7                                             
P  NNAMEm4929 NC_PVDD11_S3_P1_IMON6                                             
P  NNAMEm4930 NC_PVDD11_S3_P1_IMON5                                             
P  NNAMEm4931 NC_PVDD11_S3_P1_IMON4                                             
P  NNAMEm4932 NC_PVDD11_S3_P1_IMON3                                             
P  NNAMEm4933 NC_PVDD11_S3_P1_GL2_2                                             
P  NNAMEm4934 NC_PVDD11_S3_P1_GL2_1                                             
P  NNAMEm4935 NC_PVDD11_S3_P1_GL1_2                                             
P  NNAMEm4936 NC_PVDD11_S3_P1_GL1_1                                             
P  NNAMEm4937 NC_PVDD11_S3_P1_DNC2                                              
P  NNAMEm4938 NC_PVDD11_S3_P1_DNC1                                              
P  NNAMEm4939 NC_PVDD11_S3_P0_SVTO                                              
P  NNAMEm4940 NC_PVDD11_S3_P0_PWM8                                              
P  NNAMEm4941 NC_PVDD11_S3_P0_PWM7                                              
P  NNAMEm4942 NC_PVDD11_S3_P0_PWM6                                              
P  NNAMEm4943 NC_PVDD11_S3_P0_PWM5                                              
P  NNAMEm4944 NC_PVDD11_S3_P0_PWM4                                              
P  NNAMEm4945 NC_PVDD11_S3_P0_PWM3                                              
P  NNAMEm4946 NC_PVDD11_S3_P0_PG1                                               
P  NNAMEm4947 NC_PVDD11_S3_P0_IMON8                                             
P  NNAMEm4948 NC_PVDD11_S3_P0_IMON7                                             
P  NNAMEm4949 NC_PVDD11_S3_P0_IMON6                                             
P  NNAMEm4950 NC_PVDD11_S3_P0_IMON5                                             
P  NNAMEm4951 NC_PVDD11_S3_P0_IMON4                                             
P  NNAMEm4952 NC_PVDD11_S3_P0_IMON3                                             
P  NNAMEm4953 NC_PVDD11_S3_P0_GL2_2                                             
P  NNAMEm4954 NC_PVDD11_S3_P0_GL2_1                                             
P  NNAMEm4955 NC_PVDD11_S3_P0_GL1_2                                             
P  NNAMEm4956 NC_PVDD11_S3_P0_GL1_1                                             
P  NNAMEm4957 NC_PVDD11_S3_P0_DNC2                                              
P  NNAMEm4958 NC_PVDD11_S3_P0_DNC1                                              
P  NNAMEm4959 NC_CPU1_USB3_USB11_TXP                                            
P  NNAMEm4960 NC_CPU1_USB3_USB11_TXN                                            
P  NNAMEm4961 NC_CPU1_USB3_USB11_RXP                                            
P  NNAMEm4962 NC_CPU1_USB3_USB11_RXN                                            
P  NNAMEm4963 NC_CPU1_USB3_USB10_TXP                                            
P  NNAMEm4964 NC_CPU1_USB3_USB10_TXN                                            
P  NNAMEm4965 NC_CPU1_USB3_USB10_RXP                                            
P  NNAMEm4966 NC_CPU1_USB3_USB10_RXN                                            
P  NNAMEm4967 NC_CPU1_USB3_USB01_TXP                                            
P  NNAMEm4968 NC_CPU1_USB3_USB01_TXN                                            
P  NNAMEm4969 NC_CPU1_USB3_USB01_RXP                                            
P  NNAMEm4970 NC_CPU1_USB3_USB01_RXN                                            
P  NNAMEm4971 NC_CPU1_USB3_USB00_TXP                                            
P  NNAMEm4972 NC_CPU1_USB3_USB00_TXN                                            
P  NNAMEm4973 NC_CPU1_USB3_USB00_RXP                                            
P  NNAMEm4974 NC_CPU1_USB3_USB00_RXN                                            
P  NNAMEm4975 NC_CPU1_USB2_USB11_DP                                             
P  NNAMEm4976 NC_CPU1_USB2_USB11_DN                                             
P  NNAMEm4977 NC_CPU1_USB2_USB10_DP                                             
P  NNAMEm4978 NC_CPU1_USB2_USB10_DN                                             
P  NNAMEm4979 NC_CPU1_USB2_USB01_DP                                             
P  NNAMEm4980 NC_CPU1_USB2_USB01_DN                                             
P  NNAMEm4981 NC_CPU1_USB2_USB00_DP                                             
P  NNAMEm4982 NC_CPU1_USB2_USB00_DN                                             
P  NNAMEm4983 NC_CPU1_USB11_OC_N                                                
P  NNAMEm4984 NC_CPU1_USB10_OC_N                                                
P  NNAMEm4985 NC_CPU1_USB01_OC_N                                                
P  NNAMEm4986 NC_CPU1_USB00_OC_N                                                
P  NNAMEm4987 NC_CPU1_PWR_BTN_N                                                 
P  NNAMEm4988 NC_CPU1_AZ_SYNC                                                   
P  NNAMEm4989 NC_CPU1_AZ_SDOUT                                                  
P  NNAMEm4990 NC_CPU1_AZ_SDIN2                                                  
P  NNAMEm4991 NC_CPU1_AZ_SDIN1                                                  
P  NNAMEm4992 NC_CPU1_AZ_SDIN0                                                  
P  NNAMEm4993 NC_CPU1_AZ_RST_N                                                  
P  NNAMEm4994 NC_CPU1_AZ_BITCLK                                                 
P  NNAMEm4995 NC_CPU0_SPI_CS2_N                                                 
P  NNAMEm4996 NC_CPU0_AZ_SYNC                                                   
P  NNAMEm4997 NC_CPU0_AZ_SDOUT                                                  
P  NNAMEm4998 NC_CPU0_AZ_SDIN2                                                  
P  NNAMEm4999 NC_CPU0_AZ_SDIN1                                                  
P  NNAMEm5000 NC_CPU0_AZ_SDIN0                                                  
P  NNAMEm5001 NC_CPU0_AZ_RST_N                                                  
P  NNAMEm5002 NC_CPU0_AZ_BITCLK                                                 
P  NNAMEm5003 NCSI_OCP_V3_2_TX_EN                                               
P  NNAMEm5004 NCSI_OCP_V3_2_TXD1                                                
P  NNAMEm5005 NCSI_OCP_V3_2_TXD0                                                
P  NNAMEm5006 NCSI_OCP_V3_2_RXD1                                                
P  NNAMEm5007 NCSI_OCP_V3_2_RXD0                                                
P  NNAMEm5008 NCSI_OCP_V3_2_CRS_DV                                              
P  NNAMEm5009 NCSI_OCP_SFF_TX_EN                                                
P  NNAMEm5010 NCSI_OCP_SFF_TXD1                                                 
P  NNAMEm5011 NCSI_OCP_SFF_TXD0                                                 
P  NNAMEm5012 NCSI_OCP_SFF_RXD1                                                 
P  NNAMEm5013 NCSI_OCP_SFF_RXD0                                                 
P  NNAMEm5014 NCSI_OCP_SFF_CRS_DV                                               
P  NNAMEm5015 NCSI_BMC_TX_EN_R1                                                 
P  NNAMEm5016 NCSI_BMC_TX_EN_R                                                  
P  NNAMEm5017 NCSI_BMC_TXD1_R1                                                  
P  NNAMEm5018 NCSI_BMC_TXD1_R                                                   
P  NNAMEm5019 NCSI_BMC_TXD0_R1                                                  
P  NNAMEm5020 NCSI_BMC_TXD0_R                                                   
P  NNAMEm5021 NCSI_BMC_RXD1_R1                                                  
P  NNAMEm5022 NCSI_BMC_RXD1_R                                                   
P  NNAMEm5023 NCSI_BMC_RXD0_R1                                                  
P  NNAMEm5024 NCSI_BMC_RXD0_R                                                   
P  NNAMEm5025 NCSI_BMC_CRS_DV_R1                                                
P  NNAMEm5026 NCSI_BMC_CRS_DV_R                                                 
P  NNAMEm5027 M_L_CPU1_SB_RSP<0>                                                
P  NNAMEm5028 M_L_CPU1_SB_PAR                                                   
P  NNAMEm5029 M_L_CPU1_SB_DQS_DP<9>                                             
P  NNAMEm5030 M_L_CPU1_SB_DQS_DP<8>                                             
P  NNAMEm5031 M_L_CPU1_SB_DQS_DP<7>                                             
P  NNAMEm5032 M_L_CPU1_SB_DQS_DP<6>                                             
P  NNAMEm5033 M_L_CPU1_SB_DQS_DP<5>                                             
P  NNAMEm5034 M_L_CPU1_SB_DQS_DP<4>                                             
P  NNAMEm5035 M_L_CPU1_SB_DQS_DP<3>                                             
P  NNAMEm5036 M_L_CPU1_SB_DQS_DP<2>                                             
P  NNAMEm5037 M_L_CPU1_SB_DQS_DP<1>                                             
P  NNAMEm5038 M_L_CPU1_SB_DQS_DP<0>                                             
P  NNAMEm5039 M_L_CPU1_SB_DQS_DN<9>                                             
P  NNAMEm5040 M_L_CPU1_SB_DQS_DN<8>                                             
P  NNAMEm5041 M_L_CPU1_SB_DQS_DN<7>                                             
P  NNAMEm5042 M_L_CPU1_SB_DQS_DN<6>                                             
P  NNAMEm5043 M_L_CPU1_SB_DQS_DN<5>                                             
P  NNAMEm5044 M_L_CPU1_SB_DQS_DN<4>                                             
P  NNAMEm5045 M_L_CPU1_SB_DQS_DN<3>                                             
P  NNAMEm5046 M_L_CPU1_SB_DQS_DN<2>                                             
P  NNAMEm5047 M_L_CPU1_SB_DQS_DN<1>                                             
P  NNAMEm5048 M_L_CPU1_SB_DQS_DN<0>                                             
P  NNAMEm5049 M_L_CPU1_SB_DQ<9>                                                 
P  NNAMEm5050 M_L_CPU1_SB_DQ<8>                                                 
P  NNAMEm5051 M_L_CPU1_SB_DQ<7>                                                 
P  NNAMEm5052 M_L_CPU1_SB_DQ<6>                                                 
P  NNAMEm5053 M_L_CPU1_SB_DQ<5>                                                 
P  NNAMEm5054 M_L_CPU1_SB_DQ<4>                                                 
P  NNAMEm5055 M_L_CPU1_SB_DQ<3>                                                 
P  NNAMEm5056 M_L_CPU1_SB_DQ<31>                                                
P  NNAMEm5057 M_L_CPU1_SB_DQ<30>                                                
P  NNAMEm5058 M_L_CPU1_SB_DQ<2>                                                 
P  NNAMEm5059 M_L_CPU1_SB_DQ<29>                                                
P  NNAMEm5060 M_L_CPU1_SB_DQ<28>                                                
P  NNAMEm5061 M_L_CPU1_SB_DQ<27>                                                
P  NNAMEm5062 M_L_CPU1_SB_DQ<26>                                                
P  NNAMEm5063 M_L_CPU1_SB_DQ<25>                                                
P  NNAMEm5064 M_L_CPU1_SB_DQ<24>                                                
P  NNAMEm5065 M_L_CPU1_SB_DQ<23>                                                
P  NNAMEm5066 M_L_CPU1_SB_DQ<22>                                                
P  NNAMEm5067 M_L_CPU1_SB_DQ<21>                                                
P  NNAMEm5068 M_L_CPU1_SB_DQ<20>                                                
P  NNAMEm5069 M_L_CPU1_SB_DQ<1>                                                 
P  NNAMEm5070 M_L_CPU1_SB_DQ<19>                                                
P  NNAMEm5071 M_L_CPU1_SB_DQ<18>                                                
P  NNAMEm5072 M_L_CPU1_SB_DQ<17>                                                
P  NNAMEm5073 M_L_CPU1_SB_DQ<16>                                                
P  NNAMEm5074 M_L_CPU1_SB_DQ<15>                                                
P  NNAMEm5075 M_L_CPU1_SB_DQ<14>                                                
P  NNAMEm5076 M_L_CPU1_SB_DQ<13>                                                
P  NNAMEm5077 M_L_CPU1_SB_DQ<12>                                                
P  NNAMEm5078 M_L_CPU1_SB_DQ<11>                                                
P  NNAMEm5079 M_L_CPU1_SB_DQ<10>                                                
P  NNAMEm5080 M_L_CPU1_SB_DQ<0>                                                 
P  NNAMEm5081 M_L_CPU1_SB_CS_N<1>                                               
P  NNAMEm5082 M_L_CPU1_SB_CS_N<0>                                               
P  NNAMEm5083 M_L_CPU1_SB_CB<7>                                                 
P  NNAMEm5084 M_L_CPU1_SB_CB<6>                                                 
P  NNAMEm5085 M_L_CPU1_SB_CB<5>                                                 
P  NNAMEm5086 M_L_CPU1_SB_CB<4>                                                 
P  NNAMEm5087 M_L_CPU1_SB_CB<3>                                                 
P  NNAMEm5088 M_L_CPU1_SB_CB<2>                                                 
P  NNAMEm5089 M_L_CPU1_SB_CB<1>                                                 
P  NNAMEm5090 M_L_CPU1_SB_CB<0>                                                 
P  NNAMEm5091 M_L_CPU1_SB_CA<6>                                                 
P  NNAMEm5092 M_L_CPU1_SB_CA<5>                                                 
P  NNAMEm5093 M_L_CPU1_SB_CA<4>                                                 
P  NNAMEm5094 M_L_CPU1_SB_CA<3>                                                 
P  NNAMEm5095 M_L_CPU1_SB_CA<2>                                                 
P  NNAMEm5096 M_L_CPU1_SB_CA<1>                                                 
P  NNAMEm5097 M_L_CPU1_SB_CA<0>                                                 
P  NNAMEm5098 M_L_CPU1_SA_RSP<0>                                                
P  NNAMEm5099 M_L_CPU1_SA_PAR                                                   
P  NNAMEm5100 M_L_CPU1_SA_DQS_DP<9>                                             
P  NNAMEm5101 M_L_CPU1_SA_DQS_DP<8>                                             
P  NNAMEm5102 M_L_CPU1_SA_DQS_DP<7>                                             
P  NNAMEm5103 M_L_CPU1_SA_DQS_DP<6>                                             
P  NNAMEm5104 M_L_CPU1_SA_DQS_DP<5>                                             
P  NNAMEm5105 M_L_CPU1_SA_DQS_DP<4>                                             
P  NNAMEm5106 M_L_CPU1_SA_DQS_DP<3>                                             
P  NNAMEm5107 M_L_CPU1_SA_DQS_DP<2>                                             
P  NNAMEm5108 M_L_CPU1_SA_DQS_DP<1>                                             
P  NNAMEm5109 M_L_CPU1_SA_DQS_DP<0>                                             
P  NNAMEm5110 M_L_CPU1_SA_DQS_DN<9>                                             
P  NNAMEm5111 M_L_CPU1_SA_DQS_DN<8>                                             
P  NNAMEm5112 M_L_CPU1_SA_DQS_DN<7>                                             
P  NNAMEm5113 M_L_CPU1_SA_DQS_DN<6>                                             
P  NNAMEm5114 M_L_CPU1_SA_DQS_DN<5>                                             
P  NNAMEm5115 M_L_CPU1_SA_DQS_DN<4>                                             
P  NNAMEm5116 M_L_CPU1_SA_DQS_DN<3>                                             
P  NNAMEm5117 M_L_CPU1_SA_DQS_DN<2>                                             
P  NNAMEm5118 M_L_CPU1_SA_DQS_DN<1>                                             
P  NNAMEm5119 M_L_CPU1_SA_DQS_DN<0>                                             
P  NNAMEm5120 M_L_CPU1_SA_DQ<9>                                                 
P  NNAMEm5121 M_L_CPU1_SA_DQ<8>                                                 
P  NNAMEm5122 M_L_CPU1_SA_DQ<7>                                                 
P  NNAMEm5123 M_L_CPU1_SA_DQ<6>                                                 
P  NNAMEm5124 M_L_CPU1_SA_DQ<5>                                                 
P  NNAMEm5125 M_L_CPU1_SA_DQ<4>                                                 
P  NNAMEm5126 M_L_CPU1_SA_DQ<3>                                                 
P  NNAMEm5127 M_L_CPU1_SA_DQ<31>                                                
P  NNAMEm5128 M_L_CPU1_SA_DQ<30>                                                
P  NNAMEm5129 M_L_CPU1_SA_DQ<2>                                                 
P  NNAMEm5130 M_L_CPU1_SA_DQ<29>                                                
P  NNAMEm5131 M_L_CPU1_SA_DQ<28>                                                
P  NNAMEm5132 M_L_CPU1_SA_DQ<27>                                                
P  NNAMEm5133 M_L_CPU1_SA_DQ<26>                                                
P  NNAMEm5134 M_L_CPU1_SA_DQ<25>                                                
P  NNAMEm5135 M_L_CPU1_SA_DQ<24>                                                
P  NNAMEm5136 M_L_CPU1_SA_DQ<23>                                                
P  NNAMEm5137 M_L_CPU1_SA_DQ<22>                                                
P  NNAMEm5138 M_L_CPU1_SA_DQ<21>                                                
P  NNAMEm5139 M_L_CPU1_SA_DQ<20>                                                
P  NNAMEm5140 M_L_CPU1_SA_DQ<1>                                                 
P  NNAMEm5141 M_L_CPU1_SA_DQ<19>                                                
P  NNAMEm5142 M_L_CPU1_SA_DQ<18>                                                
P  NNAMEm5143 M_L_CPU1_SA_DQ<17>                                                
P  NNAMEm5144 M_L_CPU1_SA_DQ<16>                                                
P  NNAMEm5145 M_L_CPU1_SA_DQ<15>                                                
P  NNAMEm5146 M_L_CPU1_SA_DQ<14>                                                
P  NNAMEm5147 M_L_CPU1_SA_DQ<13>                                                
P  NNAMEm5148 M_L_CPU1_SA_DQ<12>                                                
P  NNAMEm5149 M_L_CPU1_SA_DQ<11>                                                
P  NNAMEm5150 M_L_CPU1_SA_DQ<10>                                                
P  NNAMEm5151 M_L_CPU1_SA_DQ<0>                                                 
P  NNAMEm5152 M_L_CPU1_SA_CS_N<1>                                               
P  NNAMEm5153 M_L_CPU1_SA_CS_N<0>                                               
P  NNAMEm5154 M_L_CPU1_SA_CB<7>                                                 
P  NNAMEm5155 M_L_CPU1_SA_CB<6>                                                 
P  NNAMEm5156 M_L_CPU1_SA_CB<5>                                                 
P  NNAMEm5157 M_L_CPU1_SA_CB<4>                                                 
P  NNAMEm5158 M_L_CPU1_SA_CB<3>                                                 
P  NNAMEm5159 M_L_CPU1_SA_CB<2>                                                 
P  NNAMEm5160 M_L_CPU1_SA_CB<1>                                                 
P  NNAMEm5161 M_L_CPU1_SA_CB<0>                                                 
P  NNAMEm5162 M_L_CPU1_SA_CA<6>                                                 
P  NNAMEm5163 M_L_CPU1_SA_CA<5>                                                 
P  NNAMEm5164 M_L_CPU1_SA_CA<4>                                                 
P  NNAMEm5165 M_L_CPU1_SA_CA<3>                                                 
P  NNAMEm5166 M_L_CPU1_SA_CA<2>                                                 
P  NNAMEm5167 M_L_CPU1_SA_CA<1>                                                 
P  NNAMEm5168 M_L_CPU1_SA_CA<0>                                                 
P  NNAMEm5169 M_L_CPU1_RESET_N                                                  
P  NNAMEm5170 M_L_CPU1_CLK_DP<0>                                                
P  NNAMEm5171 M_L_CPU1_CLK_DN<0>                                                
P  NNAMEm5172 M_L_CPU1_ALERT_R_N                                                
P  NNAMEm5173 M_L_CPU1_ALERT_N                                                  
P  NNAMEm5174 M_L_CPU0_SB_RSP<0>                                                
P  NNAMEm5175 M_L_CPU0_SB_PAR                                                   
P  NNAMEm5176 M_L_CPU0_SB_DQS_DP<9>                                             
P  NNAMEm5177 M_L_CPU0_SB_DQS_DP<8>                                             
P  NNAMEm5178 M_L_CPU0_SB_DQS_DP<7>                                             
P  NNAMEm5179 M_L_CPU0_SB_DQS_DP<6>                                             
P  NNAMEm5180 M_L_CPU0_SB_DQS_DP<5>                                             
P  NNAMEm5181 M_L_CPU0_SB_DQS_DP<4>                                             
P  NNAMEm5182 M_L_CPU0_SB_DQS_DP<3>                                             
P  NNAMEm5183 M_L_CPU0_SB_DQS_DP<2>                                             
P  NNAMEm5184 M_L_CPU0_SB_DQS_DP<1>                                             
P  NNAMEm5185 M_L_CPU0_SB_DQS_DP<0>                                             
P  NNAMEm5186 M_L_CPU0_SB_DQS_DN<9>                                             
P  NNAMEm5187 M_L_CPU0_SB_DQS_DN<8>                                             
P  NNAMEm5188 M_L_CPU0_SB_DQS_DN<7>                                             
P  NNAMEm5189 M_L_CPU0_SB_DQS_DN<6>                                             
P  NNAMEm5190 M_L_CPU0_SB_DQS_DN<5>                                             
P  NNAMEm5191 M_L_CPU0_SB_DQS_DN<4>                                             
P  NNAMEm5192 M_L_CPU0_SB_DQS_DN<3>                                             
P  NNAMEm5193 M_L_CPU0_SB_DQS_DN<2>                                             
P  NNAMEm5194 M_L_CPU0_SB_DQS_DN<1>                                             
P  NNAMEm5195 M_L_CPU0_SB_DQS_DN<0>                                             
P  NNAMEm5196 M_L_CPU0_SB_DQ<9>                                                 
P  NNAMEm5197 M_L_CPU0_SB_DQ<8>                                                 
P  NNAMEm5198 M_L_CPU0_SB_DQ<7>                                                 
P  NNAMEm5199 M_L_CPU0_SB_DQ<6>                                                 
P  NNAMEm5200 M_L_CPU0_SB_DQ<5>                                                 
P  NNAMEm5201 M_L_CPU0_SB_DQ<4>                                                 
P  NNAMEm5202 M_L_CPU0_SB_DQ<3>                                                 
P  NNAMEm5203 M_L_CPU0_SB_DQ<31>                                                
P  NNAMEm5204 M_L_CPU0_SB_DQ<30>                                                
P  NNAMEm5205 M_L_CPU0_SB_DQ<2>                                                 
P  NNAMEm5206 M_L_CPU0_SB_DQ<29>                                                
P  NNAMEm5207 M_L_CPU0_SB_DQ<28>                                                
P  NNAMEm5208 M_L_CPU0_SB_DQ<27>                                                
P  NNAMEm5209 M_L_CPU0_SB_DQ<26>                                                
P  NNAMEm5210 M_L_CPU0_SB_DQ<25>                                                
P  NNAMEm5211 M_L_CPU0_SB_DQ<24>                                                
P  NNAMEm5212 M_L_CPU0_SB_DQ<23>                                                
P  NNAMEm5213 M_L_CPU0_SB_DQ<22>                                                
P  NNAMEm5214 M_L_CPU0_SB_DQ<21>                                                
P  NNAMEm5215 M_L_CPU0_SB_DQ<20>                                                
P  NNAMEm5216 M_L_CPU0_SB_DQ<1>                                                 
P  NNAMEm5217 M_L_CPU0_SB_DQ<19>                                                
P  NNAMEm5218 M_L_CPU0_SB_DQ<18>                                                
P  NNAMEm5219 M_L_CPU0_SB_DQ<17>                                                
P  NNAMEm5220 M_L_CPU0_SB_DQ<16>                                                
P  NNAMEm5221 M_L_CPU0_SB_DQ<15>                                                
P  NNAMEm5222 M_L_CPU0_SB_DQ<14>                                                
P  NNAMEm5223 M_L_CPU0_SB_DQ<13>                                                
P  NNAMEm5224 M_L_CPU0_SB_DQ<12>                                                
P  NNAMEm5225 M_L_CPU0_SB_DQ<11>                                                
P  NNAMEm5226 M_L_CPU0_SB_DQ<10>                                                
P  NNAMEm5227 M_L_CPU0_SB_DQ<0>                                                 
P  NNAMEm5228 M_L_CPU0_SB_CS_N<1>                                               
P  NNAMEm5229 M_L_CPU0_SB_CS_N<0>                                               
P  NNAMEm5230 M_L_CPU0_SB_CB<7>                                                 
P  NNAMEm5231 M_L_CPU0_SB_CB<6>                                                 
P  NNAMEm5232 M_L_CPU0_SB_CB<5>                                                 
P  NNAMEm5233 M_L_CPU0_SB_CB<4>                                                 
P  NNAMEm5234 M_L_CPU0_SB_CB<3>                                                 
P  NNAMEm5235 M_L_CPU0_SB_CB<2>                                                 
P  NNAMEm5236 M_L_CPU0_SB_CB<1>                                                 
P  NNAMEm5237 M_L_CPU0_SB_CB<0>                                                 
P  NNAMEm5238 M_L_CPU0_SB_CA<6>                                                 
P  NNAMEm5239 M_L_CPU0_SB_CA<5>                                                 
P  NNAMEm5240 M_L_CPU0_SB_CA<4>                                                 
P  NNAMEm5241 M_L_CPU0_SB_CA<3>                                                 
P  NNAMEm5242 M_L_CPU0_SB_CA<2>                                                 
P  NNAMEm5243 M_L_CPU0_SB_CA<1>                                                 
P  NNAMEm5244 M_L_CPU0_SB_CA<0>                                                 
P  NNAMEm5245 M_L_CPU0_SA_RSP<0>                                                
P  NNAMEm5246 M_L_CPU0_SA_PAR                                                   
P  NNAMEm5247 M_L_CPU0_SA_DQS_DP<9>                                             
P  NNAMEm5248 M_L_CPU0_SA_DQS_DP<8>                                             
P  NNAMEm5249 M_L_CPU0_SA_DQS_DP<7>                                             
P  NNAMEm5250 M_L_CPU0_SA_DQS_DP<6>                                             
P  NNAMEm5251 M_L_CPU0_SA_DQS_DP<5>                                             
P  NNAMEm5252 M_L_CPU0_SA_DQS_DP<4>                                             
P  NNAMEm5253 M_L_CPU0_SA_DQS_DP<3>                                             
P  NNAMEm5254 M_L_CPU0_SA_DQS_DP<2>                                             
P  NNAMEm5255 M_L_CPU0_SA_DQS_DP<1>                                             
P  NNAMEm5256 M_L_CPU0_SA_DQS_DP<0>                                             
P  NNAMEm5257 M_L_CPU0_SA_DQS_DN<9>                                             
P  NNAMEm5258 M_L_CPU0_SA_DQS_DN<8>                                             
P  NNAMEm5259 M_L_CPU0_SA_DQS_DN<7>                                             
P  NNAMEm5260 M_L_CPU0_SA_DQS_DN<6>                                             
P  NNAMEm5261 M_L_CPU0_SA_DQS_DN<5>                                             
P  NNAMEm5262 M_L_CPU0_SA_DQS_DN<4>                                             
P  NNAMEm5263 M_L_CPU0_SA_DQS_DN<3>                                             
P  NNAMEm5264 M_L_CPU0_SA_DQS_DN<2>                                             
P  NNAMEm5265 M_L_CPU0_SA_DQS_DN<1>                                             
P  NNAMEm5266 M_L_CPU0_SA_DQS_DN<0>                                             
P  NNAMEm5267 M_L_CPU0_SA_DQ<9>                                                 
P  NNAMEm5268 M_L_CPU0_SA_DQ<8>                                                 
P  NNAMEm5269 M_L_CPU0_SA_DQ<7>                                                 
P  NNAMEm5270 M_L_CPU0_SA_DQ<6>                                                 
P  NNAMEm5271 M_L_CPU0_SA_DQ<5>                                                 
P  NNAMEm5272 M_L_CPU0_SA_DQ<4>                                                 
P  NNAMEm5273 M_L_CPU0_SA_DQ<3>                                                 
P  NNAMEm5274 M_L_CPU0_SA_DQ<31>                                                
P  NNAMEm5275 M_L_CPU0_SA_DQ<30>                                                
P  NNAMEm5276 M_L_CPU0_SA_DQ<2>                                                 
P  NNAMEm5277 M_L_CPU0_SA_DQ<29>                                                
P  NNAMEm5278 M_L_CPU0_SA_DQ<28>                                                
P  NNAMEm5279 M_L_CPU0_SA_DQ<27>                                                
P  NNAMEm5280 M_L_CPU0_SA_DQ<26>                                                
P  NNAMEm5281 M_L_CPU0_SA_DQ<25>                                                
P  NNAMEm5282 M_L_CPU0_SA_DQ<24>                                                
P  NNAMEm5283 M_L_CPU0_SA_DQ<23>                                                
P  NNAMEm5284 M_L_CPU0_SA_DQ<22>                                                
P  NNAMEm5285 M_L_CPU0_SA_DQ<21>                                                
P  NNAMEm5286 M_L_CPU0_SA_DQ<20>                                                
P  NNAMEm5287 M_L_CPU0_SA_DQ<1>                                                 
P  NNAMEm5288 M_L_CPU0_SA_DQ<19>                                                
P  NNAMEm5289 M_L_CPU0_SA_DQ<18>                                                
P  NNAMEm5290 M_L_CPU0_SA_DQ<17>                                                
P  NNAMEm5291 M_L_CPU0_SA_DQ<16>                                                
P  NNAMEm5292 M_L_CPU0_SA_DQ<15>                                                
P  NNAMEm5293 M_L_CPU0_SA_DQ<14>                                                
P  NNAMEm5294 M_L_CPU0_SA_DQ<13>                                                
P  NNAMEm5295 M_L_CPU0_SA_DQ<12>                                                
P  NNAMEm5296 M_L_CPU0_SA_DQ<11>                                                
P  NNAMEm5297 M_L_CPU0_SA_DQ<10>                                                
P  NNAMEm5298 M_L_CPU0_SA_DQ<0>                                                 
P  NNAMEm5299 M_L_CPU0_SA_CS_N<1>                                               
P  NNAMEm5300 M_L_CPU0_SA_CS_N<0>                                               
P  NNAMEm5301 M_L_CPU0_SA_CB<7>                                                 
P  NNAMEm5302 M_L_CPU0_SA_CB<6>                                                 
P  NNAMEm5303 M_L_CPU0_SA_CB<5>                                                 
P  NNAMEm5304 M_L_CPU0_SA_CB<4>                                                 
P  NNAMEm5305 M_L_CPU0_SA_CB<3>                                                 
P  NNAMEm5306 M_L_CPU0_SA_CB<2>                                                 
P  NNAMEm5307 M_L_CPU0_SA_CB<1>                                                 
P  NNAMEm5308 M_L_CPU0_SA_CB<0>                                                 
P  NNAMEm5309 M_L_CPU0_SA_CA<6>                                                 
P  NNAMEm5310 M_L_CPU0_SA_CA<5>                                                 
P  NNAMEm5311 M_L_CPU0_SA_CA<4>                                                 
P  NNAMEm5312 M_L_CPU0_SA_CA<3>                                                 
P  NNAMEm5313 M_L_CPU0_SA_CA<2>                                                 
P  NNAMEm5314 M_L_CPU0_SA_CA<1>                                                 
P  NNAMEm5315 M_L_CPU0_SA_CA<0>                                                 
P  NNAMEm5316 M_L_CPU0_RESET_N                                                  
P  NNAMEm5317 M_L_CPU0_CLK_DP<0>                                                
P  NNAMEm5318 M_L_CPU0_CLK_DN<0>                                                
P  NNAMEm5319 M_L_CPU0_ALERT_R_N                                                
P  NNAMEm5320 M_L_CPU0_ALERT_N                                                  
P  NNAMEm5321 M_K_CPU1_SB_RSP<0>                                                
P  NNAMEm5322 M_K_CPU1_SB_PAR                                                   
P  NNAMEm5323 M_K_CPU1_SB_DQS_DP<9>                                             
P  NNAMEm5324 M_K_CPU1_SB_DQS_DP<8>                                             
P  NNAMEm5325 M_K_CPU1_SB_DQS_DP<7>                                             
P  NNAMEm5326 M_K_CPU1_SB_DQS_DP<6>                                             
P  NNAMEm5327 M_K_CPU1_SB_DQS_DP<5>                                             
P  NNAMEm5328 M_K_CPU1_SB_DQS_DP<4>                                             
P  NNAMEm5329 M_K_CPU1_SB_DQS_DP<3>                                             
P  NNAMEm5330 M_K_CPU1_SB_DQS_DP<2>                                             
P  NNAMEm5331 M_K_CPU1_SB_DQS_DP<1>                                             
P  NNAMEm5332 M_K_CPU1_SB_DQS_DP<0>                                             
P  NNAMEm5333 M_K_CPU1_SB_DQS_DN<9>                                             
P  NNAMEm5334 M_K_CPU1_SB_DQS_DN<8>                                             
P  NNAMEm5335 M_K_CPU1_SB_DQS_DN<7>                                             
P  NNAMEm5336 M_K_CPU1_SB_DQS_DN<6>                                             
P  NNAMEm5337 M_K_CPU1_SB_DQS_DN<5>                                             
P  NNAMEm5338 M_K_CPU1_SB_DQS_DN<4>                                             
P  NNAMEm5339 M_K_CPU1_SB_DQS_DN<3>                                             
P  NNAMEm5340 M_K_CPU1_SB_DQS_DN<2>                                             
P  NNAMEm5341 M_K_CPU1_SB_DQS_DN<1>                                             
P  NNAMEm5342 M_K_CPU1_SB_DQS_DN<0>                                             
P  NNAMEm5343 M_K_CPU1_SB_DQ<9>                                                 
P  NNAMEm5344 M_K_CPU1_SB_DQ<8>                                                 
P  NNAMEm5345 M_K_CPU1_SB_DQ<7>                                                 
P  NNAMEm5346 M_K_CPU1_SB_DQ<6>                                                 
P  NNAMEm5347 M_K_CPU1_SB_DQ<5>                                                 
P  NNAMEm5348 M_K_CPU1_SB_DQ<4>                                                 
P  NNAMEm5349 M_K_CPU1_SB_DQ<3>                                                 
P  NNAMEm5350 M_K_CPU1_SB_DQ<31>                                                
P  NNAMEm5351 M_K_CPU1_SB_DQ<30>                                                
P  NNAMEm5352 M_K_CPU1_SB_DQ<2>                                                 
P  NNAMEm5353 M_K_CPU1_SB_DQ<29>                                                
P  NNAMEm5354 M_K_CPU1_SB_DQ<28>                                                
P  NNAMEm5355 M_K_CPU1_SB_DQ<27>                                                
P  NNAMEm5356 M_K_CPU1_SB_DQ<26>                                                
P  NNAMEm5357 M_K_CPU1_SB_DQ<25>                                                
P  NNAMEm5358 M_K_CPU1_SB_DQ<24>                                                
P  NNAMEm5359 M_K_CPU1_SB_DQ<23>                                                
P  NNAMEm5360 M_K_CPU1_SB_DQ<22>                                                
P  NNAMEm5361 M_K_CPU1_SB_DQ<21>                                                
P  NNAMEm5362 M_K_CPU1_SB_DQ<20>                                                
P  NNAMEm5363 M_K_CPU1_SB_DQ<1>                                                 
P  NNAMEm5364 M_K_CPU1_SB_DQ<19>                                                
P  NNAMEm5365 M_K_CPU1_SB_DQ<18>                                                
P  NNAMEm5366 M_K_CPU1_SB_DQ<17>                                                
P  NNAMEm5367 M_K_CPU1_SB_DQ<16>                                                
P  NNAMEm5368 M_K_CPU1_SB_DQ<15>                                                
P  NNAMEm5369 M_K_CPU1_SB_DQ<14>                                                
P  NNAMEm5370 M_K_CPU1_SB_DQ<13>                                                
P  NNAMEm5371 M_K_CPU1_SB_DQ<12>                                                
P  NNAMEm5372 M_K_CPU1_SB_DQ<11>                                                
P  NNAMEm5373 M_K_CPU1_SB_DQ<10>                                                
P  NNAMEm5374 M_K_CPU1_SB_DQ<0>                                                 
P  NNAMEm5375 M_K_CPU1_SB_CS_N<1>                                               
P  NNAMEm5376 M_K_CPU1_SB_CS_N<0>                                               
P  NNAMEm5377 M_K_CPU1_SB_CB<7>                                                 
P  NNAMEm5378 M_K_CPU1_SB_CB<6>                                                 
P  NNAMEm5379 M_K_CPU1_SB_CB<5>                                                 
P  NNAMEm5380 M_K_CPU1_SB_CB<4>                                                 
P  NNAMEm5381 M_K_CPU1_SB_CB<3>                                                 
P  NNAMEm5382 M_K_CPU1_SB_CB<2>                                                 
P  NNAMEm5383 M_K_CPU1_SB_CB<1>                                                 
P  NNAMEm5384 M_K_CPU1_SB_CB<0>                                                 
P  NNAMEm5385 M_K_CPU1_SB_CA<6>                                                 
P  NNAMEm5386 M_K_CPU1_SB_CA<5>                                                 
P  NNAMEm5387 M_K_CPU1_SB_CA<4>                                                 
P  NNAMEm5388 M_K_CPU1_SB_CA<3>                                                 
P  NNAMEm5389 M_K_CPU1_SB_CA<2>                                                 
P  NNAMEm5390 M_K_CPU1_SB_CA<1>                                                 
P  NNAMEm5391 M_K_CPU1_SB_CA<0>                                                 
P  NNAMEm5392 M_K_CPU1_SA_RSP<0>                                                
P  NNAMEm5393 M_K_CPU1_SA_PAR                                                   
P  NNAMEm5394 M_K_CPU1_SA_DQS_DP<9>                                             
P  NNAMEm5395 M_K_CPU1_SA_DQS_DP<8>                                             
P  NNAMEm5396 M_K_CPU1_SA_DQS_DP<7>                                             
P  NNAMEm5397 M_K_CPU1_SA_DQS_DP<6>                                             
P  NNAMEm5398 M_K_CPU1_SA_DQS_DP<5>                                             
P  NNAMEm5399 M_K_CPU1_SA_DQS_DP<4>                                             
P  NNAMEm5400 M_K_CPU1_SA_DQS_DP<3>                                             
P  NNAMEm5401 M_K_CPU1_SA_DQS_DP<2>                                             
P  NNAMEm5402 M_K_CPU1_SA_DQS_DP<1>                                             
P  NNAMEm5403 M_K_CPU1_SA_DQS_DP<0>                                             
P  NNAMEm5404 M_K_CPU1_SA_DQS_DN<9>                                             
P  NNAMEm5405 M_K_CPU1_SA_DQS_DN<8>                                             
P  NNAMEm5406 M_K_CPU1_SA_DQS_DN<7>                                             
P  NNAMEm5407 M_K_CPU1_SA_DQS_DN<6>                                             
P  NNAMEm5408 M_K_CPU1_SA_DQS_DN<5>                                             
P  NNAMEm5409 M_K_CPU1_SA_DQS_DN<4>                                             
P  NNAMEm5410 M_K_CPU1_SA_DQS_DN<3>                                             
P  NNAMEm5411 M_K_CPU1_SA_DQS_DN<2>                                             
P  NNAMEm5412 M_K_CPU1_SA_DQS_DN<1>                                             
P  NNAMEm5413 M_K_CPU1_SA_DQS_DN<0>                                             
P  NNAMEm5414 M_K_CPU1_SA_DQ<9>                                                 
P  NNAMEm5415 M_K_CPU1_SA_DQ<8>                                                 
P  NNAMEm5416 M_K_CPU1_SA_DQ<7>                                                 
P  NNAMEm5417 M_K_CPU1_SA_DQ<6>                                                 
P  NNAMEm5418 M_K_CPU1_SA_DQ<5>                                                 
P  NNAMEm5419 M_K_CPU1_SA_DQ<4>                                                 
P  NNAMEm5420 M_K_CPU1_SA_DQ<3>                                                 
P  NNAMEm5421 M_K_CPU1_SA_DQ<31>                                                
P  NNAMEm5422 M_K_CPU1_SA_DQ<30>                                                
P  NNAMEm5423 M_K_CPU1_SA_DQ<2>                                                 
P  NNAMEm5424 M_K_CPU1_SA_DQ<29>                                                
P  NNAMEm5425 M_K_CPU1_SA_DQ<28>                                                
P  NNAMEm5426 M_K_CPU1_SA_DQ<27>                                                
P  NNAMEm5427 M_K_CPU1_SA_DQ<26>                                                
P  NNAMEm5428 M_K_CPU1_SA_DQ<25>                                                
P  NNAMEm5429 M_K_CPU1_SA_DQ<24>                                                
P  NNAMEm5430 M_K_CPU1_SA_DQ<23>                                                
P  NNAMEm5431 M_K_CPU1_SA_DQ<22>                                                
P  NNAMEm5432 M_K_CPU1_SA_DQ<21>                                                
P  NNAMEm5433 M_K_CPU1_SA_DQ<20>                                                
P  NNAMEm5434 M_K_CPU1_SA_DQ<1>                                                 
P  NNAMEm5435 M_K_CPU1_SA_DQ<19>                                                
P  NNAMEm5436 M_K_CPU1_SA_DQ<18>                                                
P  NNAMEm5437 M_K_CPU1_SA_DQ<17>                                                
P  NNAMEm5438 M_K_CPU1_SA_DQ<16>                                                
P  NNAMEm5439 M_K_CPU1_SA_DQ<15>                                                
P  NNAMEm5440 M_K_CPU1_SA_DQ<14>                                                
P  NNAMEm5441 M_K_CPU1_SA_DQ<13>                                                
P  NNAMEm5442 M_K_CPU1_SA_DQ<12>                                                
P  NNAMEm5443 M_K_CPU1_SA_DQ<11>                                                
P  NNAMEm5444 M_K_CPU1_SA_DQ<10>                                                
P  NNAMEm5445 M_K_CPU1_SA_DQ<0>                                                 
P  NNAMEm5446 M_K_CPU1_SA_CS_N<1>                                               
P  NNAMEm5447 M_K_CPU1_SA_CS_N<0>                                               
P  NNAMEm5448 M_K_CPU1_SA_CB<7>                                                 
P  NNAMEm5449 M_K_CPU1_SA_CB<6>                                                 
P  NNAMEm5450 M_K_CPU1_SA_CB<5>                                                 
P  NNAMEm5451 M_K_CPU1_SA_CB<4>                                                 
P  NNAMEm5452 M_K_CPU1_SA_CB<3>                                                 
P  NNAMEm5453 M_K_CPU1_SA_CB<2>                                                 
P  NNAMEm5454 M_K_CPU1_SA_CB<1>                                                 
P  NNAMEm5455 M_K_CPU1_SA_CB<0>                                                 
P  NNAMEm5456 M_K_CPU1_SA_CA<6>                                                 
P  NNAMEm5457 M_K_CPU1_SA_CA<5>                                                 
P  NNAMEm5458 M_K_CPU1_SA_CA<4>                                                 
P  NNAMEm5459 M_K_CPU1_SA_CA<3>                                                 
P  NNAMEm5460 M_K_CPU1_SA_CA<2>                                                 
P  NNAMEm5461 M_K_CPU1_SA_CA<1>                                                 
P  NNAMEm5462 M_K_CPU1_SA_CA<0>                                                 
P  NNAMEm5463 M_K_CPU1_RESET_N                                                  
P  NNAMEm5464 M_K_CPU1_CLK_DP<0>                                                
P  NNAMEm5465 M_K_CPU1_CLK_DN<0>                                                
P  NNAMEm5466 M_K_CPU1_ALERT_R_N                                                
P  NNAMEm5467 M_K_CPU1_ALERT_N                                                  
P  NNAMEm5468 M_K_CPU0_SB_RSP<0>                                                
P  NNAMEm5469 M_K_CPU0_SB_PAR                                                   
P  NNAMEm5470 M_K_CPU0_SB_DQS_DP<9>                                             
P  NNAMEm5471 M_K_CPU0_SB_DQS_DP<8>                                             
P  NNAMEm5472 M_K_CPU0_SB_DQS_DP<7>                                             
P  NNAMEm5473 M_K_CPU0_SB_DQS_DP<6>                                             
P  NNAMEm5474 M_K_CPU0_SB_DQS_DP<5>                                             
P  NNAMEm5475 M_K_CPU0_SB_DQS_DP<4>                                             
P  NNAMEm5476 M_K_CPU0_SB_DQS_DP<3>                                             
P  NNAMEm5477 M_K_CPU0_SB_DQS_DP<2>                                             
P  NNAMEm5478 M_K_CPU0_SB_DQS_DP<1>                                             
P  NNAMEm5479 M_K_CPU0_SB_DQS_DP<0>                                             
P  NNAMEm5480 M_K_CPU0_SB_DQS_DN<9>                                             
P  NNAMEm5481 M_K_CPU0_SB_DQS_DN<8>                                             
P  NNAMEm5482 M_K_CPU0_SB_DQS_DN<7>                                             
P  NNAMEm5483 M_K_CPU0_SB_DQS_DN<6>                                             
P  NNAMEm5484 M_K_CPU0_SB_DQS_DN<5>                                             
P  NNAMEm5485 M_K_CPU0_SB_DQS_DN<4>                                             
P  NNAMEm5486 M_K_CPU0_SB_DQS_DN<3>                                             
P  NNAMEm5487 M_K_CPU0_SB_DQS_DN<2>                                             
P  NNAMEm5488 M_K_CPU0_SB_DQS_DN<1>                                             
P  NNAMEm5489 M_K_CPU0_SB_DQS_DN<0>                                             
P  NNAMEm5490 M_K_CPU0_SB_DQ<9>                                                 
P  NNAMEm5491 M_K_CPU0_SB_DQ<8>                                                 
P  NNAMEm5492 M_K_CPU0_SB_DQ<7>                                                 
P  NNAMEm5493 M_K_CPU0_SB_DQ<6>                                                 
P  NNAMEm5494 M_K_CPU0_SB_DQ<5>                                                 
P  NNAMEm5495 M_K_CPU0_SB_DQ<4>                                                 
P  NNAMEm5496 M_K_CPU0_SB_DQ<3>                                                 
P  NNAMEm5497 M_K_CPU0_SB_DQ<31>                                                
P  NNAMEm5498 M_K_CPU0_SB_DQ<30>                                                
P  NNAMEm5499 M_K_CPU0_SB_DQ<2>                                                 
P  NNAMEm5500 M_K_CPU0_SB_DQ<29>                                                
P  NNAMEm5501 M_K_CPU0_SB_DQ<28>                                                
P  NNAMEm5502 M_K_CPU0_SB_DQ<27>                                                
P  NNAMEm5503 M_K_CPU0_SB_DQ<26>                                                
P  NNAMEm5504 M_K_CPU0_SB_DQ<25>                                                
P  NNAMEm5505 M_K_CPU0_SB_DQ<24>                                                
P  NNAMEm5506 M_K_CPU0_SB_DQ<23>                                                
P  NNAMEm5507 M_K_CPU0_SB_DQ<22>                                                
P  NNAMEm5508 M_K_CPU0_SB_DQ<21>                                                
P  NNAMEm5509 M_K_CPU0_SB_DQ<20>                                                
P  NNAMEm5510 M_K_CPU0_SB_DQ<1>                                                 
P  NNAMEm5511 M_K_CPU0_SB_DQ<19>                                                
P  NNAMEm5512 M_K_CPU0_SB_DQ<18>                                                
P  NNAMEm5513 M_K_CPU0_SB_DQ<17>                                                
P  NNAMEm5514 M_K_CPU0_SB_DQ<16>                                                
P  NNAMEm5515 M_K_CPU0_SB_DQ<15>                                                
P  NNAMEm5516 M_K_CPU0_SB_DQ<14>                                                
P  NNAMEm5517 M_K_CPU0_SB_DQ<13>                                                
P  NNAMEm5518 M_K_CPU0_SB_DQ<12>                                                
P  NNAMEm5519 M_K_CPU0_SB_DQ<11>                                                
P  NNAMEm5520 M_K_CPU0_SB_DQ<10>                                                
P  NNAMEm5521 M_K_CPU0_SB_DQ<0>                                                 
P  NNAMEm5522 M_K_CPU0_SB_CS_N<1>                                               
P  NNAMEm5523 M_K_CPU0_SB_CS_N<0>                                               
P  NNAMEm5524 M_K_CPU0_SB_CB<7>                                                 
P  NNAMEm5525 M_K_CPU0_SB_CB<6>                                                 
P  NNAMEm5526 M_K_CPU0_SB_CB<5>                                                 
P  NNAMEm5527 M_K_CPU0_SB_CB<4>                                                 
P  NNAMEm5528 M_K_CPU0_SB_CB<3>                                                 
P  NNAMEm5529 M_K_CPU0_SB_CB<2>                                                 
P  NNAMEm5530 M_K_CPU0_SB_CB<1>                                                 
P  NNAMEm5531 M_K_CPU0_SB_CB<0>                                                 
P  NNAMEm5532 M_K_CPU0_SB_CA<6>                                                 
P  NNAMEm5533 M_K_CPU0_SB_CA<5>                                                 
P  NNAMEm5534 M_K_CPU0_SB_CA<4>                                                 
P  NNAMEm5535 M_K_CPU0_SB_CA<3>                                                 
P  NNAMEm5536 M_K_CPU0_SB_CA<2>                                                 
P  NNAMEm5537 M_K_CPU0_SB_CA<1>                                                 
P  NNAMEm5538 M_K_CPU0_SB_CA<0>                                                 
P  NNAMEm5539 M_K_CPU0_SA_RSP<0>                                                
P  NNAMEm5540 M_K_CPU0_SA_PAR                                                   
P  NNAMEm5541 M_K_CPU0_SA_DQS_DP<9>                                             
P  NNAMEm5542 M_K_CPU0_SA_DQS_DP<8>                                             
P  NNAMEm5543 M_K_CPU0_SA_DQS_DP<7>                                             
P  NNAMEm5544 M_K_CPU0_SA_DQS_DP<6>                                             
P  NNAMEm5545 M_K_CPU0_SA_DQS_DP<5>                                             
P  NNAMEm5546 M_K_CPU0_SA_DQS_DP<4>                                             
P  NNAMEm5547 M_K_CPU0_SA_DQS_DP<3>                                             
P  NNAMEm5548 M_K_CPU0_SA_DQS_DP<2>                                             
P  NNAMEm5549 M_K_CPU0_SA_DQS_DP<1>                                             
P  NNAMEm5550 M_K_CPU0_SA_DQS_DP<0>                                             
P  NNAMEm5551 M_K_CPU0_SA_DQS_DN<9>                                             
P  NNAMEm5552 M_K_CPU0_SA_DQS_DN<8>                                             
P  NNAMEm5553 M_K_CPU0_SA_DQS_DN<7>                                             
P  NNAMEm5554 M_K_CPU0_SA_DQS_DN<6>                                             
P  NNAMEm5555 M_K_CPU0_SA_DQS_DN<5>                                             
P  NNAMEm5556 M_K_CPU0_SA_DQS_DN<4>                                             
P  NNAMEm5557 M_K_CPU0_SA_DQS_DN<3>                                             
P  NNAMEm5558 M_K_CPU0_SA_DQS_DN<2>                                             
P  NNAMEm5559 M_K_CPU0_SA_DQS_DN<1>                                             
P  NNAMEm5560 M_K_CPU0_SA_DQS_DN<0>                                             
P  NNAMEm5561 M_K_CPU0_SA_DQ<9>                                                 
P  NNAMEm5562 M_K_CPU0_SA_DQ<8>                                                 
P  NNAMEm5563 M_K_CPU0_SA_DQ<7>                                                 
P  NNAMEm5564 M_K_CPU0_SA_DQ<6>                                                 
P  NNAMEm5565 M_K_CPU0_SA_DQ<5>                                                 
P  NNAMEm5566 M_K_CPU0_SA_DQ<4>                                                 
P  NNAMEm5567 M_K_CPU0_SA_DQ<3>                                                 
P  NNAMEm5568 M_K_CPU0_SA_DQ<31>                                                
P  NNAMEm5569 M_K_CPU0_SA_DQ<30>                                                
P  NNAMEm5570 M_K_CPU0_SA_DQ<2>                                                 
P  NNAMEm5571 M_K_CPU0_SA_DQ<29>                                                
P  NNAMEm5572 M_K_CPU0_SA_DQ<28>                                                
P  NNAMEm5573 M_K_CPU0_SA_DQ<27>                                                
P  NNAMEm5574 M_K_CPU0_SA_DQ<26>                                                
P  NNAMEm5575 M_K_CPU0_SA_DQ<25>                                                
P  NNAMEm5576 M_K_CPU0_SA_DQ<24>                                                
P  NNAMEm5577 M_K_CPU0_SA_DQ<23>                                                
P  NNAMEm5578 M_K_CPU0_SA_DQ<22>                                                
P  NNAMEm5579 M_K_CPU0_SA_DQ<21>                                                
P  NNAMEm5580 M_K_CPU0_SA_DQ<20>                                                
P  NNAMEm5581 M_K_CPU0_SA_DQ<1>                                                 
P  NNAMEm5582 M_K_CPU0_SA_DQ<19>                                                
P  NNAMEm5583 M_K_CPU0_SA_DQ<18>                                                
P  NNAMEm5584 M_K_CPU0_SA_DQ<17>                                                
P  NNAMEm5585 M_K_CPU0_SA_DQ<16>                                                
P  NNAMEm5586 M_K_CPU0_SA_DQ<15>                                                
P  NNAMEm5587 M_K_CPU0_SA_DQ<14>                                                
P  NNAMEm5588 M_K_CPU0_SA_DQ<13>                                                
P  NNAMEm5589 M_K_CPU0_SA_DQ<12>                                                
P  NNAMEm5590 M_K_CPU0_SA_DQ<11>                                                
P  NNAMEm5591 M_K_CPU0_SA_DQ<10>                                                
P  NNAMEm5592 M_K_CPU0_SA_DQ<0>                                                 
P  NNAMEm5593 M_K_CPU0_SA_CS_N<1>                                               
P  NNAMEm5594 M_K_CPU0_SA_CS_N<0>                                               
P  NNAMEm5595 M_K_CPU0_SA_CB<7>                                                 
P  NNAMEm5596 M_K_CPU0_SA_CB<6>                                                 
P  NNAMEm5597 M_K_CPU0_SA_CB<5>                                                 
P  NNAMEm5598 M_K_CPU0_SA_CB<4>                                                 
P  NNAMEm5599 M_K_CPU0_SA_CB<3>                                                 
P  NNAMEm5600 M_K_CPU0_SA_CB<2>                                                 
P  NNAMEm5601 M_K_CPU0_SA_CB<1>                                                 
P  NNAMEm5602 M_K_CPU0_SA_CB<0>                                                 
P  NNAMEm5603 M_K_CPU0_SA_CA<6>                                                 
P  NNAMEm5604 M_K_CPU0_SA_CA<5>                                                 
P  NNAMEm5605 M_K_CPU0_SA_CA<4>                                                 
P  NNAMEm5606 M_K_CPU0_SA_CA<3>                                                 
P  NNAMEm5607 M_K_CPU0_SA_CA<2>                                                 
P  NNAMEm5608 M_K_CPU0_SA_CA<1>                                                 
P  NNAMEm5609 M_K_CPU0_SA_CA<0>                                                 
P  NNAMEm5610 M_K_CPU0_RESET_N                                                  
P  NNAMEm5611 M_K_CPU0_CLK_DP<0>                                                
P  NNAMEm5612 M_K_CPU0_CLK_DN<0>                                                
P  NNAMEm5613 M_K_CPU0_ALERT_R_N                                                
P  NNAMEm5614 M_K_CPU0_ALERT_N                                                  
P  NNAMEm5615 M_J_CPU1_SB_RSP<0>                                                
P  NNAMEm5616 M_J_CPU1_SB_PAR                                                   
P  NNAMEm5617 M_J_CPU1_SB_DQS_DP<9>                                             
P  NNAMEm5618 M_J_CPU1_SB_DQS_DP<8>                                             
P  NNAMEm5619 M_J_CPU1_SB_DQS_DP<7>                                             
P  NNAMEm5620 M_J_CPU1_SB_DQS_DP<6>                                             
P  NNAMEm5621 M_J_CPU1_SB_DQS_DP<5>                                             
P  NNAMEm5622 M_J_CPU1_SB_DQS_DP<4>                                             
P  NNAMEm5623 M_J_CPU1_SB_DQS_DP<3>                                             
P  NNAMEm5624 M_J_CPU1_SB_DQS_DP<2>                                             
P  NNAMEm5625 M_J_CPU1_SB_DQS_DP<1>                                             
P  NNAMEm5626 M_J_CPU1_SB_DQS_DP<0>                                             
P  NNAMEm5627 M_J_CPU1_SB_DQS_DN<9>                                             
P  NNAMEm5628 M_J_CPU1_SB_DQS_DN<8>                                             
P  NNAMEm5629 M_J_CPU1_SB_DQS_DN<7>                                             
P  NNAMEm5630 M_J_CPU1_SB_DQS_DN<6>                                             
P  NNAMEm5631 M_J_CPU1_SB_DQS_DN<5>                                             
P  NNAMEm5632 M_J_CPU1_SB_DQS_DN<4>                                             
P  NNAMEm5633 M_J_CPU1_SB_DQS_DN<3>                                             
P  NNAMEm5634 M_J_CPU1_SB_DQS_DN<2>                                             
P  NNAMEm5635 M_J_CPU1_SB_DQS_DN<1>                                             
P  NNAMEm5636 M_J_CPU1_SB_DQS_DN<0>                                             
P  NNAMEm5637 M_J_CPU1_SB_DQ<9>                                                 
P  NNAMEm5638 M_J_CPU1_SB_DQ<8>                                                 
P  NNAMEm5639 M_J_CPU1_SB_DQ<7>                                                 
P  NNAMEm5640 M_J_CPU1_SB_DQ<6>                                                 
P  NNAMEm5641 M_J_CPU1_SB_DQ<5>                                                 
P  NNAMEm5642 M_J_CPU1_SB_DQ<4>                                                 
P  NNAMEm5643 M_J_CPU1_SB_DQ<3>                                                 
P  NNAMEm5644 M_J_CPU1_SB_DQ<31>                                                
P  NNAMEm5645 M_J_CPU1_SB_DQ<30>                                                
P  NNAMEm5646 M_J_CPU1_SB_DQ<2>                                                 
P  NNAMEm5647 M_J_CPU1_SB_DQ<29>                                                
P  NNAMEm5648 M_J_CPU1_SB_DQ<28>                                                
P  NNAMEm5649 M_J_CPU1_SB_DQ<27>                                                
P  NNAMEm5650 M_J_CPU1_SB_DQ<26>                                                
P  NNAMEm5651 M_J_CPU1_SB_DQ<25>                                                
P  NNAMEm5652 M_J_CPU1_SB_DQ<24>                                                
P  NNAMEm5653 M_J_CPU1_SB_DQ<23>                                                
P  NNAMEm5654 M_J_CPU1_SB_DQ<22>                                                
P  NNAMEm5655 M_J_CPU1_SB_DQ<21>                                                
P  NNAMEm5656 M_J_CPU1_SB_DQ<20>                                                
P  NNAMEm5657 M_J_CPU1_SB_DQ<1>                                                 
P  NNAMEm5658 M_J_CPU1_SB_DQ<19>                                                
P  NNAMEm5659 M_J_CPU1_SB_DQ<18>                                                
P  NNAMEm5660 M_J_CPU1_SB_DQ<17>                                                
P  NNAMEm5661 M_J_CPU1_SB_DQ<16>                                                
P  NNAMEm5662 M_J_CPU1_SB_DQ<15>                                                
P  NNAMEm5663 M_J_CPU1_SB_DQ<14>                                                
P  NNAMEm5664 M_J_CPU1_SB_DQ<13>                                                
P  NNAMEm5665 M_J_CPU1_SB_DQ<12>                                                
P  NNAMEm5666 M_J_CPU1_SB_DQ<11>                                                
P  NNAMEm5667 M_J_CPU1_SB_DQ<10>                                                
P  NNAMEm5668 M_J_CPU1_SB_DQ<0>                                                 
P  NNAMEm5669 M_J_CPU1_SB_CS_N<1>                                               
P  NNAMEm5670 M_J_CPU1_SB_CS_N<0>                                               
P  NNAMEm5671 M_J_CPU1_SB_CB<7>                                                 
P  NNAMEm5672 M_J_CPU1_SB_CB<6>                                                 
P  NNAMEm5673 M_J_CPU1_SB_CB<5>                                                 
P  NNAMEm5674 M_J_CPU1_SB_CB<4>                                                 
P  NNAMEm5675 M_J_CPU1_SB_CB<3>                                                 
P  NNAMEm5676 M_J_CPU1_SB_CB<2>                                                 
P  NNAMEm5677 M_J_CPU1_SB_CB<1>                                                 
P  NNAMEm5678 M_J_CPU1_SB_CB<0>                                                 
P  NNAMEm5679 M_J_CPU1_SB_CA<6>                                                 
P  NNAMEm5680 M_J_CPU1_SB_CA<5>                                                 
P  NNAMEm5681 M_J_CPU1_SB_CA<4>                                                 
P  NNAMEm5682 M_J_CPU1_SB_CA<3>                                                 
P  NNAMEm5683 M_J_CPU1_SB_CA<2>                                                 
P  NNAMEm5684 M_J_CPU1_SB_CA<1>                                                 
P  NNAMEm5685 M_J_CPU1_SB_CA<0>                                                 
P  NNAMEm5686 M_J_CPU1_SA_RSP<0>                                                
P  NNAMEm5687 M_J_CPU1_SA_PAR                                                   
P  NNAMEm5688 M_J_CPU1_SA_DQS_DP<9>                                             
P  NNAMEm5689 M_J_CPU1_SA_DQS_DP<8>                                             
P  NNAMEm5690 M_J_CPU1_SA_DQS_DP<7>                                             
P  NNAMEm5691 M_J_CPU1_SA_DQS_DP<6>                                             
P  NNAMEm5692 M_J_CPU1_SA_DQS_DP<5>                                             
P  NNAMEm5693 M_J_CPU1_SA_DQS_DP<4>                                             
P  NNAMEm5694 M_J_CPU1_SA_DQS_DP<3>                                             
P  NNAMEm5695 M_J_CPU1_SA_DQS_DP<2>                                             
P  NNAMEm5696 M_J_CPU1_SA_DQS_DP<1>                                             
P  NNAMEm5697 M_J_CPU1_SA_DQS_DP<0>                                             
P  NNAMEm5698 M_J_CPU1_SA_DQS_DN<9>                                             
P  NNAMEm5699 M_J_CPU1_SA_DQS_DN<8>                                             
P  NNAMEm5700 M_J_CPU1_SA_DQS_DN<7>                                             
P  NNAMEm5701 M_J_CPU1_SA_DQS_DN<6>                                             
P  NNAMEm5702 M_J_CPU1_SA_DQS_DN<5>                                             
P  NNAMEm5703 M_J_CPU1_SA_DQS_DN<4>                                             
P  NNAMEm5704 M_J_CPU1_SA_DQS_DN<3>                                             
P  NNAMEm5705 M_J_CPU1_SA_DQS_DN<2>                                             
P  NNAMEm5706 M_J_CPU1_SA_DQS_DN<1>                                             
P  NNAMEm5707 M_J_CPU1_SA_DQS_DN<0>                                             
P  NNAMEm5708 M_J_CPU1_SA_DQ<9>                                                 
P  NNAMEm5709 M_J_CPU1_SA_DQ<8>                                                 
P  NNAMEm5710 M_J_CPU1_SA_DQ<7>                                                 
P  NNAMEm5711 M_J_CPU1_SA_DQ<6>                                                 
P  NNAMEm5712 M_J_CPU1_SA_DQ<5>                                                 
P  NNAMEm5713 M_J_CPU1_SA_DQ<4>                                                 
P  NNAMEm5714 M_J_CPU1_SA_DQ<3>                                                 
P  NNAMEm5715 M_J_CPU1_SA_DQ<31>                                                
P  NNAMEm5716 M_J_CPU1_SA_DQ<30>                                                
P  NNAMEm5717 M_J_CPU1_SA_DQ<2>                                                 
P  NNAMEm5718 M_J_CPU1_SA_DQ<29>                                                
P  NNAMEm5719 M_J_CPU1_SA_DQ<28>                                                
P  NNAMEm5720 M_J_CPU1_SA_DQ<27>                                                
P  NNAMEm5721 M_J_CPU1_SA_DQ<26>                                                
P  NNAMEm5722 M_J_CPU1_SA_DQ<25>                                                
P  NNAMEm5723 M_J_CPU1_SA_DQ<24>                                                
P  NNAMEm5724 M_J_CPU1_SA_DQ<23>                                                
P  NNAMEm5725 M_J_CPU1_SA_DQ<22>                                                
P  NNAMEm5726 M_J_CPU1_SA_DQ<21>                                                
P  NNAMEm5727 M_J_CPU1_SA_DQ<20>                                                
P  NNAMEm5728 M_J_CPU1_SA_DQ<1>                                                 
P  NNAMEm5729 M_J_CPU1_SA_DQ<19>                                                
P  NNAMEm5730 M_J_CPU1_SA_DQ<18>                                                
P  NNAMEm5731 M_J_CPU1_SA_DQ<17>                                                
P  NNAMEm5732 M_J_CPU1_SA_DQ<16>                                                
P  NNAMEm5733 M_J_CPU1_SA_DQ<15>                                                
P  NNAMEm5734 M_J_CPU1_SA_DQ<14>                                                
P  NNAMEm5735 M_J_CPU1_SA_DQ<13>                                                
P  NNAMEm5736 M_J_CPU1_SA_DQ<12>                                                
P  NNAMEm5737 M_J_CPU1_SA_DQ<11>                                                
P  NNAMEm5738 M_J_CPU1_SA_DQ<10>                                                
P  NNAMEm5739 M_J_CPU1_SA_DQ<0>                                                 
P  NNAMEm5740 M_J_CPU1_SA_CS_N<1>                                               
P  NNAMEm5741 M_J_CPU1_SA_CS_N<0>                                               
P  NNAMEm5742 M_J_CPU1_SA_CB<7>                                                 
P  NNAMEm5743 M_J_CPU1_SA_CB<6>                                                 
P  NNAMEm5744 M_J_CPU1_SA_CB<5>                                                 
P  NNAMEm5745 M_J_CPU1_SA_CB<4>                                                 
P  NNAMEm5746 M_J_CPU1_SA_CB<3>                                                 
P  NNAMEm5747 M_J_CPU1_SA_CB<2>                                                 
P  NNAMEm5748 M_J_CPU1_SA_CB<1>                                                 
P  NNAMEm5749 M_J_CPU1_SA_CB<0>                                                 
P  NNAMEm5750 M_J_CPU1_SA_CA<6>                                                 
P  NNAMEm5751 M_J_CPU1_SA_CA<5>                                                 
P  NNAMEm5752 M_J_CPU1_SA_CA<4>                                                 
P  NNAMEm5753 M_J_CPU1_SA_CA<3>                                                 
P  NNAMEm5754 M_J_CPU1_SA_CA<2>                                                 
P  NNAMEm5755 M_J_CPU1_SA_CA<1>                                                 
P  NNAMEm5756 M_J_CPU1_SA_CA<0>                                                 
P  NNAMEm5757 M_J_CPU1_RESET_N                                                  
P  NNAMEm5758 M_J_CPU1_CLK_DP<0>                                                
P  NNAMEm5759 M_J_CPU1_CLK_DN<0>                                                
P  NNAMEm5760 M_J_CPU1_ALERT_R_N                                                
P  NNAMEm5761 M_J_CPU1_ALERT_N                                                  
P  NNAMEm5762 M_J_CPU0_SB_RSP<0>                                                
P  NNAMEm5763 M_J_CPU0_SB_PAR                                                   
P  NNAMEm5764 M_J_CPU0_SB_DQS_DP<9>                                             
P  NNAMEm5765 M_J_CPU0_SB_DQS_DP<8>                                             
P  NNAMEm5766 M_J_CPU0_SB_DQS_DP<7>                                             
P  NNAMEm5767 M_J_CPU0_SB_DQS_DP<6>                                             
P  NNAMEm5768 M_J_CPU0_SB_DQS_DP<5>                                             
P  NNAMEm5769 M_J_CPU0_SB_DQS_DP<4>                                             
P  NNAMEm5770 M_J_CPU0_SB_DQS_DP<3>                                             
P  NNAMEm5771 M_J_CPU0_SB_DQS_DP<2>                                             
P  NNAMEm5772 M_J_CPU0_SB_DQS_DP<1>                                             
P  NNAMEm5773 M_J_CPU0_SB_DQS_DP<0>                                             
P  NNAMEm5774 M_J_CPU0_SB_DQS_DN<9>                                             
P  NNAMEm5775 M_J_CPU0_SB_DQS_DN<8>                                             
P  NNAMEm5776 M_J_CPU0_SB_DQS_DN<7>                                             
P  NNAMEm5777 M_J_CPU0_SB_DQS_DN<6>                                             
P  NNAMEm5778 M_J_CPU0_SB_DQS_DN<5>                                             
P  NNAMEm5779 M_J_CPU0_SB_DQS_DN<4>                                             
P  NNAMEm5780 M_J_CPU0_SB_DQS_DN<3>                                             
P  NNAMEm5781 M_J_CPU0_SB_DQS_DN<2>                                             
P  NNAMEm5782 M_J_CPU0_SB_DQS_DN<1>                                             
P  NNAMEm5783 M_J_CPU0_SB_DQS_DN<0>                                             
P  NNAMEm5784 M_J_CPU0_SB_DQ<9>                                                 
P  NNAMEm5785 M_J_CPU0_SB_DQ<8>                                                 
P  NNAMEm5786 M_J_CPU0_SB_DQ<7>                                                 
P  NNAMEm5787 M_J_CPU0_SB_DQ<6>                                                 
P  NNAMEm5788 M_J_CPU0_SB_DQ<5>                                                 
P  NNAMEm5789 M_J_CPU0_SB_DQ<4>                                                 
P  NNAMEm5790 M_J_CPU0_SB_DQ<3>                                                 
P  NNAMEm5791 M_J_CPU0_SB_DQ<31>                                                
P  NNAMEm5792 M_J_CPU0_SB_DQ<30>                                                
P  NNAMEm5793 M_J_CPU0_SB_DQ<2>                                                 
P  NNAMEm5794 M_J_CPU0_SB_DQ<29>                                                
P  NNAMEm5795 M_J_CPU0_SB_DQ<28>                                                
P  NNAMEm5796 M_J_CPU0_SB_DQ<27>                                                
P  NNAMEm5797 M_J_CPU0_SB_DQ<26>                                                
P  NNAMEm5798 M_J_CPU0_SB_DQ<25>                                                
P  NNAMEm5799 M_J_CPU0_SB_DQ<24>                                                
P  NNAMEm5800 M_J_CPU0_SB_DQ<23>                                                
P  NNAMEm5801 M_J_CPU0_SB_DQ<22>                                                
P  NNAMEm5802 M_J_CPU0_SB_DQ<21>                                                
P  NNAMEm5803 M_J_CPU0_SB_DQ<20>                                                
P  NNAMEm5804 M_J_CPU0_SB_DQ<1>                                                 
P  NNAMEm5805 M_J_CPU0_SB_DQ<19>                                                
P  NNAMEm5806 M_J_CPU0_SB_DQ<18>                                                
P  NNAMEm5807 M_J_CPU0_SB_DQ<17>                                                
P  NNAMEm5808 M_J_CPU0_SB_DQ<16>                                                
P  NNAMEm5809 M_J_CPU0_SB_DQ<15>                                                
P  NNAMEm5810 M_J_CPU0_SB_DQ<14>                                                
P  NNAMEm5811 M_J_CPU0_SB_DQ<13>                                                
P  NNAMEm5812 M_J_CPU0_SB_DQ<12>                                                
P  NNAMEm5813 M_J_CPU0_SB_DQ<11>                                                
P  NNAMEm5814 M_J_CPU0_SB_DQ<10>                                                
P  NNAMEm5815 M_J_CPU0_SB_DQ<0>                                                 
P  NNAMEm5816 M_J_CPU0_SB_CS_N<1>                                               
P  NNAMEm5817 M_J_CPU0_SB_CS_N<0>                                               
P  NNAMEm5818 M_J_CPU0_SB_CB<7>                                                 
P  NNAMEm5819 M_J_CPU0_SB_CB<6>                                                 
P  NNAMEm5820 M_J_CPU0_SB_CB<5>                                                 
P  NNAMEm5821 M_J_CPU0_SB_CB<4>                                                 
P  NNAMEm5822 M_J_CPU0_SB_CB<3>                                                 
P  NNAMEm5823 M_J_CPU0_SB_CB<2>                                                 
P  NNAMEm5824 M_J_CPU0_SB_CB<1>                                                 
P  NNAMEm5825 M_J_CPU0_SB_CB<0>                                                 
P  NNAMEm5826 M_J_CPU0_SB_CA<6>                                                 
P  NNAMEm5827 M_J_CPU0_SB_CA<5>                                                 
P  NNAMEm5828 M_J_CPU0_SB_CA<4>                                                 
P  NNAMEm5829 M_J_CPU0_SB_CA<3>                                                 
P  NNAMEm5830 M_J_CPU0_SB_CA<2>                                                 
P  NNAMEm5831 M_J_CPU0_SB_CA<1>                                                 
P  NNAMEm5832 M_J_CPU0_SB_CA<0>                                                 
P  NNAMEm5833 M_J_CPU0_SA_RSP<0>                                                
P  NNAMEm5834 M_J_CPU0_SA_PAR                                                   
P  NNAMEm5835 M_J_CPU0_SA_DQS_DP<9>                                             
P  NNAMEm5836 M_J_CPU0_SA_DQS_DP<8>                                             
P  NNAMEm5837 M_J_CPU0_SA_DQS_DP<7>                                             
P  NNAMEm5838 M_J_CPU0_SA_DQS_DP<6>                                             
P  NNAMEm5839 M_J_CPU0_SA_DQS_DP<5>                                             
P  NNAMEm5840 M_J_CPU0_SA_DQS_DP<4>                                             
P  NNAMEm5841 M_J_CPU0_SA_DQS_DP<3>                                             
P  NNAMEm5842 M_J_CPU0_SA_DQS_DP<2>                                             
P  NNAMEm5843 M_J_CPU0_SA_DQS_DP<1>                                             
P  NNAMEm5844 M_J_CPU0_SA_DQS_DP<0>                                             
P  NNAMEm5845 M_J_CPU0_SA_DQS_DN<9>                                             
P  NNAMEm5846 M_J_CPU0_SA_DQS_DN<8>                                             
P  NNAMEm5847 M_J_CPU0_SA_DQS_DN<7>                                             
P  NNAMEm5848 M_J_CPU0_SA_DQS_DN<6>                                             
P  NNAMEm5849 M_J_CPU0_SA_DQS_DN<5>                                             
P  NNAMEm5850 M_J_CPU0_SA_DQS_DN<4>                                             
P  NNAMEm5851 M_J_CPU0_SA_DQS_DN<3>                                             
P  NNAMEm5852 M_J_CPU0_SA_DQS_DN<2>                                             
P  NNAMEm5853 M_J_CPU0_SA_DQS_DN<1>                                             
P  NNAMEm5854 M_J_CPU0_SA_DQS_DN<0>                                             
P  NNAMEm5855 M_J_CPU0_SA_DQ<9>                                                 
P  NNAMEm5856 M_J_CPU0_SA_DQ<8>                                                 
P  NNAMEm5857 M_J_CPU0_SA_DQ<7>                                                 
P  NNAMEm5858 M_J_CPU0_SA_DQ<6>                                                 
P  NNAMEm5859 M_J_CPU0_SA_DQ<5>                                                 
P  NNAMEm5860 M_J_CPU0_SA_DQ<4>                                                 
P  NNAMEm5861 M_J_CPU0_SA_DQ<3>                                                 
P  NNAMEm5862 M_J_CPU0_SA_DQ<31>                                                
P  NNAMEm5863 M_J_CPU0_SA_DQ<30>                                                
P  NNAMEm5864 M_J_CPU0_SA_DQ<2>                                                 
P  NNAMEm5865 M_J_CPU0_SA_DQ<29>                                                
P  NNAMEm5866 M_J_CPU0_SA_DQ<28>                                                
P  NNAMEm5867 M_J_CPU0_SA_DQ<27>                                                
P  NNAMEm5868 M_J_CPU0_SA_DQ<26>                                                
P  NNAMEm5869 M_J_CPU0_SA_DQ<25>                                                
P  NNAMEm5870 M_J_CPU0_SA_DQ<24>                                                
P  NNAMEm5871 M_J_CPU0_SA_DQ<23>                                                
P  NNAMEm5872 M_J_CPU0_SA_DQ<22>                                                
P  NNAMEm5873 M_J_CPU0_SA_DQ<21>                                                
P  NNAMEm5874 M_J_CPU0_SA_DQ<20>                                                
P  NNAMEm5875 M_J_CPU0_SA_DQ<1>                                                 
P  NNAMEm5876 M_J_CPU0_SA_DQ<19>                                                
P  NNAMEm5877 M_J_CPU0_SA_DQ<18>                                                
P  NNAMEm5878 M_J_CPU0_SA_DQ<17>                                                
P  NNAMEm5879 M_J_CPU0_SA_DQ<16>                                                
P  NNAMEm5880 M_J_CPU0_SA_DQ<15>                                                
P  NNAMEm5881 M_J_CPU0_SA_DQ<14>                                                
P  NNAMEm5882 M_J_CPU0_SA_DQ<13>                                                
P  NNAMEm5883 M_J_CPU0_SA_DQ<12>                                                
P  NNAMEm5884 M_J_CPU0_SA_DQ<11>                                                
P  NNAMEm5885 M_J_CPU0_SA_DQ<10>                                                
P  NNAMEm5886 M_J_CPU0_SA_DQ<0>                                                 
P  NNAMEm5887 M_J_CPU0_SA_CS_N<1>                                               
P  NNAMEm5888 M_J_CPU0_SA_CS_N<0>                                               
P  NNAMEm5889 M_J_CPU0_SA_CB<7>                                                 
P  NNAMEm5890 M_J_CPU0_SA_CB<6>                                                 
P  NNAMEm5891 M_J_CPU0_SA_CB<5>                                                 
P  NNAMEm5892 M_J_CPU0_SA_CB<4>                                                 
P  NNAMEm5893 M_J_CPU0_SA_CB<3>                                                 
P  NNAMEm5894 M_J_CPU0_SA_CB<2>                                                 
P  NNAMEm5895 M_J_CPU0_SA_CB<1>                                                 
P  NNAMEm5896 M_J_CPU0_SA_CB<0>                                                 
P  NNAMEm5897 M_J_CPU0_SA_CA<6>                                                 
P  NNAMEm5898 M_J_CPU0_SA_CA<5>                                                 
P  NNAMEm5899 M_J_CPU0_SA_CA<4>                                                 
P  NNAMEm5900 M_J_CPU0_SA_CA<3>                                                 
P  NNAMEm5901 M_J_CPU0_SA_CA<2>                                                 
P  NNAMEm5902 M_J_CPU0_SA_CA<1>                                                 
P  NNAMEm5903 M_J_CPU0_SA_CA<0>                                                 
P  NNAMEm5904 M_J_CPU0_RESET_N                                                  
P  NNAMEm5905 M_J_CPU0_CLK_DP<0>                                                
P  NNAMEm5906 M_J_CPU0_CLK_DN<0>                                                
P  NNAMEm5907 M_J_CPU0_ALERT_R_N                                                
P  NNAMEm5908 M_J_CPU0_ALERT_N                                                  
P  NNAMEm5909 M_I_CPU1_SB_RSP<0>                                                
P  NNAMEm5910 M_I_CPU1_SB_PAR                                                   
P  NNAMEm5911 M_I_CPU1_SB_DQS_DP<9>                                             
P  NNAMEm5912 M_I_CPU1_SB_DQS_DP<8>                                             
P  NNAMEm5913 M_I_CPU1_SB_DQS_DP<7>                                             
P  NNAMEm5914 M_I_CPU1_SB_DQS_DP<6>                                             
P  NNAMEm5915 M_I_CPU1_SB_DQS_DP<5>                                             
P  NNAMEm5916 M_I_CPU1_SB_DQS_DP<4>                                             
P  NNAMEm5917 M_I_CPU1_SB_DQS_DP<3>                                             
P  NNAMEm5918 M_I_CPU1_SB_DQS_DP<2>                                             
P  NNAMEm5919 M_I_CPU1_SB_DQS_DP<1>                                             
P  NNAMEm5920 M_I_CPU1_SB_DQS_DP<0>                                             
P  NNAMEm5921 M_I_CPU1_SB_DQS_DN<9>                                             
P  NNAMEm5922 M_I_CPU1_SB_DQS_DN<8>                                             
P  NNAMEm5923 M_I_CPU1_SB_DQS_DN<7>                                             
P  NNAMEm5924 M_I_CPU1_SB_DQS_DN<6>                                             
P  NNAMEm5925 M_I_CPU1_SB_DQS_DN<5>                                             
P  NNAMEm5926 M_I_CPU1_SB_DQS_DN<4>                                             
P  NNAMEm5927 M_I_CPU1_SB_DQS_DN<3>                                             
P  NNAMEm5928 M_I_CPU1_SB_DQS_DN<2>                                             
P  NNAMEm5929 M_I_CPU1_SB_DQS_DN<1>                                             
P  NNAMEm5930 M_I_CPU1_SB_DQS_DN<0>                                             
P  NNAMEm5931 M_I_CPU1_SB_DQ<9>                                                 
P  NNAMEm5932 M_I_CPU1_SB_DQ<8>                                                 
P  NNAMEm5933 M_I_CPU1_SB_DQ<7>                                                 
P  NNAMEm5934 M_I_CPU1_SB_DQ<6>                                                 
P  NNAMEm5935 M_I_CPU1_SB_DQ<5>                                                 
P  NNAMEm5936 M_I_CPU1_SB_DQ<4>                                                 
P  NNAMEm5937 M_I_CPU1_SB_DQ<3>                                                 
P  NNAMEm5938 M_I_CPU1_SB_DQ<31>                                                
P  NNAMEm5939 M_I_CPU1_SB_DQ<30>                                                
P  NNAMEm5940 M_I_CPU1_SB_DQ<2>                                                 
P  NNAMEm5941 M_I_CPU1_SB_DQ<29>                                                
P  NNAMEm5942 M_I_CPU1_SB_DQ<28>                                                
P  NNAMEm5943 M_I_CPU1_SB_DQ<27>                                                
P  NNAMEm5944 M_I_CPU1_SB_DQ<26>                                                
P  NNAMEm5945 M_I_CPU1_SB_DQ<25>                                                
P  NNAMEm5946 M_I_CPU1_SB_DQ<24>                                                
P  NNAMEm5947 M_I_CPU1_SB_DQ<23>                                                
P  NNAMEm5948 M_I_CPU1_SB_DQ<22>                                                
P  NNAMEm5949 M_I_CPU1_SB_DQ<21>                                                
P  NNAMEm5950 M_I_CPU1_SB_DQ<20>                                                
P  NNAMEm5951 M_I_CPU1_SB_DQ<1>                                                 
P  NNAMEm5952 M_I_CPU1_SB_DQ<19>                                                
P  NNAMEm5953 M_I_CPU1_SB_DQ<18>                                                
P  NNAMEm5954 M_I_CPU1_SB_DQ<17>                                                
P  NNAMEm5955 M_I_CPU1_SB_DQ<16>                                                
P  NNAMEm5956 M_I_CPU1_SB_DQ<15>                                                
P  NNAMEm5957 M_I_CPU1_SB_DQ<14>                                                
P  NNAMEm5958 M_I_CPU1_SB_DQ<13>                                                
P  NNAMEm5959 M_I_CPU1_SB_DQ<12>                                                
P  NNAMEm5960 M_I_CPU1_SB_DQ<11>                                                
P  NNAMEm5961 M_I_CPU1_SB_DQ<10>                                                
P  NNAMEm5962 M_I_CPU1_SB_DQ<0>                                                 
P  NNAMEm5963 M_I_CPU1_SB_CS_N<1>                                               
P  NNAMEm5964 M_I_CPU1_SB_CS_N<0>                                               
P  NNAMEm5965 M_I_CPU1_SB_CB<7>                                                 
P  NNAMEm5966 M_I_CPU1_SB_CB<6>                                                 
P  NNAMEm5967 M_I_CPU1_SB_CB<5>                                                 
P  NNAMEm5968 M_I_CPU1_SB_CB<4>                                                 
P  NNAMEm5969 M_I_CPU1_SB_CB<3>                                                 
P  NNAMEm5970 M_I_CPU1_SB_CB<2>                                                 
P  NNAMEm5971 M_I_CPU1_SB_CB<1>                                                 
P  NNAMEm5972 M_I_CPU1_SB_CB<0>                                                 
P  NNAMEm5973 M_I_CPU1_SB_CA<6>                                                 
P  NNAMEm5974 M_I_CPU1_SB_CA<5>                                                 
P  NNAMEm5975 M_I_CPU1_SB_CA<4>                                                 
P  NNAMEm5976 M_I_CPU1_SB_CA<3>                                                 
P  NNAMEm5977 M_I_CPU1_SB_CA<2>                                                 
P  NNAMEm5978 M_I_CPU1_SB_CA<1>                                                 
P  NNAMEm5979 M_I_CPU1_SB_CA<0>                                                 
P  NNAMEm5980 M_I_CPU1_SA_RSP<0>                                                
P  NNAMEm5981 M_I_CPU1_SA_PAR                                                   
P  NNAMEm5982 M_I_CPU1_SA_DQS_DP<9>                                             
P  NNAMEm5983 M_I_CPU1_SA_DQS_DP<8>                                             
P  NNAMEm5984 M_I_CPU1_SA_DQS_DP<7>                                             
P  NNAMEm5985 M_I_CPU1_SA_DQS_DP<6>                                             
P  NNAMEm5986 M_I_CPU1_SA_DQS_DP<5>                                             
P  NNAMEm5987 M_I_CPU1_SA_DQS_DP<4>                                             
P  NNAMEm5988 M_I_CPU1_SA_DQS_DP<3>                                             
P  NNAMEm5989 M_I_CPU1_SA_DQS_DP<2>                                             
P  NNAMEm5990 M_I_CPU1_SA_DQS_DP<1>                                             
P  NNAMEm5991 M_I_CPU1_SA_DQS_DP<0>                                             
P  NNAMEm5992 M_I_CPU1_SA_DQS_DN<9>                                             
P  NNAMEm5993 M_I_CPU1_SA_DQS_DN<8>                                             
P  NNAMEm5994 M_I_CPU1_SA_DQS_DN<7>                                             
P  NNAMEm5995 M_I_CPU1_SA_DQS_DN<6>                                             
P  NNAMEm5996 M_I_CPU1_SA_DQS_DN<5>                                             
P  NNAMEm5997 M_I_CPU1_SA_DQS_DN<4>                                             
P  NNAMEm5998 M_I_CPU1_SA_DQS_DN<3>                                             
P  NNAMEm5999 M_I_CPU1_SA_DQS_DN<2>                                             
P  NNAMEm6000 M_I_CPU1_SA_DQS_DN<1>                                             
P  NNAMEm6001 M_I_CPU1_SA_DQS_DN<0>                                             
P  NNAMEm6002 M_I_CPU1_SA_DQ<9>                                                 
P  NNAMEm6003 M_I_CPU1_SA_DQ<8>                                                 
P  NNAMEm6004 M_I_CPU1_SA_DQ<7>                                                 
P  NNAMEm6005 M_I_CPU1_SA_DQ<6>                                                 
P  NNAMEm6006 M_I_CPU1_SA_DQ<5>                                                 
P  NNAMEm6007 M_I_CPU1_SA_DQ<4>                                                 
P  NNAMEm6008 M_I_CPU1_SA_DQ<3>                                                 
P  NNAMEm6009 M_I_CPU1_SA_DQ<31>                                                
P  NNAMEm6010 M_I_CPU1_SA_DQ<30>                                                
P  NNAMEm6011 M_I_CPU1_SA_DQ<2>                                                 
P  NNAMEm6012 M_I_CPU1_SA_DQ<29>                                                
P  NNAMEm6013 M_I_CPU1_SA_DQ<28>                                                
P  NNAMEm6014 M_I_CPU1_SA_DQ<27>                                                
P  NNAMEm6015 M_I_CPU1_SA_DQ<26>                                                
P  NNAMEm6016 M_I_CPU1_SA_DQ<25>                                                
P  NNAMEm6017 M_I_CPU1_SA_DQ<24>                                                
P  NNAMEm6018 M_I_CPU1_SA_DQ<23>                                                
P  NNAMEm6019 M_I_CPU1_SA_DQ<22>                                                
P  NNAMEm6020 M_I_CPU1_SA_DQ<21>                                                
P  NNAMEm6021 M_I_CPU1_SA_DQ<20>                                                
P  NNAMEm6022 M_I_CPU1_SA_DQ<1>                                                 
P  NNAMEm6023 M_I_CPU1_SA_DQ<19>                                                
P  NNAMEm6024 M_I_CPU1_SA_DQ<18>                                                
P  NNAMEm6025 M_I_CPU1_SA_DQ<17>                                                
P  NNAMEm6026 M_I_CPU1_SA_DQ<16>                                                
P  NNAMEm6027 M_I_CPU1_SA_DQ<15>                                                
P  NNAMEm6028 M_I_CPU1_SA_DQ<14>                                                
P  NNAMEm6029 M_I_CPU1_SA_DQ<13>                                                
P  NNAMEm6030 M_I_CPU1_SA_DQ<12>                                                
P  NNAMEm6031 M_I_CPU1_SA_DQ<11>                                                
P  NNAMEm6032 M_I_CPU1_SA_DQ<10>                                                
P  NNAMEm6033 M_I_CPU1_SA_DQ<0>                                                 
P  NNAMEm6034 M_I_CPU1_SA_CS_N<1>                                               
P  NNAMEm6035 M_I_CPU1_SA_CS_N<0>                                               
P  NNAMEm6036 M_I_CPU1_SA_CB<7>                                                 
P  NNAMEm6037 M_I_CPU1_SA_CB<6>                                                 
P  NNAMEm6038 M_I_CPU1_SA_CB<5>                                                 
P  NNAMEm6039 M_I_CPU1_SA_CB<4>                                                 
P  NNAMEm6040 M_I_CPU1_SA_CB<3>                                                 
P  NNAMEm6041 M_I_CPU1_SA_CB<2>                                                 
P  NNAMEm6042 M_I_CPU1_SA_CB<1>                                                 
P  NNAMEm6043 M_I_CPU1_SA_CB<0>                                                 
P  NNAMEm6044 M_I_CPU1_SA_CA<6>                                                 
P  NNAMEm6045 M_I_CPU1_SA_CA<5>                                                 
P  NNAMEm6046 M_I_CPU1_SA_CA<4>                                                 
P  NNAMEm6047 M_I_CPU1_SA_CA<3>                                                 
P  NNAMEm6048 M_I_CPU1_SA_CA<2>                                                 
P  NNAMEm6049 M_I_CPU1_SA_CA<1>                                                 
P  NNAMEm6050 M_I_CPU1_SA_CA<0>                                                 
P  NNAMEm6051 M_I_CPU1_RESET_N                                                  
P  NNAMEm6052 M_I_CPU1_CLK_DP<0>                                                
P  NNAMEm6053 M_I_CPU1_CLK_DN<0>                                                
P  NNAMEm6054 M_I_CPU1_ALERT_R_N                                                
P  NNAMEm6055 M_I_CPU1_ALERT_N                                                  
P  NNAMEm6056 M_I_CPU0_SB_RSP<0>                                                
P  NNAMEm6057 M_I_CPU0_SB_PAR                                                   
P  NNAMEm6058 M_I_CPU0_SB_DQS_DP<9>                                             
P  NNAMEm6059 M_I_CPU0_SB_DQS_DP<8>                                             
P  NNAMEm6060 M_I_CPU0_SB_DQS_DP<7>                                             
P  NNAMEm6061 M_I_CPU0_SB_DQS_DP<6>                                             
P  NNAMEm6062 M_I_CPU0_SB_DQS_DP<5>                                             
P  NNAMEm6063 M_I_CPU0_SB_DQS_DP<4>                                             
P  NNAMEm6064 M_I_CPU0_SB_DQS_DP<3>                                             
P  NNAMEm6065 M_I_CPU0_SB_DQS_DP<2>                                             
P  NNAMEm6066 M_I_CPU0_SB_DQS_DP<1>                                             
P  NNAMEm6067 M_I_CPU0_SB_DQS_DP<0>                                             
P  NNAMEm6068 M_I_CPU0_SB_DQS_DN<9>                                             
P  NNAMEm6069 M_I_CPU0_SB_DQS_DN<8>                                             
P  NNAMEm6070 M_I_CPU0_SB_DQS_DN<7>                                             
P  NNAMEm6071 M_I_CPU0_SB_DQS_DN<6>                                             
P  NNAMEm6072 M_I_CPU0_SB_DQS_DN<5>                                             
P  NNAMEm6073 M_I_CPU0_SB_DQS_DN<4>                                             
P  NNAMEm6074 M_I_CPU0_SB_DQS_DN<3>                                             
P  NNAMEm6075 M_I_CPU0_SB_DQS_DN<2>                                             
P  NNAMEm6076 M_I_CPU0_SB_DQS_DN<1>                                             
P  NNAMEm6077 M_I_CPU0_SB_DQS_DN<0>                                             
P  NNAMEm6078 M_I_CPU0_SB_DQ<9>                                                 
P  NNAMEm6079 M_I_CPU0_SB_DQ<8>                                                 
P  NNAMEm6080 M_I_CPU0_SB_DQ<7>                                                 
P  NNAMEm6081 M_I_CPU0_SB_DQ<6>                                                 
P  NNAMEm6082 M_I_CPU0_SB_DQ<5>                                                 
P  NNAMEm6083 M_I_CPU0_SB_DQ<4>                                                 
P  NNAMEm6084 M_I_CPU0_SB_DQ<3>                                                 
P  NNAMEm6085 M_I_CPU0_SB_DQ<31>                                                
P  NNAMEm6086 M_I_CPU0_SB_DQ<30>                                                
P  NNAMEm6087 M_I_CPU0_SB_DQ<2>                                                 
P  NNAMEm6088 M_I_CPU0_SB_DQ<29>                                                
P  NNAMEm6089 M_I_CPU0_SB_DQ<28>                                                
P  NNAMEm6090 M_I_CPU0_SB_DQ<27>                                                
P  NNAMEm6091 M_I_CPU0_SB_DQ<26>                                                
P  NNAMEm6092 M_I_CPU0_SB_DQ<25>                                                
P  NNAMEm6093 M_I_CPU0_SB_DQ<24>                                                
P  NNAMEm6094 M_I_CPU0_SB_DQ<23>                                                
P  NNAMEm6095 M_I_CPU0_SB_DQ<22>                                                
P  NNAMEm6096 M_I_CPU0_SB_DQ<21>                                                
P  NNAMEm6097 M_I_CPU0_SB_DQ<20>                                                
P  NNAMEm6098 M_I_CPU0_SB_DQ<1>                                                 
P  NNAMEm6099 M_I_CPU0_SB_DQ<19>                                                
P  NNAMEm6100 M_I_CPU0_SB_DQ<18>                                                
P  NNAMEm6101 M_I_CPU0_SB_DQ<17>                                                
P  NNAMEm6102 M_I_CPU0_SB_DQ<16>                                                
P  NNAMEm6103 M_I_CPU0_SB_DQ<15>                                                
P  NNAMEm6104 M_I_CPU0_SB_DQ<14>                                                
P  NNAMEm6105 M_I_CPU0_SB_DQ<13>                                                
P  NNAMEm6106 M_I_CPU0_SB_DQ<12>                                                
P  NNAMEm6107 M_I_CPU0_SB_DQ<11>                                                
P  NNAMEm6108 M_I_CPU0_SB_DQ<10>                                                
P  NNAMEm6109 M_I_CPU0_SB_DQ<0>                                                 
P  NNAMEm6110 M_I_CPU0_SB_CS_N<1>                                               
P  NNAMEm6111 M_I_CPU0_SB_CS_N<0>                                               
P  NNAMEm6112 M_I_CPU0_SB_CB<7>                                                 
P  NNAMEm6113 M_I_CPU0_SB_CB<6>                                                 
P  NNAMEm6114 M_I_CPU0_SB_CB<5>                                                 
P  NNAMEm6115 M_I_CPU0_SB_CB<4>                                                 
P  NNAMEm6116 M_I_CPU0_SB_CB<3>                                                 
P  NNAMEm6117 M_I_CPU0_SB_CB<2>                                                 
P  NNAMEm6118 M_I_CPU0_SB_CB<1>                                                 
P  NNAMEm6119 M_I_CPU0_SB_CB<0>                                                 
P  NNAMEm6120 M_I_CPU0_SB_CA<6>                                                 
P  NNAMEm6121 M_I_CPU0_SB_CA<5>                                                 
P  NNAMEm6122 M_I_CPU0_SB_CA<4>                                                 
P  NNAMEm6123 M_I_CPU0_SB_CA<3>                                                 
P  NNAMEm6124 M_I_CPU0_SB_CA<2>                                                 
P  NNAMEm6125 M_I_CPU0_SB_CA<1>                                                 
P  NNAMEm6126 M_I_CPU0_SB_CA<0>                                                 
P  NNAMEm6127 M_I_CPU0_SA_RSP<0>                                                
P  NNAMEm6128 M_I_CPU0_SA_PAR                                                   
P  NNAMEm6129 M_I_CPU0_SA_DQS_DP<9>                                             
P  NNAMEm6130 M_I_CPU0_SA_DQS_DP<8>                                             
P  NNAMEm6131 M_I_CPU0_SA_DQS_DP<7>                                             
P  NNAMEm6132 M_I_CPU0_SA_DQS_DP<6>                                             
P  NNAMEm6133 M_I_CPU0_SA_DQS_DP<5>                                             
P  NNAMEm6134 M_I_CPU0_SA_DQS_DP<4>                                             
P  NNAMEm6135 M_I_CPU0_SA_DQS_DP<3>                                             
P  NNAMEm6136 M_I_CPU0_SA_DQS_DP<2>                                             
P  NNAMEm6137 M_I_CPU0_SA_DQS_DP<1>                                             
P  NNAMEm6138 M_I_CPU0_SA_DQS_DP<0>                                             
P  NNAMEm6139 M_I_CPU0_SA_DQS_DN<9>                                             
P  NNAMEm6140 M_I_CPU0_SA_DQS_DN<8>                                             
P  NNAMEm6141 M_I_CPU0_SA_DQS_DN<7>                                             
P  NNAMEm6142 M_I_CPU0_SA_DQS_DN<6>                                             
P  NNAMEm6143 M_I_CPU0_SA_DQS_DN<5>                                             
P  NNAMEm6144 M_I_CPU0_SA_DQS_DN<4>                                             
P  NNAMEm6145 M_I_CPU0_SA_DQS_DN<3>                                             
P  NNAMEm6146 M_I_CPU0_SA_DQS_DN<2>                                             
P  NNAMEm6147 M_I_CPU0_SA_DQS_DN<1>                                             
P  NNAMEm6148 M_I_CPU0_SA_DQS_DN<0>                                             
P  NNAMEm6149 M_I_CPU0_SA_DQ<9>                                                 
P  NNAMEm6150 M_I_CPU0_SA_DQ<8>                                                 
P  NNAMEm6151 M_I_CPU0_SA_DQ<7>                                                 
P  NNAMEm6152 M_I_CPU0_SA_DQ<6>                                                 
P  NNAMEm6153 M_I_CPU0_SA_DQ<5>                                                 
P  NNAMEm6154 M_I_CPU0_SA_DQ<4>                                                 
P  NNAMEm6155 M_I_CPU0_SA_DQ<3>                                                 
P  NNAMEm6156 M_I_CPU0_SA_DQ<31>                                                
P  NNAMEm6157 M_I_CPU0_SA_DQ<30>                                                
P  NNAMEm6158 M_I_CPU0_SA_DQ<2>                                                 
P  NNAMEm6159 M_I_CPU0_SA_DQ<29>                                                
P  NNAMEm6160 M_I_CPU0_SA_DQ<28>                                                
P  NNAMEm6161 M_I_CPU0_SA_DQ<27>                                                
P  NNAMEm6162 M_I_CPU0_SA_DQ<26>                                                
P  NNAMEm6163 M_I_CPU0_SA_DQ<25>                                                
P  NNAMEm6164 M_I_CPU0_SA_DQ<24>                                                
P  NNAMEm6165 M_I_CPU0_SA_DQ<23>                                                
P  NNAMEm6166 M_I_CPU0_SA_DQ<22>                                                
P  NNAMEm6167 M_I_CPU0_SA_DQ<21>                                                
P  NNAMEm6168 M_I_CPU0_SA_DQ<20>                                                
P  NNAMEm6169 M_I_CPU0_SA_DQ<1>                                                 
P  NNAMEm6170 M_I_CPU0_SA_DQ<19>                                                
P  NNAMEm6171 M_I_CPU0_SA_DQ<18>                                                
P  NNAMEm6172 M_I_CPU0_SA_DQ<17>                                                
P  NNAMEm6173 M_I_CPU0_SA_DQ<16>                                                
P  NNAMEm6174 M_I_CPU0_SA_DQ<15>                                                
P  NNAMEm6175 M_I_CPU0_SA_DQ<14>                                                
P  NNAMEm6176 M_I_CPU0_SA_DQ<13>                                                
P  NNAMEm6177 M_I_CPU0_SA_DQ<12>                                                
P  NNAMEm6178 M_I_CPU0_SA_DQ<11>                                                
P  NNAMEm6179 M_I_CPU0_SA_DQ<10>                                                
P  NNAMEm6180 M_I_CPU0_SA_DQ<0>                                                 
P  NNAMEm6181 M_I_CPU0_SA_CS_N<1>                                               
P  NNAMEm6182 M_I_CPU0_SA_CS_N<0>                                               
P  NNAMEm6183 M_I_CPU0_SA_CB<7>                                                 
P  NNAMEm6184 M_I_CPU0_SA_CB<6>                                                 
P  NNAMEm6185 M_I_CPU0_SA_CB<5>                                                 
P  NNAMEm6186 M_I_CPU0_SA_CB<4>                                                 
P  NNAMEm6187 M_I_CPU0_SA_CB<3>                                                 
P  NNAMEm6188 M_I_CPU0_SA_CB<2>                                                 
P  NNAMEm6189 M_I_CPU0_SA_CB<1>                                                 
P  NNAMEm6190 M_I_CPU0_SA_CB<0>                                                 
P  NNAMEm6191 M_I_CPU0_SA_CA<6>                                                 
P  NNAMEm6192 M_I_CPU0_SA_CA<5>                                                 
P  NNAMEm6193 M_I_CPU0_SA_CA<4>                                                 
P  NNAMEm6194 M_I_CPU0_SA_CA<3>                                                 
P  NNAMEm6195 M_I_CPU0_SA_CA<2>                                                 
P  NNAMEm6196 M_I_CPU0_SA_CA<1>                                                 
P  NNAMEm6197 M_I_CPU0_SA_CA<0>                                                 
P  NNAMEm6198 M_I_CPU0_RESET_N                                                  
P  NNAMEm6199 M_I_CPU0_CLK_DP<0>                                                
P  NNAMEm6200 M_I_CPU0_CLK_DN<0>                                                
P  NNAMEm6201 M_I_CPU0_ALERT_R_N                                                
P  NNAMEm6202 M_I_CPU0_ALERT_N                                                  
P  NNAMEm6203 M_H_CPU1_SB_RSP<0>                                                
P  NNAMEm6204 M_H_CPU1_SB_PAR                                                   
P  NNAMEm6205 M_H_CPU1_SB_DQS_DP<9>                                             
P  NNAMEm6206 M_H_CPU1_SB_DQS_DP<8>                                             
P  NNAMEm6207 M_H_CPU1_SB_DQS_DP<7>                                             
P  NNAMEm6208 M_H_CPU1_SB_DQS_DP<6>                                             
P  NNAMEm6209 M_H_CPU1_SB_DQS_DP<5>                                             
P  NNAMEm6210 M_H_CPU1_SB_DQS_DP<4>                                             
P  NNAMEm6211 M_H_CPU1_SB_DQS_DP<3>                                             
P  NNAMEm6212 M_H_CPU1_SB_DQS_DP<2>                                             
P  NNAMEm6213 M_H_CPU1_SB_DQS_DP<1>                                             
P  NNAMEm6214 M_H_CPU1_SB_DQS_DP<0>                                             
P  NNAMEm6215 M_H_CPU1_SB_DQS_DN<9>                                             
P  NNAMEm6216 M_H_CPU1_SB_DQS_DN<8>                                             
P  NNAMEm6217 M_H_CPU1_SB_DQS_DN<7>                                             
P  NNAMEm6218 M_H_CPU1_SB_DQS_DN<6>                                             
P  NNAMEm6219 M_H_CPU1_SB_DQS_DN<5>                                             
P  NNAMEm6220 M_H_CPU1_SB_DQS_DN<4>                                             
P  NNAMEm6221 M_H_CPU1_SB_DQS_DN<3>                                             
P  NNAMEm6222 M_H_CPU1_SB_DQS_DN<2>                                             
P  NNAMEm6223 M_H_CPU1_SB_DQS_DN<1>                                             
P  NNAMEm6224 M_H_CPU1_SB_DQS_DN<0>                                             
P  NNAMEm6225 M_H_CPU1_SB_DQ<9>                                                 
P  NNAMEm6226 M_H_CPU1_SB_DQ<8>                                                 
P  NNAMEm6227 M_H_CPU1_SB_DQ<7>                                                 
P  NNAMEm6228 M_H_CPU1_SB_DQ<6>                                                 
P  NNAMEm6229 M_H_CPU1_SB_DQ<5>                                                 
P  NNAMEm6230 M_H_CPU1_SB_DQ<4>                                                 
P  NNAMEm6231 M_H_CPU1_SB_DQ<3>                                                 
P  NNAMEm6232 M_H_CPU1_SB_DQ<31>                                                
P  NNAMEm6233 M_H_CPU1_SB_DQ<30>                                                
P  NNAMEm6234 M_H_CPU1_SB_DQ<2>                                                 
P  NNAMEm6235 M_H_CPU1_SB_DQ<29>                                                
P  NNAMEm6236 M_H_CPU1_SB_DQ<28>                                                
P  NNAMEm6237 M_H_CPU1_SB_DQ<27>                                                
P  NNAMEm6238 M_H_CPU1_SB_DQ<26>                                                
P  NNAMEm6239 M_H_CPU1_SB_DQ<25>                                                
P  NNAMEm6240 M_H_CPU1_SB_DQ<24>                                                
P  NNAMEm6241 M_H_CPU1_SB_DQ<23>                                                
P  NNAMEm6242 M_H_CPU1_SB_DQ<22>                                                
P  NNAMEm6243 M_H_CPU1_SB_DQ<21>                                                
P  NNAMEm6244 M_H_CPU1_SB_DQ<20>                                                
P  NNAMEm6245 M_H_CPU1_SB_DQ<1>                                                 
P  NNAMEm6246 M_H_CPU1_SB_DQ<19>                                                
P  NNAMEm6247 M_H_CPU1_SB_DQ<18>                                                
P  NNAMEm6248 M_H_CPU1_SB_DQ<17>                                                
P  NNAMEm6249 M_H_CPU1_SB_DQ<16>                                                
P  NNAMEm6250 M_H_CPU1_SB_DQ<15>                                                
P  NNAMEm6251 M_H_CPU1_SB_DQ<14>                                                
P  NNAMEm6252 M_H_CPU1_SB_DQ<13>                                                
P  NNAMEm6253 M_H_CPU1_SB_DQ<12>                                                
P  NNAMEm6254 M_H_CPU1_SB_DQ<11>                                                
P  NNAMEm6255 M_H_CPU1_SB_DQ<10>                                                
P  NNAMEm6256 M_H_CPU1_SB_DQ<0>                                                 
P  NNAMEm6257 M_H_CPU1_SB_CS_N<1>                                               
P  NNAMEm6258 M_H_CPU1_SB_CS_N<0>                                               
P  NNAMEm6259 M_H_CPU1_SB_CB<7>                                                 
P  NNAMEm6260 M_H_CPU1_SB_CB<6>                                                 
P  NNAMEm6261 M_H_CPU1_SB_CB<5>                                                 
P  NNAMEm6262 M_H_CPU1_SB_CB<4>                                                 
P  NNAMEm6263 M_H_CPU1_SB_CB<3>                                                 
P  NNAMEm6264 M_H_CPU1_SB_CB<2>                                                 
P  NNAMEm6265 M_H_CPU1_SB_CB<1>                                                 
P  NNAMEm6266 M_H_CPU1_SB_CB<0>                                                 
P  NNAMEm6267 M_H_CPU1_SB_CA<6>                                                 
P  NNAMEm6268 M_H_CPU1_SB_CA<5>                                                 
P  NNAMEm6269 M_H_CPU1_SB_CA<4>                                                 
P  NNAMEm6270 M_H_CPU1_SB_CA<3>                                                 
P  NNAMEm6271 M_H_CPU1_SB_CA<2>                                                 
P  NNAMEm6272 M_H_CPU1_SB_CA<1>                                                 
P  NNAMEm6273 M_H_CPU1_SB_CA<0>                                                 
P  NNAMEm6274 M_H_CPU1_SA_RSP<0>                                                
P  NNAMEm6275 M_H_CPU1_SA_PAR                                                   
P  NNAMEm6276 M_H_CPU1_SA_DQS_DP<9>                                             
P  NNAMEm6277 M_H_CPU1_SA_DQS_DP<8>                                             
P  NNAMEm6278 M_H_CPU1_SA_DQS_DP<7>                                             
P  NNAMEm6279 M_H_CPU1_SA_DQS_DP<6>                                             
P  NNAMEm6280 M_H_CPU1_SA_DQS_DP<5>                                             
P  NNAMEm6281 M_H_CPU1_SA_DQS_DP<4>                                             
P  NNAMEm6282 M_H_CPU1_SA_DQS_DP<3>                                             
P  NNAMEm6283 M_H_CPU1_SA_DQS_DP<2>                                             
P  NNAMEm6284 M_H_CPU1_SA_DQS_DP<1>                                             
P  NNAMEm6285 M_H_CPU1_SA_DQS_DP<0>                                             
P  NNAMEm6286 M_H_CPU1_SA_DQS_DN<9>                                             
P  NNAMEm6287 M_H_CPU1_SA_DQS_DN<8>                                             
P  NNAMEm6288 M_H_CPU1_SA_DQS_DN<7>                                             
P  NNAMEm6289 M_H_CPU1_SA_DQS_DN<6>                                             
P  NNAMEm6290 M_H_CPU1_SA_DQS_DN<5>                                             
P  NNAMEm6291 M_H_CPU1_SA_DQS_DN<4>                                             
P  NNAMEm6292 M_H_CPU1_SA_DQS_DN<3>                                             
P  NNAMEm6293 M_H_CPU1_SA_DQS_DN<2>                                             
P  NNAMEm6294 M_H_CPU1_SA_DQS_DN<1>                                             
P  NNAMEm6295 M_H_CPU1_SA_DQS_DN<0>                                             
P  NNAMEm6296 M_H_CPU1_SA_DQ<9>                                                 
P  NNAMEm6297 M_H_CPU1_SA_DQ<8>                                                 
P  NNAMEm6298 M_H_CPU1_SA_DQ<7>                                                 
P  NNAMEm6299 M_H_CPU1_SA_DQ<6>                                                 
P  NNAMEm6300 M_H_CPU1_SA_DQ<5>                                                 
P  NNAMEm6301 M_H_CPU1_SA_DQ<4>                                                 
P  NNAMEm6302 M_H_CPU1_SA_DQ<3>                                                 
P  NNAMEm6303 M_H_CPU1_SA_DQ<31>                                                
P  NNAMEm6304 M_H_CPU1_SA_DQ<30>                                                
P  NNAMEm6305 M_H_CPU1_SA_DQ<2>                                                 
P  NNAMEm6306 M_H_CPU1_SA_DQ<29>                                                
P  NNAMEm6307 M_H_CPU1_SA_DQ<28>                                                
P  NNAMEm6308 M_H_CPU1_SA_DQ<27>                                                
P  NNAMEm6309 M_H_CPU1_SA_DQ<26>                                                
P  NNAMEm6310 M_H_CPU1_SA_DQ<25>                                                
P  NNAMEm6311 M_H_CPU1_SA_DQ<24>                                                
P  NNAMEm6312 M_H_CPU1_SA_DQ<23>                                                
P  NNAMEm6313 M_H_CPU1_SA_DQ<22>                                                
P  NNAMEm6314 M_H_CPU1_SA_DQ<21>                                                
P  NNAMEm6315 M_H_CPU1_SA_DQ<20>                                                
P  NNAMEm6316 M_H_CPU1_SA_DQ<1>                                                 
P  NNAMEm6317 M_H_CPU1_SA_DQ<19>                                                
P  NNAMEm6318 M_H_CPU1_SA_DQ<18>                                                
P  NNAMEm6319 M_H_CPU1_SA_DQ<17>                                                
P  NNAMEm6320 M_H_CPU1_SA_DQ<16>                                                
P  NNAMEm6321 M_H_CPU1_SA_DQ<15>                                                
P  NNAMEm6322 M_H_CPU1_SA_DQ<14>                                                
P  NNAMEm6323 M_H_CPU1_SA_DQ<13>                                                
P  NNAMEm6324 M_H_CPU1_SA_DQ<12>                                                
P  NNAMEm6325 M_H_CPU1_SA_DQ<11>                                                
P  NNAMEm6326 M_H_CPU1_SA_DQ<10>                                                
P  NNAMEm6327 M_H_CPU1_SA_DQ<0>                                                 
P  NNAMEm6328 M_H_CPU1_SA_CS_N<1>                                               
P  NNAMEm6329 M_H_CPU1_SA_CS_N<0>                                               
P  NNAMEm6330 M_H_CPU1_SA_CB<7>                                                 
P  NNAMEm6331 M_H_CPU1_SA_CB<6>                                                 
P  NNAMEm6332 M_H_CPU1_SA_CB<5>                                                 
P  NNAMEm6333 M_H_CPU1_SA_CB<4>                                                 
P  NNAMEm6334 M_H_CPU1_SA_CB<3>                                                 
P  NNAMEm6335 M_H_CPU1_SA_CB<2>                                                 
P  NNAMEm6336 M_H_CPU1_SA_CB<1>                                                 
P  NNAMEm6337 M_H_CPU1_SA_CB<0>                                                 
P  NNAMEm6338 M_H_CPU1_SA_CA<6>                                                 
P  NNAMEm6339 M_H_CPU1_SA_CA<5>                                                 
P  NNAMEm6340 M_H_CPU1_SA_CA<4>                                                 
P  NNAMEm6341 M_H_CPU1_SA_CA<3>                                                 
P  NNAMEm6342 M_H_CPU1_SA_CA<2>                                                 
P  NNAMEm6343 M_H_CPU1_SA_CA<1>                                                 
P  NNAMEm6344 M_H_CPU1_SA_CA<0>                                                 
P  NNAMEm6345 M_H_CPU1_RESET_N                                                  
P  NNAMEm6346 M_H_CPU1_CLK_DP<0>                                                
P  NNAMEm6347 M_H_CPU1_CLK_DN<0>                                                
P  NNAMEm6348 M_H_CPU1_ALERT_R_N                                                
P  NNAMEm6349 M_H_CPU1_ALERT_N                                                  
P  NNAMEm6350 M_H_CPU0_SB_RSP<0>                                                
P  NNAMEm6351 M_H_CPU0_SB_PAR                                                   
P  NNAMEm6352 M_H_CPU0_SB_DQS_DP<9>                                             
P  NNAMEm6353 M_H_CPU0_SB_DQS_DP<8>                                             
P  NNAMEm6354 M_H_CPU0_SB_DQS_DP<7>                                             
P  NNAMEm6355 M_H_CPU0_SB_DQS_DP<6>                                             
P  NNAMEm6356 M_H_CPU0_SB_DQS_DP<5>                                             
P  NNAMEm6357 M_H_CPU0_SB_DQS_DP<4>                                             
P  NNAMEm6358 M_H_CPU0_SB_DQS_DP<3>                                             
P  NNAMEm6359 M_H_CPU0_SB_DQS_DP<2>                                             
P  NNAMEm6360 M_H_CPU0_SB_DQS_DP<1>                                             
P  NNAMEm6361 M_H_CPU0_SB_DQS_DP<0>                                             
P  NNAMEm6362 M_H_CPU0_SB_DQS_DN<9>                                             
P  NNAMEm6363 M_H_CPU0_SB_DQS_DN<8>                                             
P  NNAMEm6364 M_H_CPU0_SB_DQS_DN<7>                                             
P  NNAMEm6365 M_H_CPU0_SB_DQS_DN<6>                                             
P  NNAMEm6366 M_H_CPU0_SB_DQS_DN<5>                                             
P  NNAMEm6367 M_H_CPU0_SB_DQS_DN<4>                                             
P  NNAMEm6368 M_H_CPU0_SB_DQS_DN<3>                                             
P  NNAMEm6369 M_H_CPU0_SB_DQS_DN<2>                                             
P  NNAMEm6370 M_H_CPU0_SB_DQS_DN<1>                                             
P  NNAMEm6371 M_H_CPU0_SB_DQS_DN<0>                                             
P  NNAMEm6372 M_H_CPU0_SB_DQ<9>                                                 
P  NNAMEm6373 M_H_CPU0_SB_DQ<8>                                                 
P  NNAMEm6374 M_H_CPU0_SB_DQ<7>                                                 
P  NNAMEm6375 M_H_CPU0_SB_DQ<6>                                                 
P  NNAMEm6376 M_H_CPU0_SB_DQ<5>                                                 
P  NNAMEm6377 M_H_CPU0_SB_DQ<4>                                                 
P  NNAMEm6378 M_H_CPU0_SB_DQ<3>                                                 
P  NNAMEm6379 M_H_CPU0_SB_DQ<31>                                                
P  NNAMEm6380 M_H_CPU0_SB_DQ<30>                                                
P  NNAMEm6381 M_H_CPU0_SB_DQ<2>                                                 
P  NNAMEm6382 M_H_CPU0_SB_DQ<29>                                                
P  NNAMEm6383 M_H_CPU0_SB_DQ<28>                                                
P  NNAMEm6384 M_H_CPU0_SB_DQ<27>                                                
P  NNAMEm6385 M_H_CPU0_SB_DQ<26>                                                
P  NNAMEm6386 M_H_CPU0_SB_DQ<25>                                                
P  NNAMEm6387 M_H_CPU0_SB_DQ<24>                                                
P  NNAMEm6388 M_H_CPU0_SB_DQ<23>                                                
P  NNAMEm6389 M_H_CPU0_SB_DQ<22>                                                
P  NNAMEm6390 M_H_CPU0_SB_DQ<21>                                                
P  NNAMEm6391 M_H_CPU0_SB_DQ<20>                                                
P  NNAMEm6392 M_H_CPU0_SB_DQ<1>                                                 
P  NNAMEm6393 M_H_CPU0_SB_DQ<19>                                                
P  NNAMEm6394 M_H_CPU0_SB_DQ<18>                                                
P  NNAMEm6395 M_H_CPU0_SB_DQ<17>                                                
P  NNAMEm6396 M_H_CPU0_SB_DQ<16>                                                
P  NNAMEm6397 M_H_CPU0_SB_DQ<15>                                                
P  NNAMEm6398 M_H_CPU0_SB_DQ<14>                                                
P  NNAMEm6399 M_H_CPU0_SB_DQ<13>                                                
P  NNAMEm6400 M_H_CPU0_SB_DQ<12>                                                
P  NNAMEm6401 M_H_CPU0_SB_DQ<11>                                                
P  NNAMEm6402 M_H_CPU0_SB_DQ<10>                                                
P  NNAMEm6403 M_H_CPU0_SB_DQ<0>                                                 
P  NNAMEm6404 M_H_CPU0_SB_CS_N<1>                                               
P  NNAMEm6405 M_H_CPU0_SB_CS_N<0>                                               
P  NNAMEm6406 M_H_CPU0_SB_CB<7>                                                 
P  NNAMEm6407 M_H_CPU0_SB_CB<6>                                                 
P  NNAMEm6408 M_H_CPU0_SB_CB<5>                                                 
P  NNAMEm6409 M_H_CPU0_SB_CB<4>                                                 
P  NNAMEm6410 M_H_CPU0_SB_CB<3>                                                 
P  NNAMEm6411 M_H_CPU0_SB_CB<2>                                                 
P  NNAMEm6412 M_H_CPU0_SB_CB<1>                                                 
P  NNAMEm6413 M_H_CPU0_SB_CB<0>                                                 
P  NNAMEm6414 M_H_CPU0_SB_CA<6>                                                 
P  NNAMEm6415 M_H_CPU0_SB_CA<5>                                                 
P  NNAMEm6416 M_H_CPU0_SB_CA<4>                                                 
P  NNAMEm6417 M_H_CPU0_SB_CA<3>                                                 
P  NNAMEm6418 M_H_CPU0_SB_CA<2>                                                 
P  NNAMEm6419 M_H_CPU0_SB_CA<1>                                                 
P  NNAMEm6420 M_H_CPU0_SB_CA<0>                                                 
P  NNAMEm6421 M_H_CPU0_SA_RSP<0>                                                
P  NNAMEm6422 M_H_CPU0_SA_PAR                                                   
P  NNAMEm6423 M_H_CPU0_SA_DQS_DP<9>                                             
P  NNAMEm6424 M_H_CPU0_SA_DQS_DP<8>                                             
P  NNAMEm6425 M_H_CPU0_SA_DQS_DP<7>                                             
P  NNAMEm6426 M_H_CPU0_SA_DQS_DP<6>                                             
P  NNAMEm6427 M_H_CPU0_SA_DQS_DP<5>                                             
P  NNAMEm6428 M_H_CPU0_SA_DQS_DP<4>                                             
P  NNAMEm6429 M_H_CPU0_SA_DQS_DP<3>                                             
P  NNAMEm6430 M_H_CPU0_SA_DQS_DP<2>                                             
P  NNAMEm6431 M_H_CPU0_SA_DQS_DP<1>                                             
P  NNAMEm6432 M_H_CPU0_SA_DQS_DP<0>                                             
P  NNAMEm6433 M_H_CPU0_SA_DQS_DN<9>                                             
P  NNAMEm6434 M_H_CPU0_SA_DQS_DN<8>                                             
P  NNAMEm6435 M_H_CPU0_SA_DQS_DN<7>                                             
P  NNAMEm6436 M_H_CPU0_SA_DQS_DN<6>                                             
P  NNAMEm6437 M_H_CPU0_SA_DQS_DN<5>                                             
P  NNAMEm6438 M_H_CPU0_SA_DQS_DN<4>                                             
P  NNAMEm6439 M_H_CPU0_SA_DQS_DN<3>                                             
P  NNAMEm6440 M_H_CPU0_SA_DQS_DN<2>                                             
P  NNAMEm6441 M_H_CPU0_SA_DQS_DN<1>                                             
P  NNAMEm6442 M_H_CPU0_SA_DQS_DN<0>                                             
P  NNAMEm6443 M_H_CPU0_SA_DQ<9>                                                 
P  NNAMEm6444 M_H_CPU0_SA_DQ<8>                                                 
P  NNAMEm6445 M_H_CPU0_SA_DQ<7>                                                 
P  NNAMEm6446 M_H_CPU0_SA_DQ<6>                                                 
P  NNAMEm6447 M_H_CPU0_SA_DQ<5>                                                 
P  NNAMEm6448 M_H_CPU0_SA_DQ<4>                                                 
P  NNAMEm6449 M_H_CPU0_SA_DQ<3>                                                 
P  NNAMEm6450 M_H_CPU0_SA_DQ<31>                                                
P  NNAMEm6451 M_H_CPU0_SA_DQ<30>                                                
P  NNAMEm6452 M_H_CPU0_SA_DQ<2>                                                 
P  NNAMEm6453 M_H_CPU0_SA_DQ<29>                                                
P  NNAMEm6454 M_H_CPU0_SA_DQ<28>                                                
P  NNAMEm6455 M_H_CPU0_SA_DQ<27>                                                
P  NNAMEm6456 M_H_CPU0_SA_DQ<26>                                                
P  NNAMEm6457 M_H_CPU0_SA_DQ<25>                                                
P  NNAMEm6458 M_H_CPU0_SA_DQ<24>                                                
P  NNAMEm6459 M_H_CPU0_SA_DQ<23>                                                
P  NNAMEm6460 M_H_CPU0_SA_DQ<22>                                                
P  NNAMEm6461 M_H_CPU0_SA_DQ<21>                                                
P  NNAMEm6462 M_H_CPU0_SA_DQ<20>                                                
P  NNAMEm6463 M_H_CPU0_SA_DQ<1>                                                 
P  NNAMEm6464 M_H_CPU0_SA_DQ<19>                                                
P  NNAMEm6465 M_H_CPU0_SA_DQ<18>                                                
P  NNAMEm6466 M_H_CPU0_SA_DQ<17>                                                
P  NNAMEm6467 M_H_CPU0_SA_DQ<16>                                                
P  NNAMEm6468 M_H_CPU0_SA_DQ<15>                                                
P  NNAMEm6469 M_H_CPU0_SA_DQ<14>                                                
P  NNAMEm6470 M_H_CPU0_SA_DQ<13>                                                
P  NNAMEm6471 M_H_CPU0_SA_DQ<12>                                                
P  NNAMEm6472 M_H_CPU0_SA_DQ<11>                                                
P  NNAMEm6473 M_H_CPU0_SA_DQ<10>                                                
P  NNAMEm6474 M_H_CPU0_SA_DQ<0>                                                 
P  NNAMEm6475 M_H_CPU0_SA_CS_N<1>                                               
P  NNAMEm6476 M_H_CPU0_SA_CS_N<0>                                               
P  NNAMEm6477 M_H_CPU0_SA_CB<7>                                                 
P  NNAMEm6478 M_H_CPU0_SA_CB<6>                                                 
P  NNAMEm6479 M_H_CPU0_SA_CB<5>                                                 
P  NNAMEm6480 M_H_CPU0_SA_CB<4>                                                 
P  NNAMEm6481 M_H_CPU0_SA_CB<3>                                                 
P  NNAMEm6482 M_H_CPU0_SA_CB<2>                                                 
P  NNAMEm6483 M_H_CPU0_SA_CB<1>                                                 
P  NNAMEm6484 M_H_CPU0_SA_CB<0>                                                 
P  NNAMEm6485 M_H_CPU0_SA_CA<6>                                                 
P  NNAMEm6486 M_H_CPU0_SA_CA<5>                                                 
P  NNAMEm6487 M_H_CPU0_SA_CA<4>                                                 
P  NNAMEm6488 M_H_CPU0_SA_CA<3>                                                 
P  NNAMEm6489 M_H_CPU0_SA_CA<2>                                                 
P  NNAMEm6490 M_H_CPU0_SA_CA<1>                                                 
P  NNAMEm6491 M_H_CPU0_SA_CA<0>                                                 
P  NNAMEm6492 M_H_CPU0_RESET_N                                                  
P  NNAMEm6493 M_H_CPU0_CLK_DP<0>                                                
P  NNAMEm6494 M_H_CPU0_CLK_DN<0>                                                
P  NNAMEm6495 M_H_CPU0_ALERT_R_N                                                
P  NNAMEm6496 M_H_CPU0_ALERT_N                                                  
P  NNAMEm6497 M_G_CPU1_SB_RSP<0>                                                
P  NNAMEm6498 M_G_CPU1_SB_PAR                                                   
P  NNAMEm6499 M_G_CPU1_SB_DQS_DP<9>                                             
P  NNAMEm6500 M_G_CPU1_SB_DQS_DP<8>                                             
P  NNAMEm6501 M_G_CPU1_SB_DQS_DP<7>                                             
P  NNAMEm6502 M_G_CPU1_SB_DQS_DP<6>                                             
P  NNAMEm6503 M_G_CPU1_SB_DQS_DP<5>                                             
P  NNAMEm6504 M_G_CPU1_SB_DQS_DP<4>                                             
P  NNAMEm6505 M_G_CPU1_SB_DQS_DP<3>                                             
P  NNAMEm6506 M_G_CPU1_SB_DQS_DP<2>                                             
P  NNAMEm6507 M_G_CPU1_SB_DQS_DP<1>                                             
P  NNAMEm6508 M_G_CPU1_SB_DQS_DP<0>                                             
P  NNAMEm6509 M_G_CPU1_SB_DQS_DN<9>                                             
P  NNAMEm6510 M_G_CPU1_SB_DQS_DN<8>                                             
P  NNAMEm6511 M_G_CPU1_SB_DQS_DN<7>                                             
P  NNAMEm6512 M_G_CPU1_SB_DQS_DN<6>                                             
P  NNAMEm6513 M_G_CPU1_SB_DQS_DN<5>                                             
P  NNAMEm6514 M_G_CPU1_SB_DQS_DN<4>                                             
P  NNAMEm6515 M_G_CPU1_SB_DQS_DN<3>                                             
P  NNAMEm6516 M_G_CPU1_SB_DQS_DN<2>                                             
P  NNAMEm6517 M_G_CPU1_SB_DQS_DN<1>                                             
P  NNAMEm6518 M_G_CPU1_SB_DQS_DN<0>                                             
P  NNAMEm6519 M_G_CPU1_SB_DQ<9>                                                 
P  NNAMEm6520 M_G_CPU1_SB_DQ<8>                                                 
P  NNAMEm6521 M_G_CPU1_SB_DQ<7>                                                 
P  NNAMEm6522 M_G_CPU1_SB_DQ<6>                                                 
P  NNAMEm6523 M_G_CPU1_SB_DQ<5>                                                 
P  NNAMEm6524 M_G_CPU1_SB_DQ<4>                                                 
P  NNAMEm6525 M_G_CPU1_SB_DQ<3>                                                 
P  NNAMEm6526 M_G_CPU1_SB_DQ<31>                                                
P  NNAMEm6527 M_G_CPU1_SB_DQ<30>                                                
P  NNAMEm6528 M_G_CPU1_SB_DQ<2>                                                 
P  NNAMEm6529 M_G_CPU1_SB_DQ<29>                                                
P  NNAMEm6530 M_G_CPU1_SB_DQ<28>                                                
P  NNAMEm6531 M_G_CPU1_SB_DQ<27>                                                
P  NNAMEm6532 M_G_CPU1_SB_DQ<26>                                                
P  NNAMEm6533 M_G_CPU1_SB_DQ<25>                                                
P  NNAMEm6534 M_G_CPU1_SB_DQ<24>                                                
P  NNAMEm6535 M_G_CPU1_SB_DQ<23>                                                
P  NNAMEm6536 M_G_CPU1_SB_DQ<22>                                                
P  NNAMEm6537 M_G_CPU1_SB_DQ<21>                                                
P  NNAMEm6538 M_G_CPU1_SB_DQ<20>                                                
P  NNAMEm6539 M_G_CPU1_SB_DQ<1>                                                 
P  NNAMEm6540 M_G_CPU1_SB_DQ<19>                                                
P  NNAMEm6541 M_G_CPU1_SB_DQ<18>                                                
P  NNAMEm6542 M_G_CPU1_SB_DQ<17>                                                
P  NNAMEm6543 M_G_CPU1_SB_DQ<16>                                                
P  NNAMEm6544 M_G_CPU1_SB_DQ<15>                                                
P  NNAMEm6545 M_G_CPU1_SB_DQ<14>                                                
P  NNAMEm6546 M_G_CPU1_SB_DQ<13>                                                
P  NNAMEm6547 M_G_CPU1_SB_DQ<12>                                                
P  NNAMEm6548 M_G_CPU1_SB_DQ<11>                                                
P  NNAMEm6549 M_G_CPU1_SB_DQ<10>                                                
P  NNAMEm6550 M_G_CPU1_SB_DQ<0>                                                 
P  NNAMEm6551 M_G_CPU1_SB_CS_N<1>                                               
P  NNAMEm6552 M_G_CPU1_SB_CS_N<0>                                               
P  NNAMEm6553 M_G_CPU1_SB_CB<7>                                                 
P  NNAMEm6554 M_G_CPU1_SB_CB<6>                                                 
P  NNAMEm6555 M_G_CPU1_SB_CB<5>                                                 
P  NNAMEm6556 M_G_CPU1_SB_CB<4>                                                 
P  NNAMEm6557 M_G_CPU1_SB_CB<3>                                                 
P  NNAMEm6558 M_G_CPU1_SB_CB<2>                                                 
P  NNAMEm6559 M_G_CPU1_SB_CB<1>                                                 
P  NNAMEm6560 M_G_CPU1_SB_CB<0>                                                 
P  NNAMEm6561 M_G_CPU1_SB_CA<6>                                                 
P  NNAMEm6562 M_G_CPU1_SB_CA<5>                                                 
P  NNAMEm6563 M_G_CPU1_SB_CA<4>                                                 
P  NNAMEm6564 M_G_CPU1_SB_CA<3>                                                 
P  NNAMEm6565 M_G_CPU1_SB_CA<2>                                                 
P  NNAMEm6566 M_G_CPU1_SB_CA<1>                                                 
P  NNAMEm6567 M_G_CPU1_SB_CA<0>                                                 
P  NNAMEm6568 M_G_CPU1_SA_RSP<0>                                                
P  NNAMEm6569 M_G_CPU1_SA_PAR                                                   
P  NNAMEm6570 M_G_CPU1_SA_DQS_DP<9>                                             
P  NNAMEm6571 M_G_CPU1_SA_DQS_DP<8>                                             
P  NNAMEm6572 M_G_CPU1_SA_DQS_DP<7>                                             
P  NNAMEm6573 M_G_CPU1_SA_DQS_DP<6>                                             
P  NNAMEm6574 M_G_CPU1_SA_DQS_DP<5>                                             
P  NNAMEm6575 M_G_CPU1_SA_DQS_DP<4>                                             
P  NNAMEm6576 M_G_CPU1_SA_DQS_DP<3>                                             
P  NNAMEm6577 M_G_CPU1_SA_DQS_DP<2>                                             
P  NNAMEm6578 M_G_CPU1_SA_DQS_DP<1>                                             
P  NNAMEm6579 M_G_CPU1_SA_DQS_DP<0>                                             
P  NNAMEm6580 M_G_CPU1_SA_DQS_DN<9>                                             
P  NNAMEm6581 M_G_CPU1_SA_DQS_DN<8>                                             
P  NNAMEm6582 M_G_CPU1_SA_DQS_DN<7>                                             
P  NNAMEm6583 M_G_CPU1_SA_DQS_DN<6>                                             
P  NNAMEm6584 M_G_CPU1_SA_DQS_DN<5>                                             
P  NNAMEm6585 M_G_CPU1_SA_DQS_DN<4>                                             
P  NNAMEm6586 M_G_CPU1_SA_DQS_DN<3>                                             
P  NNAMEm6587 M_G_CPU1_SA_DQS_DN<2>                                             
P  NNAMEm6588 M_G_CPU1_SA_DQS_DN<1>                                             
P  NNAMEm6589 M_G_CPU1_SA_DQS_DN<0>                                             
P  NNAMEm6590 M_G_CPU1_SA_DQ<9>                                                 
P  NNAMEm6591 M_G_CPU1_SA_DQ<8>                                                 
P  NNAMEm6592 M_G_CPU1_SA_DQ<7>                                                 
P  NNAMEm6593 M_G_CPU1_SA_DQ<6>                                                 
P  NNAMEm6594 M_G_CPU1_SA_DQ<5>                                                 
P  NNAMEm6595 M_G_CPU1_SA_DQ<4>                                                 
P  NNAMEm6596 M_G_CPU1_SA_DQ<3>                                                 
P  NNAMEm6597 M_G_CPU1_SA_DQ<31>                                                
P  NNAMEm6598 M_G_CPU1_SA_DQ<30>                                                
P  NNAMEm6599 M_G_CPU1_SA_DQ<2>                                                 
P  NNAMEm6600 M_G_CPU1_SA_DQ<29>                                                
P  NNAMEm6601 M_G_CPU1_SA_DQ<28>                                                
P  NNAMEm6602 M_G_CPU1_SA_DQ<27>                                                
P  NNAMEm6603 M_G_CPU1_SA_DQ<26>                                                
P  NNAMEm6604 M_G_CPU1_SA_DQ<25>                                                
P  NNAMEm6605 M_G_CPU1_SA_DQ<24>                                                
P  NNAMEm6606 M_G_CPU1_SA_DQ<23>                                                
P  NNAMEm6607 M_G_CPU1_SA_DQ<22>                                                
P  NNAMEm6608 M_G_CPU1_SA_DQ<21>                                                
P  NNAMEm6609 M_G_CPU1_SA_DQ<20>                                                
P  NNAMEm6610 M_G_CPU1_SA_DQ<1>                                                 
P  NNAMEm6611 M_G_CPU1_SA_DQ<19>                                                
P  NNAMEm6612 M_G_CPU1_SA_DQ<18>                                                
P  NNAMEm6613 M_G_CPU1_SA_DQ<17>                                                
P  NNAMEm6614 M_G_CPU1_SA_DQ<16>                                                
P  NNAMEm6615 M_G_CPU1_SA_DQ<15>                                                
P  NNAMEm6616 M_G_CPU1_SA_DQ<14>                                                
P  NNAMEm6617 M_G_CPU1_SA_DQ<13>                                                
P  NNAMEm6618 M_G_CPU1_SA_DQ<12>                                                
P  NNAMEm6619 M_G_CPU1_SA_DQ<11>                                                
P  NNAMEm6620 M_G_CPU1_SA_DQ<10>                                                
P  NNAMEm6621 M_G_CPU1_SA_DQ<0>                                                 
P  NNAMEm6622 M_G_CPU1_SA_CS_N<1>                                               
P  NNAMEm6623 M_G_CPU1_SA_CS_N<0>                                               
P  NNAMEm6624 M_G_CPU1_SA_CB<7>                                                 
P  NNAMEm6625 M_G_CPU1_SA_CB<6>                                                 
P  NNAMEm6626 M_G_CPU1_SA_CB<5>                                                 
P  NNAMEm6627 M_G_CPU1_SA_CB<4>                                                 
P  NNAMEm6628 M_G_CPU1_SA_CB<3>                                                 
P  NNAMEm6629 M_G_CPU1_SA_CB<2>                                                 
P  NNAMEm6630 M_G_CPU1_SA_CB<1>                                                 
P  NNAMEm6631 M_G_CPU1_SA_CB<0>                                                 
P  NNAMEm6632 M_G_CPU1_SA_CA<6>                                                 
P  NNAMEm6633 M_G_CPU1_SA_CA<5>                                                 
P  NNAMEm6634 M_G_CPU1_SA_CA<4>                                                 
P  NNAMEm6635 M_G_CPU1_SA_CA<3>                                                 
P  NNAMEm6636 M_G_CPU1_SA_CA<2>                                                 
P  NNAMEm6637 M_G_CPU1_SA_CA<1>                                                 
P  NNAMEm6638 M_G_CPU1_SA_CA<0>                                                 
P  NNAMEm6639 M_G_CPU1_RESET_N                                                  
P  NNAMEm6640 M_G_CPU1_CLK_DP<0>                                                
P  NNAMEm6641 M_G_CPU1_CLK_DN<0>                                                
P  NNAMEm6642 M_G_CPU1_ALERT_R_N                                                
P  NNAMEm6643 M_G_CPU1_ALERT_N                                                  
P  NNAMEm6644 M_G_CPU0_SB_RSP<0>                                                
P  NNAMEm6645 M_G_CPU0_SB_PAR                                                   
P  NNAMEm6646 M_G_CPU0_SB_DQS_DP<9>                                             
P  NNAMEm6647 M_G_CPU0_SB_DQS_DP<8>                                             
P  NNAMEm6648 M_G_CPU0_SB_DQS_DP<7>                                             
P  NNAMEm6649 M_G_CPU0_SB_DQS_DP<6>                                             
P  NNAMEm6650 M_G_CPU0_SB_DQS_DP<5>                                             
P  NNAMEm6651 M_G_CPU0_SB_DQS_DP<4>                                             
P  NNAMEm6652 M_G_CPU0_SB_DQS_DP<3>                                             
P  NNAMEm6653 M_G_CPU0_SB_DQS_DP<2>                                             
P  NNAMEm6654 M_G_CPU0_SB_DQS_DP<1>                                             
P  NNAMEm6655 M_G_CPU0_SB_DQS_DP<0>                                             
P  NNAMEm6656 M_G_CPU0_SB_DQS_DN<9>                                             
P  NNAMEm6657 M_G_CPU0_SB_DQS_DN<8>                                             
P  NNAMEm6658 M_G_CPU0_SB_DQS_DN<7>                                             
P  NNAMEm6659 M_G_CPU0_SB_DQS_DN<6>                                             
P  NNAMEm6660 M_G_CPU0_SB_DQS_DN<5>                                             
P  NNAMEm6661 M_G_CPU0_SB_DQS_DN<4>                                             
P  NNAMEm6662 M_G_CPU0_SB_DQS_DN<3>                                             
P  NNAMEm6663 M_G_CPU0_SB_DQS_DN<2>                                             
P  NNAMEm6664 M_G_CPU0_SB_DQS_DN<1>                                             
P  NNAMEm6665 M_G_CPU0_SB_DQS_DN<0>                                             
P  NNAMEm6666 M_G_CPU0_SB_DQ<9>                                                 
P  NNAMEm6667 M_G_CPU0_SB_DQ<8>                                                 
P  NNAMEm6668 M_G_CPU0_SB_DQ<7>                                                 
P  NNAMEm6669 M_G_CPU0_SB_DQ<6>                                                 
P  NNAMEm6670 M_G_CPU0_SB_DQ<5>                                                 
P  NNAMEm6671 M_G_CPU0_SB_DQ<4>                                                 
P  NNAMEm6672 M_G_CPU0_SB_DQ<3>                                                 
P  NNAMEm6673 M_G_CPU0_SB_DQ<31>                                                
P  NNAMEm6674 M_G_CPU0_SB_DQ<30>                                                
P  NNAMEm6675 M_G_CPU0_SB_DQ<2>                                                 
P  NNAMEm6676 M_G_CPU0_SB_DQ<29>                                                
P  NNAMEm6677 M_G_CPU0_SB_DQ<28>                                                
P  NNAMEm6678 M_G_CPU0_SB_DQ<27>                                                
P  NNAMEm6679 M_G_CPU0_SB_DQ<26>                                                
P  NNAMEm6680 M_G_CPU0_SB_DQ<25>                                                
P  NNAMEm6681 M_G_CPU0_SB_DQ<24>                                                
P  NNAMEm6682 M_G_CPU0_SB_DQ<23>                                                
P  NNAMEm6683 M_G_CPU0_SB_DQ<22>                                                
P  NNAMEm6684 M_G_CPU0_SB_DQ<21>                                                
P  NNAMEm6685 M_G_CPU0_SB_DQ<20>                                                
P  NNAMEm6686 M_G_CPU0_SB_DQ<1>                                                 
P  NNAMEm6687 M_G_CPU0_SB_DQ<19>                                                
P  NNAMEm6688 M_G_CPU0_SB_DQ<18>                                                
P  NNAMEm6689 M_G_CPU0_SB_DQ<17>                                                
P  NNAMEm6690 M_G_CPU0_SB_DQ<16>                                                
P  NNAMEm6691 M_G_CPU0_SB_DQ<15>                                                
P  NNAMEm6692 M_G_CPU0_SB_DQ<14>                                                
P  NNAMEm6693 M_G_CPU0_SB_DQ<13>                                                
P  NNAMEm6694 M_G_CPU0_SB_DQ<12>                                                
P  NNAMEm6695 M_G_CPU0_SB_DQ<11>                                                
P  NNAMEm6696 M_G_CPU0_SB_DQ<10>                                                
P  NNAMEm6697 M_G_CPU0_SB_DQ<0>                                                 
P  NNAMEm6698 M_G_CPU0_SB_CS_N<1>                                               
P  NNAMEm6699 M_G_CPU0_SB_CS_N<0>                                               
P  NNAMEm6700 M_G_CPU0_SB_CB<7>                                                 
P  NNAMEm6701 M_G_CPU0_SB_CB<6>                                                 
P  NNAMEm6702 M_G_CPU0_SB_CB<5>                                                 
P  NNAMEm6703 M_G_CPU0_SB_CB<4>                                                 
P  NNAMEm6704 M_G_CPU0_SB_CB<3>                                                 
P  NNAMEm6705 M_G_CPU0_SB_CB<2>                                                 
P  NNAMEm6706 M_G_CPU0_SB_CB<1>                                                 
P  NNAMEm6707 M_G_CPU0_SB_CB<0>                                                 
P  NNAMEm6708 M_G_CPU0_SB_CA<6>                                                 
P  NNAMEm6709 M_G_CPU0_SB_CA<5>                                                 
P  NNAMEm6710 M_G_CPU0_SB_CA<4>                                                 
P  NNAMEm6711 M_G_CPU0_SB_CA<3>                                                 
P  NNAMEm6712 M_G_CPU0_SB_CA<2>                                                 
P  NNAMEm6713 M_G_CPU0_SB_CA<1>                                                 
P  NNAMEm6714 M_G_CPU0_SB_CA<0>                                                 
P  NNAMEm6715 M_G_CPU0_SA_RSP<0>                                                
P  NNAMEm6716 M_G_CPU0_SA_PAR                                                   
P  NNAMEm6717 M_G_CPU0_SA_DQS_DP<9>                                             
P  NNAMEm6718 M_G_CPU0_SA_DQS_DP<8>                                             
P  NNAMEm6719 M_G_CPU0_SA_DQS_DP<7>                                             
P  NNAMEm6720 M_G_CPU0_SA_DQS_DP<6>                                             
P  NNAMEm6721 M_G_CPU0_SA_DQS_DP<5>                                             
P  NNAMEm6722 M_G_CPU0_SA_DQS_DP<4>                                             
P  NNAMEm6723 M_G_CPU0_SA_DQS_DP<3>                                             
P  NNAMEm6724 M_G_CPU0_SA_DQS_DP<2>                                             
P  NNAMEm6725 M_G_CPU0_SA_DQS_DP<1>                                             
P  NNAMEm6726 M_G_CPU0_SA_DQS_DP<0>                                             
P  NNAMEm6727 M_G_CPU0_SA_DQS_DN<9>                                             
P  NNAMEm6728 M_G_CPU0_SA_DQS_DN<8>                                             
P  NNAMEm6729 M_G_CPU0_SA_DQS_DN<7>                                             
P  NNAMEm6730 M_G_CPU0_SA_DQS_DN<6>                                             
P  NNAMEm6731 M_G_CPU0_SA_DQS_DN<5>                                             
P  NNAMEm6732 M_G_CPU0_SA_DQS_DN<4>                                             
P  NNAMEm6733 M_G_CPU0_SA_DQS_DN<3>                                             
P  NNAMEm6734 M_G_CPU0_SA_DQS_DN<2>                                             
P  NNAMEm6735 M_G_CPU0_SA_DQS_DN<1>                                             
P  NNAMEm6736 M_G_CPU0_SA_DQS_DN<0>                                             
P  NNAMEm6737 M_G_CPU0_SA_DQ<9>                                                 
P  NNAMEm6738 M_G_CPU0_SA_DQ<8>                                                 
P  NNAMEm6739 M_G_CPU0_SA_DQ<7>                                                 
P  NNAMEm6740 M_G_CPU0_SA_DQ<6>                                                 
P  NNAMEm6741 M_G_CPU0_SA_DQ<5>                                                 
P  NNAMEm6742 M_G_CPU0_SA_DQ<4>                                                 
P  NNAMEm6743 M_G_CPU0_SA_DQ<3>                                                 
P  NNAMEm6744 M_G_CPU0_SA_DQ<31>                                                
P  NNAMEm6745 M_G_CPU0_SA_DQ<30>                                                
P  NNAMEm6746 M_G_CPU0_SA_DQ<2>                                                 
P  NNAMEm6747 M_G_CPU0_SA_DQ<29>                                                
P  NNAMEm6748 M_G_CPU0_SA_DQ<28>                                                
P  NNAMEm6749 M_G_CPU0_SA_DQ<27>                                                
P  NNAMEm6750 M_G_CPU0_SA_DQ<26>                                                
P  NNAMEm6751 M_G_CPU0_SA_DQ<25>                                                
P  NNAMEm6752 M_G_CPU0_SA_DQ<24>                                                
P  NNAMEm6753 M_G_CPU0_SA_DQ<23>                                                
P  NNAMEm6754 M_G_CPU0_SA_DQ<22>                                                
P  NNAMEm6755 M_G_CPU0_SA_DQ<21>                                                
P  NNAMEm6756 M_G_CPU0_SA_DQ<20>                                                
P  NNAMEm6757 M_G_CPU0_SA_DQ<1>                                                 
P  NNAMEm6758 M_G_CPU0_SA_DQ<19>                                                
P  NNAMEm6759 M_G_CPU0_SA_DQ<18>                                                
P  NNAMEm6760 M_G_CPU0_SA_DQ<17>                                                
P  NNAMEm6761 M_G_CPU0_SA_DQ<16>                                                
P  NNAMEm6762 M_G_CPU0_SA_DQ<15>                                                
P  NNAMEm6763 M_G_CPU0_SA_DQ<14>                                                
P  NNAMEm6764 M_G_CPU0_SA_DQ<13>                                                
P  NNAMEm6765 M_G_CPU0_SA_DQ<12>                                                
P  NNAMEm6766 M_G_CPU0_SA_DQ<11>                                                
P  NNAMEm6767 M_G_CPU0_SA_DQ<10>                                                
P  NNAMEm6768 M_G_CPU0_SA_DQ<0>                                                 
P  NNAMEm6769 M_G_CPU0_SA_CS_N<1>                                               
P  NNAMEm6770 M_G_CPU0_SA_CS_N<0>                                               
P  NNAMEm6771 M_G_CPU0_SA_CB<7>                                                 
P  NNAMEm6772 M_G_CPU0_SA_CB<6>                                                 
P  NNAMEm6773 M_G_CPU0_SA_CB<5>                                                 
P  NNAMEm6774 M_G_CPU0_SA_CB<4>                                                 
P  NNAMEm6775 M_G_CPU0_SA_CB<3>                                                 
P  NNAMEm6776 M_G_CPU0_SA_CB<2>                                                 
P  NNAMEm6777 M_G_CPU0_SA_CB<1>                                                 
P  NNAMEm6778 M_G_CPU0_SA_CB<0>                                                 
P  NNAMEm6779 M_G_CPU0_SA_CA<6>                                                 
P  NNAMEm6780 M_G_CPU0_SA_CA<5>                                                 
P  NNAMEm6781 M_G_CPU0_SA_CA<4>                                                 
P  NNAMEm6782 M_G_CPU0_SA_CA<3>                                                 
P  NNAMEm6783 M_G_CPU0_SA_CA<2>                                                 
P  NNAMEm6784 M_G_CPU0_SA_CA<1>                                                 
P  NNAMEm6785 M_G_CPU0_SA_CA<0>                                                 
P  NNAMEm6786 M_G_CPU0_RESET_N                                                  
P  NNAMEm6787 M_G_CPU0_CLK_DP<0>                                                
P  NNAMEm6788 M_G_CPU0_CLK_DN<0>                                                
P  NNAMEm6789 M_G_CPU0_ALERT_R_N                                                
P  NNAMEm6790 M_G_CPU0_ALERT_N                                                  
P  NNAMEm6791 M_F_CPU1_SB_RSP<0>                                                
P  NNAMEm6792 M_F_CPU1_SB_PAR                                                   
P  NNAMEm6793 M_F_CPU1_SB_DQS_DP<9>                                             
P  NNAMEm6794 M_F_CPU1_SB_DQS_DP<8>                                             
P  NNAMEm6795 M_F_CPU1_SB_DQS_DP<7>                                             
P  NNAMEm6796 M_F_CPU1_SB_DQS_DP<6>                                             
P  NNAMEm6797 M_F_CPU1_SB_DQS_DP<5>                                             
P  NNAMEm6798 M_F_CPU1_SB_DQS_DP<4>                                             
P  NNAMEm6799 M_F_CPU1_SB_DQS_DP<3>                                             
P  NNAMEm6800 M_F_CPU1_SB_DQS_DP<2>                                             
P  NNAMEm6801 M_F_CPU1_SB_DQS_DP<1>                                             
P  NNAMEm6802 M_F_CPU1_SB_DQS_DP<0>                                             
P  NNAMEm6803 M_F_CPU1_SB_DQS_DN<9>                                             
P  NNAMEm6804 M_F_CPU1_SB_DQS_DN<8>                                             
P  NNAMEm6805 M_F_CPU1_SB_DQS_DN<7>                                             
P  NNAMEm6806 M_F_CPU1_SB_DQS_DN<6>                                             
P  NNAMEm6807 M_F_CPU1_SB_DQS_DN<5>                                             
P  NNAMEm6808 M_F_CPU1_SB_DQS_DN<4>                                             
P  NNAMEm6809 M_F_CPU1_SB_DQS_DN<3>                                             
P  NNAMEm6810 M_F_CPU1_SB_DQS_DN<2>                                             
P  NNAMEm6811 M_F_CPU1_SB_DQS_DN<1>                                             
P  NNAMEm6812 M_F_CPU1_SB_DQS_DN<0>                                             
P  NNAMEm6813 M_F_CPU1_SB_DQ<9>                                                 
P  NNAMEm6814 M_F_CPU1_SB_DQ<8>                                                 
P  NNAMEm6815 M_F_CPU1_SB_DQ<7>                                                 
P  NNAMEm6816 M_F_CPU1_SB_DQ<6>                                                 
P  NNAMEm6817 M_F_CPU1_SB_DQ<5>                                                 
P  NNAMEm6818 M_F_CPU1_SB_DQ<4>                                                 
P  NNAMEm6819 M_F_CPU1_SB_DQ<3>                                                 
P  NNAMEm6820 M_F_CPU1_SB_DQ<31>                                                
P  NNAMEm6821 M_F_CPU1_SB_DQ<30>                                                
P  NNAMEm6822 M_F_CPU1_SB_DQ<2>                                                 
P  NNAMEm6823 M_F_CPU1_SB_DQ<29>                                                
P  NNAMEm6824 M_F_CPU1_SB_DQ<28>                                                
P  NNAMEm6825 M_F_CPU1_SB_DQ<27>                                                
P  NNAMEm6826 M_F_CPU1_SB_DQ<26>                                                
P  NNAMEm6827 M_F_CPU1_SB_DQ<25>                                                
P  NNAMEm6828 M_F_CPU1_SB_DQ<24>                                                
P  NNAMEm6829 M_F_CPU1_SB_DQ<23>                                                
P  NNAMEm6830 M_F_CPU1_SB_DQ<22>                                                
P  NNAMEm6831 M_F_CPU1_SB_DQ<21>                                                
P  NNAMEm6832 M_F_CPU1_SB_DQ<20>                                                
P  NNAMEm6833 M_F_CPU1_SB_DQ<1>                                                 
P  NNAMEm6834 M_F_CPU1_SB_DQ<19>                                                
P  NNAMEm6835 M_F_CPU1_SB_DQ<18>                                                
P  NNAMEm6836 M_F_CPU1_SB_DQ<17>                                                
P  NNAMEm6837 M_F_CPU1_SB_DQ<16>                                                
P  NNAMEm6838 M_F_CPU1_SB_DQ<15>                                                
P  NNAMEm6839 M_F_CPU1_SB_DQ<14>                                                
P  NNAMEm6840 M_F_CPU1_SB_DQ<13>                                                
P  NNAMEm6841 M_F_CPU1_SB_DQ<12>                                                
P  NNAMEm6842 M_F_CPU1_SB_DQ<11>                                                
P  NNAMEm6843 M_F_CPU1_SB_DQ<10>                                                
P  NNAMEm6844 M_F_CPU1_SB_DQ<0>                                                 
P  NNAMEm6845 M_F_CPU1_SB_CS_N<1>                                               
P  NNAMEm6846 M_F_CPU1_SB_CS_N<0>                                               
P  NNAMEm6847 M_F_CPU1_SB_CB<7>                                                 
P  NNAMEm6848 M_F_CPU1_SB_CB<6>                                                 
P  NNAMEm6849 M_F_CPU1_SB_CB<5>                                                 
P  NNAMEm6850 M_F_CPU1_SB_CB<4>                                                 
P  NNAMEm6851 M_F_CPU1_SB_CB<3>                                                 
P  NNAMEm6852 M_F_CPU1_SB_CB<2>                                                 
P  NNAMEm6853 M_F_CPU1_SB_CB<1>                                                 
P  NNAMEm6854 M_F_CPU1_SB_CB<0>                                                 
P  NNAMEm6855 M_F_CPU1_SB_CA<6>                                                 
P  NNAMEm6856 M_F_CPU1_SB_CA<5>                                                 
P  NNAMEm6857 M_F_CPU1_SB_CA<4>                                                 
P  NNAMEm6858 M_F_CPU1_SB_CA<3>                                                 
P  NNAMEm6859 M_F_CPU1_SB_CA<2>                                                 
P  NNAMEm6860 M_F_CPU1_SB_CA<1>                                                 
P  NNAMEm6861 M_F_CPU1_SB_CA<0>                                                 
P  NNAMEm6862 M_F_CPU1_SA_RSP<0>                                                
P  NNAMEm6863 M_F_CPU1_SA_PAR                                                   
P  NNAMEm6864 M_F_CPU1_SA_DQS_DP<9>                                             
P  NNAMEm6865 M_F_CPU1_SA_DQS_DP<8>                                             
P  NNAMEm6866 M_F_CPU1_SA_DQS_DP<7>                                             
P  NNAMEm6867 M_F_CPU1_SA_DQS_DP<6>                                             
P  NNAMEm6868 M_F_CPU1_SA_DQS_DP<5>                                             
P  NNAMEm6869 M_F_CPU1_SA_DQS_DP<4>                                             
P  NNAMEm6870 M_F_CPU1_SA_DQS_DP<3>                                             
P  NNAMEm6871 M_F_CPU1_SA_DQS_DP<2>                                             
P  NNAMEm6872 M_F_CPU1_SA_DQS_DP<1>                                             
P  NNAMEm6873 M_F_CPU1_SA_DQS_DP<0>                                             
P  NNAMEm6874 M_F_CPU1_SA_DQS_DN<9>                                             
P  NNAMEm6875 M_F_CPU1_SA_DQS_DN<8>                                             
P  NNAMEm6876 M_F_CPU1_SA_DQS_DN<7>                                             
P  NNAMEm6877 M_F_CPU1_SA_DQS_DN<6>                                             
P  NNAMEm6878 M_F_CPU1_SA_DQS_DN<5>                                             
P  NNAMEm6879 M_F_CPU1_SA_DQS_DN<4>                                             
P  NNAMEm6880 M_F_CPU1_SA_DQS_DN<3>                                             
P  NNAMEm6881 M_F_CPU1_SA_DQS_DN<2>                                             
P  NNAMEm6882 M_F_CPU1_SA_DQS_DN<1>                                             
P  NNAMEm6883 M_F_CPU1_SA_DQS_DN<0>                                             
P  NNAMEm6884 M_F_CPU1_SA_DQ<9>                                                 
P  NNAMEm6885 M_F_CPU1_SA_DQ<8>                                                 
P  NNAMEm6886 M_F_CPU1_SA_DQ<7>                                                 
P  NNAMEm6887 M_F_CPU1_SA_DQ<6>                                                 
P  NNAMEm6888 M_F_CPU1_SA_DQ<5>                                                 
P  NNAMEm6889 M_F_CPU1_SA_DQ<4>                                                 
P  NNAMEm6890 M_F_CPU1_SA_DQ<3>                                                 
P  NNAMEm6891 M_F_CPU1_SA_DQ<31>                                                
P  NNAMEm6892 M_F_CPU1_SA_DQ<30>                                                
P  NNAMEm6893 M_F_CPU1_SA_DQ<2>                                                 
P  NNAMEm6894 M_F_CPU1_SA_DQ<29>                                                
P  NNAMEm6895 M_F_CPU1_SA_DQ<28>                                                
P  NNAMEm6896 M_F_CPU1_SA_DQ<27>                                                
P  NNAMEm6897 M_F_CPU1_SA_DQ<26>                                                
P  NNAMEm6898 M_F_CPU1_SA_DQ<25>                                                
P  NNAMEm6899 M_F_CPU1_SA_DQ<24>                                                
P  NNAMEm6900 M_F_CPU1_SA_DQ<23>                                                
P  NNAMEm6901 M_F_CPU1_SA_DQ<22>                                                
P  NNAMEm6902 M_F_CPU1_SA_DQ<21>                                                
P  NNAMEm6903 M_F_CPU1_SA_DQ<20>                                                
P  NNAMEm6904 M_F_CPU1_SA_DQ<1>                                                 
P  NNAMEm6905 M_F_CPU1_SA_DQ<19>                                                
P  NNAMEm6906 M_F_CPU1_SA_DQ<18>                                                
P  NNAMEm6907 M_F_CPU1_SA_DQ<17>                                                
P  NNAMEm6908 M_F_CPU1_SA_DQ<16>                                                
P  NNAMEm6909 M_F_CPU1_SA_DQ<15>                                                
P  NNAMEm6910 M_F_CPU1_SA_DQ<14>                                                
P  NNAMEm6911 M_F_CPU1_SA_DQ<13>                                                
P  NNAMEm6912 M_F_CPU1_SA_DQ<12>                                                
P  NNAMEm6913 M_F_CPU1_SA_DQ<11>                                                
P  NNAMEm6914 M_F_CPU1_SA_DQ<10>                                                
P  NNAMEm6915 M_F_CPU1_SA_DQ<0>                                                 
P  NNAMEm6916 M_F_CPU1_SA_CS_N<1>                                               
P  NNAMEm6917 M_F_CPU1_SA_CS_N<0>                                               
P  NNAMEm6918 M_F_CPU1_SA_CB<7>                                                 
P  NNAMEm6919 M_F_CPU1_SA_CB<6>                                                 
P  NNAMEm6920 M_F_CPU1_SA_CB<5>                                                 
P  NNAMEm6921 M_F_CPU1_SA_CB<4>                                                 
P  NNAMEm6922 M_F_CPU1_SA_CB<3>                                                 
P  NNAMEm6923 M_F_CPU1_SA_CB<2>                                                 
P  NNAMEm6924 M_F_CPU1_SA_CB<1>                                                 
P  NNAMEm6925 M_F_CPU1_SA_CB<0>                                                 
P  NNAMEm6926 M_F_CPU1_SA_CA<6>                                                 
P  NNAMEm6927 M_F_CPU1_SA_CA<5>                                                 
P  NNAMEm6928 M_F_CPU1_SA_CA<4>                                                 
P  NNAMEm6929 M_F_CPU1_SA_CA<3>                                                 
P  NNAMEm6930 M_F_CPU1_SA_CA<2>                                                 
P  NNAMEm6931 M_F_CPU1_SA_CA<1>                                                 
P  NNAMEm6932 M_F_CPU1_SA_CA<0>                                                 
P  NNAMEm6933 M_F_CPU1_RESET_N                                                  
P  NNAMEm6934 M_F_CPU1_CLK_DP<0>                                                
P  NNAMEm6935 M_F_CPU1_CLK_DN<0>                                                
P  NNAMEm6936 M_F_CPU1_ALERT_R_N                                                
P  NNAMEm6937 M_F_CPU1_ALERT_N                                                  
P  NNAMEm6938 M_F_CPU0_SB_RSP<0>                                                
P  NNAMEm6939 M_F_CPU0_SB_PAR                                                   
P  NNAMEm6940 M_F_CPU0_SB_DQS_DP<9>                                             
P  NNAMEm6941 M_F_CPU0_SB_DQS_DP<8>                                             
P  NNAMEm6942 M_F_CPU0_SB_DQS_DP<7>                                             
P  NNAMEm6943 M_F_CPU0_SB_DQS_DP<6>                                             
P  NNAMEm6944 M_F_CPU0_SB_DQS_DP<5>                                             
P  NNAMEm6945 M_F_CPU0_SB_DQS_DP<4>                                             
P  NNAMEm6946 M_F_CPU0_SB_DQS_DP<3>                                             
P  NNAMEm6947 M_F_CPU0_SB_DQS_DP<2>                                             
P  NNAMEm6948 M_F_CPU0_SB_DQS_DP<1>                                             
P  NNAMEm6949 M_F_CPU0_SB_DQS_DP<0>                                             
P  NNAMEm6950 M_F_CPU0_SB_DQS_DN<9>                                             
P  NNAMEm6951 M_F_CPU0_SB_DQS_DN<8>                                             
P  NNAMEm6952 M_F_CPU0_SB_DQS_DN<7>                                             
P  NNAMEm6953 M_F_CPU0_SB_DQS_DN<6>                                             
P  NNAMEm6954 M_F_CPU0_SB_DQS_DN<5>                                             
P  NNAMEm6955 M_F_CPU0_SB_DQS_DN<4>                                             
P  NNAMEm6956 M_F_CPU0_SB_DQS_DN<3>                                             
P  NNAMEm6957 M_F_CPU0_SB_DQS_DN<2>                                             
P  NNAMEm6958 M_F_CPU0_SB_DQS_DN<1>                                             
P  NNAMEm6959 M_F_CPU0_SB_DQS_DN<0>                                             
P  NNAMEm6960 M_F_CPU0_SB_DQ<9>                                                 
P  NNAMEm6961 M_F_CPU0_SB_DQ<8>                                                 
P  NNAMEm6962 M_F_CPU0_SB_DQ<7>                                                 
P  NNAMEm6963 M_F_CPU0_SB_DQ<6>                                                 
P  NNAMEm6964 M_F_CPU0_SB_DQ<5>                                                 
P  NNAMEm6965 M_F_CPU0_SB_DQ<4>                                                 
P  NNAMEm6966 M_F_CPU0_SB_DQ<3>                                                 
P  NNAMEm6967 M_F_CPU0_SB_DQ<31>                                                
P  NNAMEm6968 M_F_CPU0_SB_DQ<30>                                                
P  NNAMEm6969 M_F_CPU0_SB_DQ<2>                                                 
P  NNAMEm6970 M_F_CPU0_SB_DQ<29>                                                
P  NNAMEm6971 M_F_CPU0_SB_DQ<28>                                                
P  NNAMEm6972 M_F_CPU0_SB_DQ<27>                                                
P  NNAMEm6973 M_F_CPU0_SB_DQ<26>                                                
P  NNAMEm6974 M_F_CPU0_SB_DQ<25>                                                
P  NNAMEm6975 M_F_CPU0_SB_DQ<24>                                                
P  NNAMEm6976 M_F_CPU0_SB_DQ<23>                                                
P  NNAMEm6977 M_F_CPU0_SB_DQ<22>                                                
P  NNAMEm6978 M_F_CPU0_SB_DQ<21>                                                
P  NNAMEm6979 M_F_CPU0_SB_DQ<20>                                                
P  NNAMEm6980 M_F_CPU0_SB_DQ<1>                                                 
P  NNAMEm6981 M_F_CPU0_SB_DQ<19>                                                
P  NNAMEm6982 M_F_CPU0_SB_DQ<18>                                                
P  NNAMEm6983 M_F_CPU0_SB_DQ<17>                                                
P  NNAMEm6984 M_F_CPU0_SB_DQ<16>                                                
P  NNAMEm6985 M_F_CPU0_SB_DQ<15>                                                
P  NNAMEm6986 M_F_CPU0_SB_DQ<14>                                                
P  NNAMEm6987 M_F_CPU0_SB_DQ<13>                                                
P  NNAMEm6988 M_F_CPU0_SB_DQ<12>                                                
P  NNAMEm6989 M_F_CPU0_SB_DQ<11>                                                
P  NNAMEm6990 M_F_CPU0_SB_DQ<10>                                                
P  NNAMEm6991 M_F_CPU0_SB_DQ<0>                                                 
P  NNAMEm6992 M_F_CPU0_SB_CS_N<1>                                               
P  NNAMEm6993 M_F_CPU0_SB_CS_N<0>                                               
P  NNAMEm6994 M_F_CPU0_SB_CB<7>                                                 
P  NNAMEm6995 M_F_CPU0_SB_CB<6>                                                 
P  NNAMEm6996 M_F_CPU0_SB_CB<5>                                                 
P  NNAMEm6997 M_F_CPU0_SB_CB<4>                                                 
P  NNAMEm6998 M_F_CPU0_SB_CB<3>                                                 
P  NNAMEm6999 M_F_CPU0_SB_CB<2>                                                 
P  NNAMEm7000 M_F_CPU0_SB_CB<1>                                                 
P  NNAMEm7001 M_F_CPU0_SB_CB<0>                                                 
P  NNAMEm7002 M_F_CPU0_SB_CA<6>                                                 
P  NNAMEm7003 M_F_CPU0_SB_CA<5>                                                 
P  NNAMEm7004 M_F_CPU0_SB_CA<4>                                                 
P  NNAMEm7005 M_F_CPU0_SB_CA<3>                                                 
P  NNAMEm7006 M_F_CPU0_SB_CA<2>                                                 
P  NNAMEm7007 M_F_CPU0_SB_CA<1>                                                 
P  NNAMEm7008 M_F_CPU0_SB_CA<0>                                                 
P  NNAMEm7009 M_F_CPU0_SA_RSP<0>                                                
P  NNAMEm7010 M_F_CPU0_SA_PAR                                                   
P  NNAMEm7011 M_F_CPU0_SA_DQS_DP<9>                                             
P  NNAMEm7012 M_F_CPU0_SA_DQS_DP<8>                                             
P  NNAMEm7013 M_F_CPU0_SA_DQS_DP<7>                                             
P  NNAMEm7014 M_F_CPU0_SA_DQS_DP<6>                                             
P  NNAMEm7015 M_F_CPU0_SA_DQS_DP<5>                                             
P  NNAMEm7016 M_F_CPU0_SA_DQS_DP<4>                                             
P  NNAMEm7017 M_F_CPU0_SA_DQS_DP<3>                                             
P  NNAMEm7018 M_F_CPU0_SA_DQS_DP<2>                                             
P  NNAMEm7019 M_F_CPU0_SA_DQS_DP<1>                                             
P  NNAMEm7020 M_F_CPU0_SA_DQS_DP<0>                                             
P  NNAMEm7021 M_F_CPU0_SA_DQS_DN<9>                                             
P  NNAMEm7022 M_F_CPU0_SA_DQS_DN<8>                                             
P  NNAMEm7023 M_F_CPU0_SA_DQS_DN<7>                                             
P  NNAMEm7024 M_F_CPU0_SA_DQS_DN<6>                                             
P  NNAMEm7025 M_F_CPU0_SA_DQS_DN<5>                                             
P  NNAMEm7026 M_F_CPU0_SA_DQS_DN<4>                                             
P  NNAMEm7027 M_F_CPU0_SA_DQS_DN<3>                                             
P  NNAMEm7028 M_F_CPU0_SA_DQS_DN<2>                                             
P  NNAMEm7029 M_F_CPU0_SA_DQS_DN<1>                                             
P  NNAMEm7030 M_F_CPU0_SA_DQS_DN<0>                                             
P  NNAMEm7031 M_F_CPU0_SA_DQ<9>                                                 
P  NNAMEm7032 M_F_CPU0_SA_DQ<8>                                                 
P  NNAMEm7033 M_F_CPU0_SA_DQ<7>                                                 
P  NNAMEm7034 M_F_CPU0_SA_DQ<6>                                                 
P  NNAMEm7035 M_F_CPU0_SA_DQ<5>                                                 
P  NNAMEm7036 M_F_CPU0_SA_DQ<4>                                                 
P  NNAMEm7037 M_F_CPU0_SA_DQ<3>                                                 
P  NNAMEm7038 M_F_CPU0_SA_DQ<31>                                                
P  NNAMEm7039 M_F_CPU0_SA_DQ<30>                                                
P  NNAMEm7040 M_F_CPU0_SA_DQ<2>                                                 
P  NNAMEm7041 M_F_CPU0_SA_DQ<29>                                                
P  NNAMEm7042 M_F_CPU0_SA_DQ<28>                                                
P  NNAMEm7043 M_F_CPU0_SA_DQ<27>                                                
P  NNAMEm7044 M_F_CPU0_SA_DQ<26>                                                
P  NNAMEm7045 M_F_CPU0_SA_DQ<25>                                                
P  NNAMEm7046 M_F_CPU0_SA_DQ<24>                                                
P  NNAMEm7047 M_F_CPU0_SA_DQ<23>                                                
P  NNAMEm7048 M_F_CPU0_SA_DQ<22>                                                
P  NNAMEm7049 M_F_CPU0_SA_DQ<21>                                                
P  NNAMEm7050 M_F_CPU0_SA_DQ<20>                                                
P  NNAMEm7051 M_F_CPU0_SA_DQ<1>                                                 
P  NNAMEm7052 M_F_CPU0_SA_DQ<19>                                                
P  NNAMEm7053 M_F_CPU0_SA_DQ<18>                                                
P  NNAMEm7054 M_F_CPU0_SA_DQ<17>                                                
P  NNAMEm7055 M_F_CPU0_SA_DQ<16>                                                
P  NNAMEm7056 M_F_CPU0_SA_DQ<15>                                                
P  NNAMEm7057 M_F_CPU0_SA_DQ<14>                                                
P  NNAMEm7058 M_F_CPU0_SA_DQ<13>                                                
P  NNAMEm7059 M_F_CPU0_SA_DQ<12>                                                
P  NNAMEm7060 M_F_CPU0_SA_DQ<11>                                                
P  NNAMEm7061 M_F_CPU0_SA_DQ<10>                                                
P  NNAMEm7062 M_F_CPU0_SA_DQ<0>                                                 
P  NNAMEm7063 M_F_CPU0_SA_CS_N<1>                                               
P  NNAMEm7064 M_F_CPU0_SA_CS_N<0>                                               
P  NNAMEm7065 M_F_CPU0_SA_CB<7>                                                 
P  NNAMEm7066 M_F_CPU0_SA_CB<6>                                                 
P  NNAMEm7067 M_F_CPU0_SA_CB<5>                                                 
P  NNAMEm7068 M_F_CPU0_SA_CB<4>                                                 
P  NNAMEm7069 M_F_CPU0_SA_CB<3>                                                 
P  NNAMEm7070 M_F_CPU0_SA_CB<2>                                                 
P  NNAMEm7071 M_F_CPU0_SA_CB<1>                                                 
P  NNAMEm7072 M_F_CPU0_SA_CB<0>                                                 
P  NNAMEm7073 M_F_CPU0_SA_CA<6>                                                 
P  NNAMEm7074 M_F_CPU0_SA_CA<5>                                                 
P  NNAMEm7075 M_F_CPU0_SA_CA<4>                                                 
P  NNAMEm7076 M_F_CPU0_SA_CA<3>                                                 
P  NNAMEm7077 M_F_CPU0_SA_CA<2>                                                 
P  NNAMEm7078 M_F_CPU0_SA_CA<1>                                                 
P  NNAMEm7079 M_F_CPU0_SA_CA<0>                                                 
P  NNAMEm7080 M_F_CPU0_RESET_N                                                  
P  NNAMEm7081 M_F_CPU0_CLK_DP<0>                                                
P  NNAMEm7082 M_F_CPU0_CLK_DN<0>                                                
P  NNAMEm7083 M_F_CPU0_ALERT_R_N                                                
P  NNAMEm7084 M_F_CPU0_ALERT_N                                                  
P  NNAMEm7085 M_E_CPU1_SB_RSP<0>                                                
P  NNAMEm7086 M_E_CPU1_SB_PAR                                                   
P  NNAMEm7087 M_E_CPU1_SB_DQS_DP<9>                                             
P  NNAMEm7088 M_E_CPU1_SB_DQS_DP<8>                                             
P  NNAMEm7089 M_E_CPU1_SB_DQS_DP<7>                                             
P  NNAMEm7090 M_E_CPU1_SB_DQS_DP<6>                                             
P  NNAMEm7091 M_E_CPU1_SB_DQS_DP<5>                                             
P  NNAMEm7092 M_E_CPU1_SB_DQS_DP<4>                                             
P  NNAMEm7093 M_E_CPU1_SB_DQS_DP<3>                                             
P  NNAMEm7094 M_E_CPU1_SB_DQS_DP<2>                                             
P  NNAMEm7095 M_E_CPU1_SB_DQS_DP<1>                                             
P  NNAMEm7096 M_E_CPU1_SB_DQS_DP<0>                                             
P  NNAMEm7097 M_E_CPU1_SB_DQS_DN<9>                                             
P  NNAMEm7098 M_E_CPU1_SB_DQS_DN<8>                                             
P  NNAMEm7099 M_E_CPU1_SB_DQS_DN<7>                                             
P  NNAMEm7100 M_E_CPU1_SB_DQS_DN<6>                                             
P  NNAMEm7101 M_E_CPU1_SB_DQS_DN<5>                                             
P  NNAMEm7102 M_E_CPU1_SB_DQS_DN<4>                                             
P  NNAMEm7103 M_E_CPU1_SB_DQS_DN<3>                                             
P  NNAMEm7104 M_E_CPU1_SB_DQS_DN<2>                                             
P  NNAMEm7105 M_E_CPU1_SB_DQS_DN<1>                                             
P  NNAMEm7106 M_E_CPU1_SB_DQS_DN<0>                                             
P  NNAMEm7107 M_E_CPU1_SB_DQ<9>                                                 
P  NNAMEm7108 M_E_CPU1_SB_DQ<8>                                                 
P  NNAMEm7109 M_E_CPU1_SB_DQ<7>                                                 
P  NNAMEm7110 M_E_CPU1_SB_DQ<6>                                                 
P  NNAMEm7111 M_E_CPU1_SB_DQ<5>                                                 
P  NNAMEm7112 M_E_CPU1_SB_DQ<4>                                                 
P  NNAMEm7113 M_E_CPU1_SB_DQ<3>                                                 
P  NNAMEm7114 M_E_CPU1_SB_DQ<31>                                                
P  NNAMEm7115 M_E_CPU1_SB_DQ<30>                                                
P  NNAMEm7116 M_E_CPU1_SB_DQ<2>                                                 
P  NNAMEm7117 M_E_CPU1_SB_DQ<29>                                                
P  NNAMEm7118 M_E_CPU1_SB_DQ<28>                                                
P  NNAMEm7119 M_E_CPU1_SB_DQ<27>                                                
P  NNAMEm7120 M_E_CPU1_SB_DQ<26>                                                
P  NNAMEm7121 M_E_CPU1_SB_DQ<25>                                                
P  NNAMEm7122 M_E_CPU1_SB_DQ<24>                                                
P  NNAMEm7123 M_E_CPU1_SB_DQ<23>                                                
P  NNAMEm7124 M_E_CPU1_SB_DQ<22>                                                
P  NNAMEm7125 M_E_CPU1_SB_DQ<21>                                                
P  NNAMEm7126 M_E_CPU1_SB_DQ<20>                                                
P  NNAMEm7127 M_E_CPU1_SB_DQ<1>                                                 
P  NNAMEm7128 M_E_CPU1_SB_DQ<19>                                                
P  NNAMEm7129 M_E_CPU1_SB_DQ<18>                                                
P  NNAMEm7130 M_E_CPU1_SB_DQ<17>                                                
P  NNAMEm7131 M_E_CPU1_SB_DQ<16>                                                
P  NNAMEm7132 M_E_CPU1_SB_DQ<15>                                                
P  NNAMEm7133 M_E_CPU1_SB_DQ<14>                                                
P  NNAMEm7134 M_E_CPU1_SB_DQ<13>                                                
P  NNAMEm7135 M_E_CPU1_SB_DQ<12>                                                
P  NNAMEm7136 M_E_CPU1_SB_DQ<11>                                                
P  NNAMEm7137 M_E_CPU1_SB_DQ<10>                                                
P  NNAMEm7138 M_E_CPU1_SB_DQ<0>                                                 
P  NNAMEm7139 M_E_CPU1_SB_CS_N<1>                                               
P  NNAMEm7140 M_E_CPU1_SB_CS_N<0>                                               
P  NNAMEm7141 M_E_CPU1_SB_CB<7>                                                 
P  NNAMEm7142 M_E_CPU1_SB_CB<6>                                                 
P  NNAMEm7143 M_E_CPU1_SB_CB<5>                                                 
P  NNAMEm7144 M_E_CPU1_SB_CB<4>                                                 
P  NNAMEm7145 M_E_CPU1_SB_CB<3>                                                 
P  NNAMEm7146 M_E_CPU1_SB_CB<2>                                                 
P  NNAMEm7147 M_E_CPU1_SB_CB<1>                                                 
P  NNAMEm7148 M_E_CPU1_SB_CB<0>                                                 
P  NNAMEm7149 M_E_CPU1_SB_CA<6>                                                 
P  NNAMEm7150 M_E_CPU1_SB_CA<5>                                                 
P  NNAMEm7151 M_E_CPU1_SB_CA<4>                                                 
P  NNAMEm7152 M_E_CPU1_SB_CA<3>                                                 
P  NNAMEm7153 M_E_CPU1_SB_CA<2>                                                 
P  NNAMEm7154 M_E_CPU1_SB_CA<1>                                                 
P  NNAMEm7155 M_E_CPU1_SB_CA<0>                                                 
P  NNAMEm7156 M_E_CPU1_SA_RSP<0>                                                
P  NNAMEm7157 M_E_CPU1_SA_PAR                                                   
P  NNAMEm7158 M_E_CPU1_SA_DQS_DP<9>                                             
P  NNAMEm7159 M_E_CPU1_SA_DQS_DP<8>                                             
P  NNAMEm7160 M_E_CPU1_SA_DQS_DP<7>                                             
P  NNAMEm7161 M_E_CPU1_SA_DQS_DP<6>                                             
P  NNAMEm7162 M_E_CPU1_SA_DQS_DP<5>                                             
P  NNAMEm7163 M_E_CPU1_SA_DQS_DP<4>                                             
P  NNAMEm7164 M_E_CPU1_SA_DQS_DP<3>                                             
P  NNAMEm7165 M_E_CPU1_SA_DQS_DP<2>                                             
P  NNAMEm7166 M_E_CPU1_SA_DQS_DP<1>                                             
P  NNAMEm7167 M_E_CPU1_SA_DQS_DP<0>                                             
P  NNAMEm7168 M_E_CPU1_SA_DQS_DN<9>                                             
P  NNAMEm7169 M_E_CPU1_SA_DQS_DN<8>                                             
P  NNAMEm7170 M_E_CPU1_SA_DQS_DN<7>                                             
P  NNAMEm7171 M_E_CPU1_SA_DQS_DN<6>                                             
P  NNAMEm7172 M_E_CPU1_SA_DQS_DN<5>                                             
P  NNAMEm7173 M_E_CPU1_SA_DQS_DN<4>                                             
P  NNAMEm7174 M_E_CPU1_SA_DQS_DN<3>                                             
P  NNAMEm7175 M_E_CPU1_SA_DQS_DN<2>                                             
P  NNAMEm7176 M_E_CPU1_SA_DQS_DN<1>                                             
P  NNAMEm7177 M_E_CPU1_SA_DQS_DN<0>                                             
P  NNAMEm7178 M_E_CPU1_SA_DQ<9>                                                 
P  NNAMEm7179 M_E_CPU1_SA_DQ<8>                                                 
P  NNAMEm7180 M_E_CPU1_SA_DQ<7>                                                 
P  NNAMEm7181 M_E_CPU1_SA_DQ<6>                                                 
P  NNAMEm7182 M_E_CPU1_SA_DQ<5>                                                 
P  NNAMEm7183 M_E_CPU1_SA_DQ<4>                                                 
P  NNAMEm7184 M_E_CPU1_SA_DQ<3>                                                 
P  NNAMEm7185 M_E_CPU1_SA_DQ<31>                                                
P  NNAMEm7186 M_E_CPU1_SA_DQ<30>                                                
P  NNAMEm7187 M_E_CPU1_SA_DQ<2>                                                 
P  NNAMEm7188 M_E_CPU1_SA_DQ<29>                                                
P  NNAMEm7189 M_E_CPU1_SA_DQ<28>                                                
P  NNAMEm7190 M_E_CPU1_SA_DQ<27>                                                
P  NNAMEm7191 M_E_CPU1_SA_DQ<26>                                                
P  NNAMEm7192 M_E_CPU1_SA_DQ<25>                                                
P  NNAMEm7193 M_E_CPU1_SA_DQ<24>                                                
P  NNAMEm7194 M_E_CPU1_SA_DQ<23>                                                
P  NNAMEm7195 M_E_CPU1_SA_DQ<22>                                                
P  NNAMEm7196 M_E_CPU1_SA_DQ<21>                                                
P  NNAMEm7197 M_E_CPU1_SA_DQ<20>                                                
P  NNAMEm7198 M_E_CPU1_SA_DQ<1>                                                 
P  NNAMEm7199 M_E_CPU1_SA_DQ<19>                                                
P  NNAMEm7200 M_E_CPU1_SA_DQ<18>                                                
P  NNAMEm7201 M_E_CPU1_SA_DQ<17>                                                
P  NNAMEm7202 M_E_CPU1_SA_DQ<16>                                                
P  NNAMEm7203 M_E_CPU1_SA_DQ<15>                                                
P  NNAMEm7204 M_E_CPU1_SA_DQ<14>                                                
P  NNAMEm7205 M_E_CPU1_SA_DQ<13>                                                
P  NNAMEm7206 M_E_CPU1_SA_DQ<12>                                                
P  NNAMEm7207 M_E_CPU1_SA_DQ<11>                                                
P  NNAMEm7208 M_E_CPU1_SA_DQ<10>                                                
P  NNAMEm7209 M_E_CPU1_SA_DQ<0>                                                 
P  NNAMEm7210 M_E_CPU1_SA_CS_N<1>                                               
P  NNAMEm7211 M_E_CPU1_SA_CS_N<0>                                               
P  NNAMEm7212 M_E_CPU1_SA_CB<7>                                                 
P  NNAMEm7213 M_E_CPU1_SA_CB<6>                                                 
P  NNAMEm7214 M_E_CPU1_SA_CB<5>                                                 
P  NNAMEm7215 M_E_CPU1_SA_CB<4>                                                 
P  NNAMEm7216 M_E_CPU1_SA_CB<3>                                                 
P  NNAMEm7217 M_E_CPU1_SA_CB<2>                                                 
P  NNAMEm7218 M_E_CPU1_SA_CB<1>                                                 
P  NNAMEm7219 M_E_CPU1_SA_CB<0>                                                 
P  NNAMEm7220 M_E_CPU1_SA_CA<6>                                                 
P  NNAMEm7221 M_E_CPU1_SA_CA<5>                                                 
P  NNAMEm7222 M_E_CPU1_SA_CA<4>                                                 
P  NNAMEm7223 M_E_CPU1_SA_CA<3>                                                 
P  NNAMEm7224 M_E_CPU1_SA_CA<2>                                                 
P  NNAMEm7225 M_E_CPU1_SA_CA<1>                                                 
P  NNAMEm7226 M_E_CPU1_SA_CA<0>                                                 
P  NNAMEm7227 M_E_CPU1_RESET_N                                                  
P  NNAMEm7228 M_E_CPU1_CLK_DP<0>                                                
P  NNAMEm7229 M_E_CPU1_CLK_DN<0>                                                
P  NNAMEm7230 M_E_CPU1_ALERT_R_N                                                
P  NNAMEm7231 M_E_CPU1_ALERT_N                                                  
P  NNAMEm7232 M_E_CPU0_SB_RSP<0>                                                
P  NNAMEm7233 M_E_CPU0_SB_PAR                                                   
P  NNAMEm7234 M_E_CPU0_SB_DQS_DP<9>                                             
P  NNAMEm7235 M_E_CPU0_SB_DQS_DP<8>                                             
P  NNAMEm7236 M_E_CPU0_SB_DQS_DP<7>                                             
P  NNAMEm7237 M_E_CPU0_SB_DQS_DP<6>                                             
P  NNAMEm7238 M_E_CPU0_SB_DQS_DP<5>                                             
P  NNAMEm7239 M_E_CPU0_SB_DQS_DP<4>                                             
P  NNAMEm7240 M_E_CPU0_SB_DQS_DP<3>                                             
P  NNAMEm7241 M_E_CPU0_SB_DQS_DP<2>                                             
P  NNAMEm7242 M_E_CPU0_SB_DQS_DP<1>                                             
P  NNAMEm7243 M_E_CPU0_SB_DQS_DP<0>                                             
P  NNAMEm7244 M_E_CPU0_SB_DQS_DN<9>                                             
P  NNAMEm7245 M_E_CPU0_SB_DQS_DN<8>                                             
P  NNAMEm7246 M_E_CPU0_SB_DQS_DN<7>                                             
P  NNAMEm7247 M_E_CPU0_SB_DQS_DN<6>                                             
P  NNAMEm7248 M_E_CPU0_SB_DQS_DN<5>                                             
P  NNAMEm7249 M_E_CPU0_SB_DQS_DN<4>                                             
P  NNAMEm7250 M_E_CPU0_SB_DQS_DN<3>                                             
P  NNAMEm7251 M_E_CPU0_SB_DQS_DN<2>                                             
P  NNAMEm7252 M_E_CPU0_SB_DQS_DN<1>                                             
P  NNAMEm7253 M_E_CPU0_SB_DQS_DN<0>                                             
P  NNAMEm7254 M_E_CPU0_SB_DQ<9>                                                 
P  NNAMEm7255 M_E_CPU0_SB_DQ<8>                                                 
P  NNAMEm7256 M_E_CPU0_SB_DQ<7>                                                 
P  NNAMEm7257 M_E_CPU0_SB_DQ<6>                                                 
P  NNAMEm7258 M_E_CPU0_SB_DQ<5>                                                 
P  NNAMEm7259 M_E_CPU0_SB_DQ<4>                                                 
P  NNAMEm7260 M_E_CPU0_SB_DQ<3>                                                 
P  NNAMEm7261 M_E_CPU0_SB_DQ<31>                                                
P  NNAMEm7262 M_E_CPU0_SB_DQ<30>                                                
P  NNAMEm7263 M_E_CPU0_SB_DQ<2>                                                 
P  NNAMEm7264 M_E_CPU0_SB_DQ<29>                                                
P  NNAMEm7265 M_E_CPU0_SB_DQ<28>                                                
P  NNAMEm7266 M_E_CPU0_SB_DQ<27>                                                
P  NNAMEm7267 M_E_CPU0_SB_DQ<26>                                                
P  NNAMEm7268 M_E_CPU0_SB_DQ<25>                                                
P  NNAMEm7269 M_E_CPU0_SB_DQ<24>                                                
P  NNAMEm7270 M_E_CPU0_SB_DQ<23>                                                
P  NNAMEm7271 M_E_CPU0_SB_DQ<22>                                                
P  NNAMEm7272 M_E_CPU0_SB_DQ<21>                                                
P  NNAMEm7273 M_E_CPU0_SB_DQ<20>                                                
P  NNAMEm7274 M_E_CPU0_SB_DQ<1>                                                 
P  NNAMEm7275 M_E_CPU0_SB_DQ<19>                                                
P  NNAMEm7276 M_E_CPU0_SB_DQ<18>                                                
P  NNAMEm7277 M_E_CPU0_SB_DQ<17>                                                
P  NNAMEm7278 M_E_CPU0_SB_DQ<16>                                                
P  NNAMEm7279 M_E_CPU0_SB_DQ<15>                                                
P  NNAMEm7280 M_E_CPU0_SB_DQ<14>                                                
P  NNAMEm7281 M_E_CPU0_SB_DQ<13>                                                
P  NNAMEm7282 M_E_CPU0_SB_DQ<12>                                                
P  NNAMEm7283 M_E_CPU0_SB_DQ<11>                                                
P  NNAMEm7284 M_E_CPU0_SB_DQ<10>                                                
P  NNAMEm7285 M_E_CPU0_SB_DQ<0>                                                 
P  NNAMEm7286 M_E_CPU0_SB_CS_N<1>                                               
P  NNAMEm7287 M_E_CPU0_SB_CS_N<0>                                               
P  NNAMEm7288 M_E_CPU0_SB_CB<7>                                                 
P  NNAMEm7289 M_E_CPU0_SB_CB<6>                                                 
P  NNAMEm7290 M_E_CPU0_SB_CB<5>                                                 
P  NNAMEm7291 M_E_CPU0_SB_CB<4>                                                 
P  NNAMEm7292 M_E_CPU0_SB_CB<3>                                                 
P  NNAMEm7293 M_E_CPU0_SB_CB<2>                                                 
P  NNAMEm7294 M_E_CPU0_SB_CB<1>                                                 
P  NNAMEm7295 M_E_CPU0_SB_CB<0>                                                 
P  NNAMEm7296 M_E_CPU0_SB_CA<6>                                                 
P  NNAMEm7297 M_E_CPU0_SB_CA<5>                                                 
P  NNAMEm7298 M_E_CPU0_SB_CA<4>                                                 
P  NNAMEm7299 M_E_CPU0_SB_CA<3>                                                 
P  NNAMEm7300 M_E_CPU0_SB_CA<2>                                                 
P  NNAMEm7301 M_E_CPU0_SB_CA<1>                                                 
P  NNAMEm7302 M_E_CPU0_SB_CA<0>                                                 
P  NNAMEm7303 M_E_CPU0_SA_RSP<0>                                                
P  NNAMEm7304 M_E_CPU0_SA_PAR                                                   
P  NNAMEm7305 M_E_CPU0_SA_DQS_DP<9>                                             
P  NNAMEm7306 M_E_CPU0_SA_DQS_DP<8>                                             
P  NNAMEm7307 M_E_CPU0_SA_DQS_DP<7>                                             
P  NNAMEm7308 M_E_CPU0_SA_DQS_DP<6>                                             
P  NNAMEm7309 M_E_CPU0_SA_DQS_DP<5>                                             
P  NNAMEm7310 M_E_CPU0_SA_DQS_DP<4>                                             
P  NNAMEm7311 M_E_CPU0_SA_DQS_DP<3>                                             
P  NNAMEm7312 M_E_CPU0_SA_DQS_DP<2>                                             
P  NNAMEm7313 M_E_CPU0_SA_DQS_DP<1>                                             
P  NNAMEm7314 M_E_CPU0_SA_DQS_DP<0>                                             
P  NNAMEm7315 M_E_CPU0_SA_DQS_DN<9>                                             
P  NNAMEm7316 M_E_CPU0_SA_DQS_DN<8>                                             
P  NNAMEm7317 M_E_CPU0_SA_DQS_DN<7>                                             
P  NNAMEm7318 M_E_CPU0_SA_DQS_DN<6>                                             
P  NNAMEm7319 M_E_CPU0_SA_DQS_DN<5>                                             
P  NNAMEm7320 M_E_CPU0_SA_DQS_DN<4>                                             
P  NNAMEm7321 M_E_CPU0_SA_DQS_DN<3>                                             
P  NNAMEm7322 M_E_CPU0_SA_DQS_DN<2>                                             
P  NNAMEm7323 M_E_CPU0_SA_DQS_DN<1>                                             
P  NNAMEm7324 M_E_CPU0_SA_DQS_DN<0>                                             
P  NNAMEm7325 M_E_CPU0_SA_DQ<9>                                                 
P  NNAMEm7326 M_E_CPU0_SA_DQ<8>                                                 
P  NNAMEm7327 M_E_CPU0_SA_DQ<7>                                                 
P  NNAMEm7328 M_E_CPU0_SA_DQ<6>                                                 
P  NNAMEm7329 M_E_CPU0_SA_DQ<5>                                                 
P  NNAMEm7330 M_E_CPU0_SA_DQ<4>                                                 
P  NNAMEm7331 M_E_CPU0_SA_DQ<3>                                                 
P  NNAMEm7332 M_E_CPU0_SA_DQ<31>                                                
P  NNAMEm7333 M_E_CPU0_SA_DQ<30>                                                
P  NNAMEm7334 M_E_CPU0_SA_DQ<2>                                                 
P  NNAMEm7335 M_E_CPU0_SA_DQ<29>                                                
P  NNAMEm7336 M_E_CPU0_SA_DQ<28>                                                
P  NNAMEm7337 M_E_CPU0_SA_DQ<27>                                                
P  NNAMEm7338 M_E_CPU0_SA_DQ<26>                                                
P  NNAMEm7339 M_E_CPU0_SA_DQ<25>                                                
P  NNAMEm7340 M_E_CPU0_SA_DQ<24>                                                
P  NNAMEm7341 M_E_CPU0_SA_DQ<23>                                                
P  NNAMEm7342 M_E_CPU0_SA_DQ<22>                                                
P  NNAMEm7343 M_E_CPU0_SA_DQ<21>                                                
P  NNAMEm7344 M_E_CPU0_SA_DQ<20>                                                
P  NNAMEm7345 M_E_CPU0_SA_DQ<1>                                                 
P  NNAMEm7346 M_E_CPU0_SA_DQ<19>                                                
P  NNAMEm7347 M_E_CPU0_SA_DQ<18>                                                
P  NNAMEm7348 M_E_CPU0_SA_DQ<17>                                                
P  NNAMEm7349 M_E_CPU0_SA_DQ<16>                                                
P  NNAMEm7350 M_E_CPU0_SA_DQ<15>                                                
P  NNAMEm7351 M_E_CPU0_SA_DQ<14>                                                
P  NNAMEm7352 M_E_CPU0_SA_DQ<13>                                                
P  NNAMEm7353 M_E_CPU0_SA_DQ<12>                                                
P  NNAMEm7354 M_E_CPU0_SA_DQ<11>                                                
P  NNAMEm7355 M_E_CPU0_SA_DQ<10>                                                
P  NNAMEm7356 M_E_CPU0_SA_DQ<0>                                                 
P  NNAMEm7357 M_E_CPU0_SA_CS_N<1>                                               
P  NNAMEm7358 M_E_CPU0_SA_CS_N<0>                                               
P  NNAMEm7359 M_E_CPU0_SA_CB<7>                                                 
P  NNAMEm7360 M_E_CPU0_SA_CB<6>                                                 
P  NNAMEm7361 M_E_CPU0_SA_CB<5>                                                 
P  NNAMEm7362 M_E_CPU0_SA_CB<4>                                                 
P  NNAMEm7363 M_E_CPU0_SA_CB<3>                                                 
P  NNAMEm7364 M_E_CPU0_SA_CB<2>                                                 
P  NNAMEm7365 M_E_CPU0_SA_CB<1>                                                 
P  NNAMEm7366 M_E_CPU0_SA_CB<0>                                                 
P  NNAMEm7367 M_E_CPU0_SA_CA<6>                                                 
P  NNAMEm7368 M_E_CPU0_SA_CA<5>                                                 
P  NNAMEm7369 M_E_CPU0_SA_CA<4>                                                 
P  NNAMEm7370 M_E_CPU0_SA_CA<3>                                                 
P  NNAMEm7371 M_E_CPU0_SA_CA<2>                                                 
P  NNAMEm7372 M_E_CPU0_SA_CA<1>                                                 
P  NNAMEm7373 M_E_CPU0_SA_CA<0>                                                 
P  NNAMEm7374 M_E_CPU0_RESET_N                                                  
P  NNAMEm7375 M_E_CPU0_CLK_DP<0>                                                
P  NNAMEm7376 M_E_CPU0_CLK_DN<0>                                                
P  NNAMEm7377 M_E_CPU0_ALERT_R_N                                                
P  NNAMEm7378 M_E_CPU0_ALERT_N                                                  
P  NNAMEm7379 M_D_CPU1_SB_RSP<0>                                                
P  NNAMEm7380 M_D_CPU1_SB_PAR                                                   
P  NNAMEm7381 M_D_CPU1_SB_DQS_DP<9>                                             
P  NNAMEm7382 M_D_CPU1_SB_DQS_DP<8>                                             
P  NNAMEm7383 M_D_CPU1_SB_DQS_DP<7>                                             
P  NNAMEm7384 M_D_CPU1_SB_DQS_DP<6>                                             
P  NNAMEm7385 M_D_CPU1_SB_DQS_DP<5>                                             
P  NNAMEm7386 M_D_CPU1_SB_DQS_DP<4>                                             
P  NNAMEm7387 M_D_CPU1_SB_DQS_DP<3>                                             
P  NNAMEm7388 M_D_CPU1_SB_DQS_DP<2>                                             
P  NNAMEm7389 M_D_CPU1_SB_DQS_DP<1>                                             
P  NNAMEm7390 M_D_CPU1_SB_DQS_DP<0>                                             
P  NNAMEm7391 M_D_CPU1_SB_DQS_DN<9>                                             
P  NNAMEm7392 M_D_CPU1_SB_DQS_DN<8>                                             
P  NNAMEm7393 M_D_CPU1_SB_DQS_DN<7>                                             
P  NNAMEm7394 M_D_CPU1_SB_DQS_DN<6>                                             
P  NNAMEm7395 M_D_CPU1_SB_DQS_DN<5>                                             
P  NNAMEm7396 M_D_CPU1_SB_DQS_DN<4>                                             
P  NNAMEm7397 M_D_CPU1_SB_DQS_DN<3>                                             
P  NNAMEm7398 M_D_CPU1_SB_DQS_DN<2>                                             
P  NNAMEm7399 M_D_CPU1_SB_DQS_DN<1>                                             
P  NNAMEm7400 M_D_CPU1_SB_DQS_DN<0>                                             
P  NNAMEm7401 M_D_CPU1_SB_DQ<9>                                                 
P  NNAMEm7402 M_D_CPU1_SB_DQ<8>                                                 
P  NNAMEm7403 M_D_CPU1_SB_DQ<7>                                                 
P  NNAMEm7404 M_D_CPU1_SB_DQ<6>                                                 
P  NNAMEm7405 M_D_CPU1_SB_DQ<5>                                                 
P  NNAMEm7406 M_D_CPU1_SB_DQ<4>                                                 
P  NNAMEm7407 M_D_CPU1_SB_DQ<3>                                                 
P  NNAMEm7408 M_D_CPU1_SB_DQ<31>                                                
P  NNAMEm7409 M_D_CPU1_SB_DQ<30>                                                
P  NNAMEm7410 M_D_CPU1_SB_DQ<2>                                                 
P  NNAMEm7411 M_D_CPU1_SB_DQ<29>                                                
P  NNAMEm7412 M_D_CPU1_SB_DQ<28>                                                
P  NNAMEm7413 M_D_CPU1_SB_DQ<27>                                                
P  NNAMEm7414 M_D_CPU1_SB_DQ<26>                                                
P  NNAMEm7415 M_D_CPU1_SB_DQ<25>                                                
P  NNAMEm7416 M_D_CPU1_SB_DQ<24>                                                
P  NNAMEm7417 M_D_CPU1_SB_DQ<23>                                                
P  NNAMEm7418 M_D_CPU1_SB_DQ<22>                                                
P  NNAMEm7419 M_D_CPU1_SB_DQ<21>                                                
P  NNAMEm7420 M_D_CPU1_SB_DQ<20>                                                
P  NNAMEm7421 M_D_CPU1_SB_DQ<1>                                                 
P  NNAMEm7422 M_D_CPU1_SB_DQ<19>                                                
P  NNAMEm7423 M_D_CPU1_SB_DQ<18>                                                
P  NNAMEm7424 M_D_CPU1_SB_DQ<17>                                                
P  NNAMEm7425 M_D_CPU1_SB_DQ<16>                                                
P  NNAMEm7426 M_D_CPU1_SB_DQ<15>                                                
P  NNAMEm7427 M_D_CPU1_SB_DQ<14>                                                
P  NNAMEm7428 M_D_CPU1_SB_DQ<13>                                                
P  NNAMEm7429 M_D_CPU1_SB_DQ<12>                                                
P  NNAMEm7430 M_D_CPU1_SB_DQ<11>                                                
P  NNAMEm7431 M_D_CPU1_SB_DQ<10>                                                
P  NNAMEm7432 M_D_CPU1_SB_DQ<0>                                                 
P  NNAMEm7433 M_D_CPU1_SB_CS_N<1>                                               
P  NNAMEm7434 M_D_CPU1_SB_CS_N<0>                                               
P  NNAMEm7435 M_D_CPU1_SB_CB<7>                                                 
P  NNAMEm7436 M_D_CPU1_SB_CB<6>                                                 
P  NNAMEm7437 M_D_CPU1_SB_CB<5>                                                 
P  NNAMEm7438 M_D_CPU1_SB_CB<4>                                                 
P  NNAMEm7439 M_D_CPU1_SB_CB<3>                                                 
P  NNAMEm7440 M_D_CPU1_SB_CB<2>                                                 
P  NNAMEm7441 M_D_CPU1_SB_CB<1>                                                 
P  NNAMEm7442 M_D_CPU1_SB_CB<0>                                                 
P  NNAMEm7443 M_D_CPU1_SB_CA<6>                                                 
P  NNAMEm7444 M_D_CPU1_SB_CA<5>                                                 
P  NNAMEm7445 M_D_CPU1_SB_CA<4>                                                 
P  NNAMEm7446 M_D_CPU1_SB_CA<3>                                                 
P  NNAMEm7447 M_D_CPU1_SB_CA<2>                                                 
P  NNAMEm7448 M_D_CPU1_SB_CA<1>                                                 
P  NNAMEm7449 M_D_CPU1_SB_CA<0>                                                 
P  NNAMEm7450 M_D_CPU1_SA_RSP<0>                                                
P  NNAMEm7451 M_D_CPU1_SA_PAR                                                   
P  NNAMEm7452 M_D_CPU1_SA_DQS_DP<9>                                             
P  NNAMEm7453 M_D_CPU1_SA_DQS_DP<8>                                             
P  NNAMEm7454 M_D_CPU1_SA_DQS_DP<7>                                             
P  NNAMEm7455 M_D_CPU1_SA_DQS_DP<6>                                             
P  NNAMEm7456 M_D_CPU1_SA_DQS_DP<5>                                             
P  NNAMEm7457 M_D_CPU1_SA_DQS_DP<4>                                             
P  NNAMEm7458 M_D_CPU1_SA_DQS_DP<3>                                             
P  NNAMEm7459 M_D_CPU1_SA_DQS_DP<2>                                             
P  NNAMEm7460 M_D_CPU1_SA_DQS_DP<1>                                             
P  NNAMEm7461 M_D_CPU1_SA_DQS_DP<0>                                             
P  NNAMEm7462 M_D_CPU1_SA_DQS_DN<9>                                             
P  NNAMEm7463 M_D_CPU1_SA_DQS_DN<8>                                             
P  NNAMEm7464 M_D_CPU1_SA_DQS_DN<7>                                             
P  NNAMEm7465 M_D_CPU1_SA_DQS_DN<6>                                             
P  NNAMEm7466 M_D_CPU1_SA_DQS_DN<5>                                             
P  NNAMEm7467 M_D_CPU1_SA_DQS_DN<4>                                             
P  NNAMEm7468 M_D_CPU1_SA_DQS_DN<3>                                             
P  NNAMEm7469 M_D_CPU1_SA_DQS_DN<2>                                             
P  NNAMEm7470 M_D_CPU1_SA_DQS_DN<1>                                             
P  NNAMEm7471 M_D_CPU1_SA_DQS_DN<0>                                             
P  NNAMEm7472 M_D_CPU1_SA_DQ<9>                                                 
P  NNAMEm7473 M_D_CPU1_SA_DQ<8>                                                 
P  NNAMEm7474 M_D_CPU1_SA_DQ<7>                                                 
P  NNAMEm7475 M_D_CPU1_SA_DQ<6>                                                 
P  NNAMEm7476 M_D_CPU1_SA_DQ<5>                                                 
P  NNAMEm7477 M_D_CPU1_SA_DQ<4>                                                 
P  NNAMEm7478 M_D_CPU1_SA_DQ<3>                                                 
P  NNAMEm7479 M_D_CPU1_SA_DQ<31>                                                
P  NNAMEm7480 M_D_CPU1_SA_DQ<30>                                                
P  NNAMEm7481 M_D_CPU1_SA_DQ<2>                                                 
P  NNAMEm7482 M_D_CPU1_SA_DQ<29>                                                
P  NNAMEm7483 M_D_CPU1_SA_DQ<28>                                                
P  NNAMEm7484 M_D_CPU1_SA_DQ<27>                                                
P  NNAMEm7485 M_D_CPU1_SA_DQ<26>                                                
P  NNAMEm7486 M_D_CPU1_SA_DQ<25>                                                
P  NNAMEm7487 M_D_CPU1_SA_DQ<24>                                                
P  NNAMEm7488 M_D_CPU1_SA_DQ<23>                                                
P  NNAMEm7489 M_D_CPU1_SA_DQ<22>                                                
P  NNAMEm7490 M_D_CPU1_SA_DQ<21>                                                
P  NNAMEm7491 M_D_CPU1_SA_DQ<20>                                                
P  NNAMEm7492 M_D_CPU1_SA_DQ<1>                                                 
P  NNAMEm7493 M_D_CPU1_SA_DQ<19>                                                
P  NNAMEm7494 M_D_CPU1_SA_DQ<18>                                                
P  NNAMEm7495 M_D_CPU1_SA_DQ<17>                                                
P  NNAMEm7496 M_D_CPU1_SA_DQ<16>                                                
P  NNAMEm7497 M_D_CPU1_SA_DQ<15>                                                
P  NNAMEm7498 M_D_CPU1_SA_DQ<14>                                                
P  NNAMEm7499 M_D_CPU1_SA_DQ<13>                                                
P  NNAMEm7500 M_D_CPU1_SA_DQ<12>                                                
P  NNAMEm7501 M_D_CPU1_SA_DQ<11>                                                
P  NNAMEm7502 M_D_CPU1_SA_DQ<10>                                                
P  NNAMEm7503 M_D_CPU1_SA_DQ<0>                                                 
P  NNAMEm7504 M_D_CPU1_SA_CS_N<1>                                               
P  NNAMEm7505 M_D_CPU1_SA_CS_N<0>                                               
P  NNAMEm7506 M_D_CPU1_SA_CB<7>                                                 
P  NNAMEm7507 M_D_CPU1_SA_CB<6>                                                 
P  NNAMEm7508 M_D_CPU1_SA_CB<5>                                                 
P  NNAMEm7509 M_D_CPU1_SA_CB<4>                                                 
P  NNAMEm7510 M_D_CPU1_SA_CB<3>                                                 
P  NNAMEm7511 M_D_CPU1_SA_CB<2>                                                 
P  NNAMEm7512 M_D_CPU1_SA_CB<1>                                                 
P  NNAMEm7513 M_D_CPU1_SA_CB<0>                                                 
P  NNAMEm7514 M_D_CPU1_SA_CA<6>                                                 
P  NNAMEm7515 M_D_CPU1_SA_CA<5>                                                 
P  NNAMEm7516 M_D_CPU1_SA_CA<4>                                                 
P  NNAMEm7517 M_D_CPU1_SA_CA<3>                                                 
P  NNAMEm7518 M_D_CPU1_SA_CA<2>                                                 
P  NNAMEm7519 M_D_CPU1_SA_CA<1>                                                 
P  NNAMEm7520 M_D_CPU1_SA_CA<0>                                                 
P  NNAMEm7521 M_D_CPU1_RESET_N                                                  
P  NNAMEm7522 M_D_CPU1_CLK_DP<0>                                                
P  NNAMEm7523 M_D_CPU1_CLK_DN<0>                                                
P  NNAMEm7524 M_D_CPU1_ALERT_R_N                                                
P  NNAMEm7525 M_D_CPU1_ALERT_N                                                  
P  NNAMEm7526 M_D_CPU0_SB_RSP<0>                                                
P  NNAMEm7527 M_D_CPU0_SB_PAR                                                   
P  NNAMEm7528 M_D_CPU0_SB_DQS_DP<9>                                             
P  NNAMEm7529 M_D_CPU0_SB_DQS_DP<8>                                             
P  NNAMEm7530 M_D_CPU0_SB_DQS_DP<7>                                             
P  NNAMEm7531 M_D_CPU0_SB_DQS_DP<6>                                             
P  NNAMEm7532 M_D_CPU0_SB_DQS_DP<5>                                             
P  NNAMEm7533 M_D_CPU0_SB_DQS_DP<4>                                             
P  NNAMEm7534 M_D_CPU0_SB_DQS_DP<3>                                             
P  NNAMEm7535 M_D_CPU0_SB_DQS_DP<2>                                             
P  NNAMEm7536 M_D_CPU0_SB_DQS_DP<1>                                             
P  NNAMEm7537 M_D_CPU0_SB_DQS_DP<0>                                             
P  NNAMEm7538 M_D_CPU0_SB_DQS_DN<9>                                             
P  NNAMEm7539 M_D_CPU0_SB_DQS_DN<8>                                             
P  NNAMEm7540 M_D_CPU0_SB_DQS_DN<7>                                             
P  NNAMEm7541 M_D_CPU0_SB_DQS_DN<6>                                             
P  NNAMEm7542 M_D_CPU0_SB_DQS_DN<5>                                             
P  NNAMEm7543 M_D_CPU0_SB_DQS_DN<4>                                             
P  NNAMEm7544 M_D_CPU0_SB_DQS_DN<3>                                             
P  NNAMEm7545 M_D_CPU0_SB_DQS_DN<2>                                             
P  NNAMEm7546 M_D_CPU0_SB_DQS_DN<1>                                             
P  NNAMEm7547 M_D_CPU0_SB_DQS_DN<0>                                             
P  NNAMEm7548 M_D_CPU0_SB_DQ<9>                                                 
P  NNAMEm7549 M_D_CPU0_SB_DQ<8>                                                 
P  NNAMEm7550 M_D_CPU0_SB_DQ<7>                                                 
P  NNAMEm7551 M_D_CPU0_SB_DQ<6>                                                 
P  NNAMEm7552 M_D_CPU0_SB_DQ<5>                                                 
P  NNAMEm7553 M_D_CPU0_SB_DQ<4>                                                 
P  NNAMEm7554 M_D_CPU0_SB_DQ<3>                                                 
P  NNAMEm7555 M_D_CPU0_SB_DQ<31>                                                
P  NNAMEm7556 M_D_CPU0_SB_DQ<30>                                                
P  NNAMEm7557 M_D_CPU0_SB_DQ<2>                                                 
P  NNAMEm7558 M_D_CPU0_SB_DQ<29>                                                
P  NNAMEm7559 M_D_CPU0_SB_DQ<28>                                                
P  NNAMEm7560 M_D_CPU0_SB_DQ<27>                                                
P  NNAMEm7561 M_D_CPU0_SB_DQ<26>                                                
P  NNAMEm7562 M_D_CPU0_SB_DQ<25>                                                
P  NNAMEm7563 M_D_CPU0_SB_DQ<24>                                                
P  NNAMEm7564 M_D_CPU0_SB_DQ<23>                                                
P  NNAMEm7565 M_D_CPU0_SB_DQ<22>                                                
P  NNAMEm7566 M_D_CPU0_SB_DQ<21>                                                
P  NNAMEm7567 M_D_CPU0_SB_DQ<20>                                                
P  NNAMEm7568 M_D_CPU0_SB_DQ<1>                                                 
P  NNAMEm7569 M_D_CPU0_SB_DQ<19>                                                
P  NNAMEm7570 M_D_CPU0_SB_DQ<18>                                                
P  NNAMEm7571 M_D_CPU0_SB_DQ<17>                                                
P  NNAMEm7572 M_D_CPU0_SB_DQ<16>                                                
P  NNAMEm7573 M_D_CPU0_SB_DQ<15>                                                
P  NNAMEm7574 M_D_CPU0_SB_DQ<14>                                                
P  NNAMEm7575 M_D_CPU0_SB_DQ<13>                                                
P  NNAMEm7576 M_D_CPU0_SB_DQ<12>                                                
P  NNAMEm7577 M_D_CPU0_SB_DQ<11>                                                
P  NNAMEm7578 M_D_CPU0_SB_DQ<10>                                                
P  NNAMEm7579 M_D_CPU0_SB_DQ<0>                                                 
P  NNAMEm7580 M_D_CPU0_SB_CS_N<1>                                               
P  NNAMEm7581 M_D_CPU0_SB_CS_N<0>                                               
P  NNAMEm7582 M_D_CPU0_SB_CB<7>                                                 
P  NNAMEm7583 M_D_CPU0_SB_CB<6>                                                 
P  NNAMEm7584 M_D_CPU0_SB_CB<5>                                                 
P  NNAMEm7585 M_D_CPU0_SB_CB<4>                                                 
P  NNAMEm7586 M_D_CPU0_SB_CB<3>                                                 
P  NNAMEm7587 M_D_CPU0_SB_CB<2>                                                 
P  NNAMEm7588 M_D_CPU0_SB_CB<1>                                                 
P  NNAMEm7589 M_D_CPU0_SB_CB<0>                                                 
P  NNAMEm7590 M_D_CPU0_SB_CA<6>                                                 
P  NNAMEm7591 M_D_CPU0_SB_CA<5>                                                 
P  NNAMEm7592 M_D_CPU0_SB_CA<4>                                                 
P  NNAMEm7593 M_D_CPU0_SB_CA<3>                                                 
P  NNAMEm7594 M_D_CPU0_SB_CA<2>                                                 
P  NNAMEm7595 M_D_CPU0_SB_CA<1>                                                 
P  NNAMEm7596 M_D_CPU0_SB_CA<0>                                                 
P  NNAMEm7597 M_D_CPU0_SA_RSP<0>                                                
P  NNAMEm7598 M_D_CPU0_SA_PAR                                                   
P  NNAMEm7599 M_D_CPU0_SA_DQS_DP<9>                                             
P  NNAMEm7600 M_D_CPU0_SA_DQS_DP<8>                                             
P  NNAMEm7601 M_D_CPU0_SA_DQS_DP<7>                                             
P  NNAMEm7602 M_D_CPU0_SA_DQS_DP<6>                                             
P  NNAMEm7603 M_D_CPU0_SA_DQS_DP<5>                                             
P  NNAMEm7604 M_D_CPU0_SA_DQS_DP<4>                                             
P  NNAMEm7605 M_D_CPU0_SA_DQS_DP<3>                                             
P  NNAMEm7606 M_D_CPU0_SA_DQS_DP<2>                                             
P  NNAMEm7607 M_D_CPU0_SA_DQS_DP<1>                                             
P  NNAMEm7608 M_D_CPU0_SA_DQS_DP<0>                                             
P  NNAMEm7609 M_D_CPU0_SA_DQS_DN<9>                                             
P  NNAMEm7610 M_D_CPU0_SA_DQS_DN<8>                                             
P  NNAMEm7611 M_D_CPU0_SA_DQS_DN<7>                                             
P  NNAMEm7612 M_D_CPU0_SA_DQS_DN<6>                                             
P  NNAMEm7613 M_D_CPU0_SA_DQS_DN<5>                                             
P  NNAMEm7614 M_D_CPU0_SA_DQS_DN<4>                                             
P  NNAMEm7615 M_D_CPU0_SA_DQS_DN<3>                                             
P  NNAMEm7616 M_D_CPU0_SA_DQS_DN<2>                                             
P  NNAMEm7617 M_D_CPU0_SA_DQS_DN<1>                                             
P  NNAMEm7618 M_D_CPU0_SA_DQS_DN<0>                                             
P  NNAMEm7619 M_D_CPU0_SA_DQ<9>                                                 
P  NNAMEm7620 M_D_CPU0_SA_DQ<8>                                                 
P  NNAMEm7621 M_D_CPU0_SA_DQ<7>                                                 
P  NNAMEm7622 M_D_CPU0_SA_DQ<6>                                                 
P  NNAMEm7623 M_D_CPU0_SA_DQ<5>                                                 
P  NNAMEm7624 M_D_CPU0_SA_DQ<4>                                                 
P  NNAMEm7625 M_D_CPU0_SA_DQ<3>                                                 
P  NNAMEm7626 M_D_CPU0_SA_DQ<31>                                                
P  NNAMEm7627 M_D_CPU0_SA_DQ<30>                                                
P  NNAMEm7628 M_D_CPU0_SA_DQ<2>                                                 
P  NNAMEm7629 M_D_CPU0_SA_DQ<29>                                                
P  NNAMEm7630 M_D_CPU0_SA_DQ<28>                                                
P  NNAMEm7631 M_D_CPU0_SA_DQ<27>                                                
P  NNAMEm7632 M_D_CPU0_SA_DQ<26>                                                
P  NNAMEm7633 M_D_CPU0_SA_DQ<25>                                                
P  NNAMEm7634 M_D_CPU0_SA_DQ<24>                                                
P  NNAMEm7635 M_D_CPU0_SA_DQ<23>                                                
P  NNAMEm7636 M_D_CPU0_SA_DQ<22>                                                
P  NNAMEm7637 M_D_CPU0_SA_DQ<21>                                                
P  NNAMEm7638 M_D_CPU0_SA_DQ<20>                                                
P  NNAMEm7639 M_D_CPU0_SA_DQ<1>                                                 
P  NNAMEm7640 M_D_CPU0_SA_DQ<19>                                                
P  NNAMEm7641 M_D_CPU0_SA_DQ<18>                                                
P  NNAMEm7642 M_D_CPU0_SA_DQ<17>                                                
P  NNAMEm7643 M_D_CPU0_SA_DQ<16>                                                
P  NNAMEm7644 M_D_CPU0_SA_DQ<15>                                                
P  NNAMEm7645 M_D_CPU0_SA_DQ<14>                                                
P  NNAMEm7646 M_D_CPU0_SA_DQ<13>                                                
P  NNAMEm7647 M_D_CPU0_SA_DQ<12>                                                
P  NNAMEm7648 M_D_CPU0_SA_DQ<11>                                                
P  NNAMEm7649 M_D_CPU0_SA_DQ<10>                                                
P  NNAMEm7650 M_D_CPU0_SA_DQ<0>                                                 
P  NNAMEm7651 M_D_CPU0_SA_CS_N<1>                                               
P  NNAMEm7652 M_D_CPU0_SA_CS_N<0>                                               
P  NNAMEm7653 M_D_CPU0_SA_CB<7>                                                 
P  NNAMEm7654 M_D_CPU0_SA_CB<6>                                                 
P  NNAMEm7655 M_D_CPU0_SA_CB<5>                                                 
P  NNAMEm7656 M_D_CPU0_SA_CB<4>                                                 
P  NNAMEm7657 M_D_CPU0_SA_CB<3>                                                 
P  NNAMEm7658 M_D_CPU0_SA_CB<2>                                                 
P  NNAMEm7659 M_D_CPU0_SA_CB<1>                                                 
P  NNAMEm7660 M_D_CPU0_SA_CB<0>                                                 
P  NNAMEm7661 M_D_CPU0_SA_CA<6>                                                 
P  NNAMEm7662 M_D_CPU0_SA_CA<5>                                                 
P  NNAMEm7663 M_D_CPU0_SA_CA<4>                                                 
P  NNAMEm7664 M_D_CPU0_SA_CA<3>                                                 
P  NNAMEm7665 M_D_CPU0_SA_CA<2>                                                 
P  NNAMEm7666 M_D_CPU0_SA_CA<1>                                                 
P  NNAMEm7667 M_D_CPU0_SA_CA<0>                                                 
P  NNAMEm7668 M_D_CPU0_RESET_N                                                  
P  NNAMEm7669 M_D_CPU0_CLK_DP<0>                                                
P  NNAMEm7670 M_D_CPU0_CLK_DN<0>                                                
P  NNAMEm7671 M_D_CPU0_ALERT_R_N                                                
P  NNAMEm7672 M_D_CPU0_ALERT_N                                                  
P  NNAMEm7673 M_C_CPU1_SB_RSP<0>                                                
P  NNAMEm7674 M_C_CPU1_SB_PAR                                                   
P  NNAMEm7675 M_C_CPU1_SB_DQS_DP<9>                                             
P  NNAMEm7676 M_C_CPU1_SB_DQS_DP<8>                                             
P  NNAMEm7677 M_C_CPU1_SB_DQS_DP<7>                                             
P  NNAMEm7678 M_C_CPU1_SB_DQS_DP<6>                                             
P  NNAMEm7679 M_C_CPU1_SB_DQS_DP<5>                                             
P  NNAMEm7680 M_C_CPU1_SB_DQS_DP<4>                                             
P  NNAMEm7681 M_C_CPU1_SB_DQS_DP<3>                                             
P  NNAMEm7682 M_C_CPU1_SB_DQS_DP<2>                                             
P  NNAMEm7683 M_C_CPU1_SB_DQS_DP<1>                                             
P  NNAMEm7684 M_C_CPU1_SB_DQS_DP<0>                                             
P  NNAMEm7685 M_C_CPU1_SB_DQS_DN<9>                                             
P  NNAMEm7686 M_C_CPU1_SB_DQS_DN<8>                                             
P  NNAMEm7687 M_C_CPU1_SB_DQS_DN<7>                                             
P  NNAMEm7688 M_C_CPU1_SB_DQS_DN<6>                                             
P  NNAMEm7689 M_C_CPU1_SB_DQS_DN<5>                                             
P  NNAMEm7690 M_C_CPU1_SB_DQS_DN<4>                                             
P  NNAMEm7691 M_C_CPU1_SB_DQS_DN<3>                                             
P  NNAMEm7692 M_C_CPU1_SB_DQS_DN<2>                                             
P  NNAMEm7693 M_C_CPU1_SB_DQS_DN<1>                                             
P  NNAMEm7694 M_C_CPU1_SB_DQS_DN<0>                                             
P  NNAMEm7695 M_C_CPU1_SB_DQ<9>                                                 
P  NNAMEm7696 M_C_CPU1_SB_DQ<8>                                                 
P  NNAMEm7697 M_C_CPU1_SB_DQ<7>                                                 
P  NNAMEm7698 M_C_CPU1_SB_DQ<6>                                                 
P  NNAMEm7699 M_C_CPU1_SB_DQ<5>                                                 
P  NNAMEm7700 M_C_CPU1_SB_DQ<4>                                                 
P  NNAMEm7701 M_C_CPU1_SB_DQ<3>                                                 
P  NNAMEm7702 M_C_CPU1_SB_DQ<31>                                                
P  NNAMEm7703 M_C_CPU1_SB_DQ<30>                                                
P  NNAMEm7704 M_C_CPU1_SB_DQ<2>                                                 
P  NNAMEm7705 M_C_CPU1_SB_DQ<29>                                                
P  NNAMEm7706 M_C_CPU1_SB_DQ<28>                                                
P  NNAMEm7707 M_C_CPU1_SB_DQ<27>                                                
P  NNAMEm7708 M_C_CPU1_SB_DQ<26>                                                
P  NNAMEm7709 M_C_CPU1_SB_DQ<25>                                                
P  NNAMEm7710 M_C_CPU1_SB_DQ<24>                                                
P  NNAMEm7711 M_C_CPU1_SB_DQ<23>                                                
P  NNAMEm7712 M_C_CPU1_SB_DQ<22>                                                
P  NNAMEm7713 M_C_CPU1_SB_DQ<21>                                                
P  NNAMEm7714 M_C_CPU1_SB_DQ<20>                                                
P  NNAMEm7715 M_C_CPU1_SB_DQ<1>                                                 
P  NNAMEm7716 M_C_CPU1_SB_DQ<19>                                                
P  NNAMEm7717 M_C_CPU1_SB_DQ<18>                                                
P  NNAMEm7718 M_C_CPU1_SB_DQ<17>                                                
P  NNAMEm7719 M_C_CPU1_SB_DQ<16>                                                
P  NNAMEm7720 M_C_CPU1_SB_DQ<15>                                                
P  NNAMEm7721 M_C_CPU1_SB_DQ<14>                                                
P  NNAMEm7722 M_C_CPU1_SB_DQ<13>                                                
P  NNAMEm7723 M_C_CPU1_SB_DQ<12>                                                
P  NNAMEm7724 M_C_CPU1_SB_DQ<11>                                                
P  NNAMEm7725 M_C_CPU1_SB_DQ<10>                                                
P  NNAMEm7726 M_C_CPU1_SB_DQ<0>                                                 
P  NNAMEm7727 M_C_CPU1_SB_CS_N<1>                                               
P  NNAMEm7728 M_C_CPU1_SB_CS_N<0>                                               
P  NNAMEm7729 M_C_CPU1_SB_CB<7>                                                 
P  NNAMEm7730 M_C_CPU1_SB_CB<6>                                                 
P  NNAMEm7731 M_C_CPU1_SB_CB<5>                                                 
P  NNAMEm7732 M_C_CPU1_SB_CB<4>                                                 
P  NNAMEm7733 M_C_CPU1_SB_CB<3>                                                 
P  NNAMEm7734 M_C_CPU1_SB_CB<2>                                                 
P  NNAMEm7735 M_C_CPU1_SB_CB<1>                                                 
P  NNAMEm7736 M_C_CPU1_SB_CB<0>                                                 
P  NNAMEm7737 M_C_CPU1_SB_CA<6>                                                 
P  NNAMEm7738 M_C_CPU1_SB_CA<5>                                                 
P  NNAMEm7739 M_C_CPU1_SB_CA<4>                                                 
P  NNAMEm7740 M_C_CPU1_SB_CA<3>                                                 
P  NNAMEm7741 M_C_CPU1_SB_CA<2>                                                 
P  NNAMEm7742 M_C_CPU1_SB_CA<1>                                                 
P  NNAMEm7743 M_C_CPU1_SB_CA<0>                                                 
P  NNAMEm7744 M_C_CPU1_SA_RSP<0>                                                
P  NNAMEm7745 M_C_CPU1_SA_PAR                                                   
P  NNAMEm7746 M_C_CPU1_SA_DQS_DP<9>                                             
P  NNAMEm7747 M_C_CPU1_SA_DQS_DP<8>                                             
P  NNAMEm7748 M_C_CPU1_SA_DQS_DP<7>                                             
P  NNAMEm7749 M_C_CPU1_SA_DQS_DP<6>                                             
P  NNAMEm7750 M_C_CPU1_SA_DQS_DP<5>                                             
P  NNAMEm7751 M_C_CPU1_SA_DQS_DP<4>                                             
P  NNAMEm7752 M_C_CPU1_SA_DQS_DP<3>                                             
P  NNAMEm7753 M_C_CPU1_SA_DQS_DP<2>                                             
P  NNAMEm7754 M_C_CPU1_SA_DQS_DP<1>                                             
P  NNAMEm7755 M_C_CPU1_SA_DQS_DP<0>                                             
P  NNAMEm7756 M_C_CPU1_SA_DQS_DN<9>                                             
P  NNAMEm7757 M_C_CPU1_SA_DQS_DN<8>                                             
P  NNAMEm7758 M_C_CPU1_SA_DQS_DN<7>                                             
P  NNAMEm7759 M_C_CPU1_SA_DQS_DN<6>                                             
P  NNAMEm7760 M_C_CPU1_SA_DQS_DN<5>                                             
P  NNAMEm7761 M_C_CPU1_SA_DQS_DN<4>                                             
P  NNAMEm7762 M_C_CPU1_SA_DQS_DN<3>                                             
P  NNAMEm7763 M_C_CPU1_SA_DQS_DN<2>                                             
P  NNAMEm7764 M_C_CPU1_SA_DQS_DN<1>                                             
P  NNAMEm7765 M_C_CPU1_SA_DQS_DN<0>                                             
P  NNAMEm7766 M_C_CPU1_SA_DQ<9>                                                 
P  NNAMEm7767 M_C_CPU1_SA_DQ<8>                                                 
P  NNAMEm7768 M_C_CPU1_SA_DQ<7>                                                 
P  NNAMEm7769 M_C_CPU1_SA_DQ<6>                                                 
P  NNAMEm7770 M_C_CPU1_SA_DQ<5>                                                 
P  NNAMEm7771 M_C_CPU1_SA_DQ<4>                                                 
P  NNAMEm7772 M_C_CPU1_SA_DQ<3>                                                 
P  NNAMEm7773 M_C_CPU1_SA_DQ<31>                                                
P  NNAMEm7774 M_C_CPU1_SA_DQ<30>                                                
P  NNAMEm7775 M_C_CPU1_SA_DQ<2>                                                 
P  NNAMEm7776 M_C_CPU1_SA_DQ<29>                                                
P  NNAMEm7777 M_C_CPU1_SA_DQ<28>                                                
P  NNAMEm7778 M_C_CPU1_SA_DQ<27>                                                
P  NNAMEm7779 M_C_CPU1_SA_DQ<26>                                                
P  NNAMEm7780 M_C_CPU1_SA_DQ<25>                                                
P  NNAMEm7781 M_C_CPU1_SA_DQ<24>                                                
P  NNAMEm7782 M_C_CPU1_SA_DQ<23>                                                
P  NNAMEm7783 M_C_CPU1_SA_DQ<22>                                                
P  NNAMEm7784 M_C_CPU1_SA_DQ<21>                                                
P  NNAMEm7785 M_C_CPU1_SA_DQ<20>                                                
P  NNAMEm7786 M_C_CPU1_SA_DQ<1>                                                 
P  NNAMEm7787 M_C_CPU1_SA_DQ<19>                                                
P  NNAMEm7788 M_C_CPU1_SA_DQ<18>                                                
P  NNAMEm7789 M_C_CPU1_SA_DQ<17>                                                
P  NNAMEm7790 M_C_CPU1_SA_DQ<16>                                                
P  NNAMEm7791 M_C_CPU1_SA_DQ<15>                                                
P  NNAMEm7792 M_C_CPU1_SA_DQ<14>                                                
P  NNAMEm7793 M_C_CPU1_SA_DQ<13>                                                
P  NNAMEm7794 M_C_CPU1_SA_DQ<12>                                                
P  NNAMEm7795 M_C_CPU1_SA_DQ<11>                                                
P  NNAMEm7796 M_C_CPU1_SA_DQ<10>                                                
P  NNAMEm7797 M_C_CPU1_SA_DQ<0>                                                 
P  NNAMEm7798 M_C_CPU1_SA_CS_N<1>                                               
P  NNAMEm7799 M_C_CPU1_SA_CS_N<0>                                               
P  NNAMEm7800 M_C_CPU1_SA_CB<7>                                                 
P  NNAMEm7801 M_C_CPU1_SA_CB<6>                                                 
P  NNAMEm7802 M_C_CPU1_SA_CB<5>                                                 
P  NNAMEm7803 M_C_CPU1_SA_CB<4>                                                 
P  NNAMEm7804 M_C_CPU1_SA_CB<3>                                                 
P  NNAMEm7805 M_C_CPU1_SA_CB<2>                                                 
P  NNAMEm7806 M_C_CPU1_SA_CB<1>                                                 
P  NNAMEm7807 M_C_CPU1_SA_CB<0>                                                 
P  NNAMEm7808 M_C_CPU1_SA_CA<6>                                                 
P  NNAMEm7809 M_C_CPU1_SA_CA<5>                                                 
P  NNAMEm7810 M_C_CPU1_SA_CA<4>                                                 
P  NNAMEm7811 M_C_CPU1_SA_CA<3>                                                 
P  NNAMEm7812 M_C_CPU1_SA_CA<2>                                                 
P  NNAMEm7813 M_C_CPU1_SA_CA<1>                                                 
P  NNAMEm7814 M_C_CPU1_SA_CA<0>                                                 
P  NNAMEm7815 M_C_CPU1_RESET_N                                                  
P  NNAMEm7816 M_C_CPU1_CLK_DP<0>                                                
P  NNAMEm7817 M_C_CPU1_CLK_DN<0>                                                
P  NNAMEm7818 M_C_CPU1_ALERT_R_N                                                
P  NNAMEm7819 M_C_CPU1_ALERT_N                                                  
P  NNAMEm7820 M_C_CPU0_SB_RSP<0>                                                
P  NNAMEm7821 M_C_CPU0_SB_PAR                                                   
P  NNAMEm7822 M_C_CPU0_SB_DQS_DP<9>                                             
P  NNAMEm7823 M_C_CPU0_SB_DQS_DP<8>                                             
P  NNAMEm7824 M_C_CPU0_SB_DQS_DP<7>                                             
P  NNAMEm7825 M_C_CPU0_SB_DQS_DP<6>                                             
P  NNAMEm7826 M_C_CPU0_SB_DQS_DP<5>                                             
P  NNAMEm7827 M_C_CPU0_SB_DQS_DP<4>                                             
P  NNAMEm7828 M_C_CPU0_SB_DQS_DP<3>                                             
P  NNAMEm7829 M_C_CPU0_SB_DQS_DP<2>                                             
P  NNAMEm7830 M_C_CPU0_SB_DQS_DP<1>                                             
P  NNAMEm7831 M_C_CPU0_SB_DQS_DP<0>                                             
P  NNAMEm7832 M_C_CPU0_SB_DQS_DN<9>                                             
P  NNAMEm7833 M_C_CPU0_SB_DQS_DN<8>                                             
P  NNAMEm7834 M_C_CPU0_SB_DQS_DN<7>                                             
P  NNAMEm7835 M_C_CPU0_SB_DQS_DN<6>                                             
P  NNAMEm7836 M_C_CPU0_SB_DQS_DN<5>                                             
P  NNAMEm7837 M_C_CPU0_SB_DQS_DN<4>                                             
P  NNAMEm7838 M_C_CPU0_SB_DQS_DN<3>                                             
P  NNAMEm7839 M_C_CPU0_SB_DQS_DN<2>                                             
P  NNAMEm7840 M_C_CPU0_SB_DQS_DN<1>                                             
P  NNAMEm7841 M_C_CPU0_SB_DQS_DN<0>                                             
P  NNAMEm7842 M_C_CPU0_SB_DQ<9>                                                 
P  NNAMEm7843 M_C_CPU0_SB_DQ<8>                                                 
P  NNAMEm7844 M_C_CPU0_SB_DQ<7>                                                 
P  NNAMEm7845 M_C_CPU0_SB_DQ<6>                                                 
P  NNAMEm7846 M_C_CPU0_SB_DQ<5>                                                 
P  NNAMEm7847 M_C_CPU0_SB_DQ<4>                                                 
P  NNAMEm7848 M_C_CPU0_SB_DQ<3>                                                 
P  NNAMEm7849 M_C_CPU0_SB_DQ<31>                                                
P  NNAMEm7850 M_C_CPU0_SB_DQ<30>                                                
P  NNAMEm7851 M_C_CPU0_SB_DQ<2>                                                 
P  NNAMEm7852 M_C_CPU0_SB_DQ<29>                                                
P  NNAMEm7853 M_C_CPU0_SB_DQ<28>                                                
P  NNAMEm7854 M_C_CPU0_SB_DQ<27>                                                
P  NNAMEm7855 M_C_CPU0_SB_DQ<26>                                                
P  NNAMEm7856 M_C_CPU0_SB_DQ<25>                                                
P  NNAMEm7857 M_C_CPU0_SB_DQ<24>                                                
P  NNAMEm7858 M_C_CPU0_SB_DQ<23>                                                
P  NNAMEm7859 M_C_CPU0_SB_DQ<22>                                                
P  NNAMEm7860 M_C_CPU0_SB_DQ<21>                                                
P  NNAMEm7861 M_C_CPU0_SB_DQ<20>                                                
P  NNAMEm7862 M_C_CPU0_SB_DQ<1>                                                 
P  NNAMEm7863 M_C_CPU0_SB_DQ<19>                                                
P  NNAMEm7864 M_C_CPU0_SB_DQ<18>                                                
P  NNAMEm7865 M_C_CPU0_SB_DQ<17>                                                
P  NNAMEm7866 M_C_CPU0_SB_DQ<16>                                                
P  NNAMEm7867 M_C_CPU0_SB_DQ<15>                                                
P  NNAMEm7868 M_C_CPU0_SB_DQ<14>                                                
P  NNAMEm7869 M_C_CPU0_SB_DQ<13>                                                
P  NNAMEm7870 M_C_CPU0_SB_DQ<12>                                                
P  NNAMEm7871 M_C_CPU0_SB_DQ<11>                                                
P  NNAMEm7872 M_C_CPU0_SB_DQ<10>                                                
P  NNAMEm7873 M_C_CPU0_SB_DQ<0>                                                 
P  NNAMEm7874 M_C_CPU0_SB_CS_N<1>                                               
P  NNAMEm7875 M_C_CPU0_SB_CS_N<0>                                               
P  NNAMEm7876 M_C_CPU0_SB_CB<7>                                                 
P  NNAMEm7877 M_C_CPU0_SB_CB<6>                                                 
P  NNAMEm7878 M_C_CPU0_SB_CB<5>                                                 
P  NNAMEm7879 M_C_CPU0_SB_CB<4>                                                 
P  NNAMEm7880 M_C_CPU0_SB_CB<3>                                                 
P  NNAMEm7881 M_C_CPU0_SB_CB<2>                                                 
P  NNAMEm7882 M_C_CPU0_SB_CB<1>                                                 
P  NNAMEm7883 M_C_CPU0_SB_CB<0>                                                 
P  NNAMEm7884 M_C_CPU0_SB_CA<6>                                                 
P  NNAMEm7885 M_C_CPU0_SB_CA<5>                                                 
P  NNAMEm7886 M_C_CPU0_SB_CA<4>                                                 
P  NNAMEm7887 M_C_CPU0_SB_CA<3>                                                 
P  NNAMEm7888 M_C_CPU0_SB_CA<2>                                                 
P  NNAMEm7889 M_C_CPU0_SB_CA<1>                                                 
P  NNAMEm7890 M_C_CPU0_SB_CA<0>                                                 
P  NNAMEm7891 M_C_CPU0_SA_RSP<0>                                                
P  NNAMEm7892 M_C_CPU0_SA_PAR                                                   
P  NNAMEm7893 M_C_CPU0_SA_DQS_DP<9>                                             
P  NNAMEm7894 M_C_CPU0_SA_DQS_DP<8>                                             
P  NNAMEm7895 M_C_CPU0_SA_DQS_DP<7>                                             
P  NNAMEm7896 M_C_CPU0_SA_DQS_DP<6>                                             
P  NNAMEm7897 M_C_CPU0_SA_DQS_DP<5>                                             
P  NNAMEm7898 M_C_CPU0_SA_DQS_DP<4>                                             
P  NNAMEm7899 M_C_CPU0_SA_DQS_DP<3>                                             
P  NNAMEm7900 M_C_CPU0_SA_DQS_DP<2>                                             
P  NNAMEm7901 M_C_CPU0_SA_DQS_DP<1>                                             
P  NNAMEm7902 M_C_CPU0_SA_DQS_DP<0>                                             
P  NNAMEm7903 M_C_CPU0_SA_DQS_DN<9>                                             
P  NNAMEm7904 M_C_CPU0_SA_DQS_DN<8>                                             
P  NNAMEm7905 M_C_CPU0_SA_DQS_DN<7>                                             
P  NNAMEm7906 M_C_CPU0_SA_DQS_DN<6>                                             
P  NNAMEm7907 M_C_CPU0_SA_DQS_DN<5>                                             
P  NNAMEm7908 M_C_CPU0_SA_DQS_DN<4>                                             
P  NNAMEm7909 M_C_CPU0_SA_DQS_DN<3>                                             
P  NNAMEm7910 M_C_CPU0_SA_DQS_DN<2>                                             
P  NNAMEm7911 M_C_CPU0_SA_DQS_DN<1>                                             
P  NNAMEm7912 M_C_CPU0_SA_DQS_DN<0>                                             
P  NNAMEm7913 M_C_CPU0_SA_DQ<9>                                                 
P  NNAMEm7914 M_C_CPU0_SA_DQ<8>                                                 
P  NNAMEm7915 M_C_CPU0_SA_DQ<7>                                                 
P  NNAMEm7916 M_C_CPU0_SA_DQ<6>                                                 
P  NNAMEm7917 M_C_CPU0_SA_DQ<5>                                                 
P  NNAMEm7918 M_C_CPU0_SA_DQ<4>                                                 
P  NNAMEm7919 M_C_CPU0_SA_DQ<3>                                                 
P  NNAMEm7920 M_C_CPU0_SA_DQ<31>                                                
P  NNAMEm7921 M_C_CPU0_SA_DQ<30>                                                
P  NNAMEm7922 M_C_CPU0_SA_DQ<2>                                                 
P  NNAMEm7923 M_C_CPU0_SA_DQ<29>                                                
P  NNAMEm7924 M_C_CPU0_SA_DQ<28>                                                
P  NNAMEm7925 M_C_CPU0_SA_DQ<27>                                                
P  NNAMEm7926 M_C_CPU0_SA_DQ<26>                                                
P  NNAMEm7927 M_C_CPU0_SA_DQ<25>                                                
P  NNAMEm7928 M_C_CPU0_SA_DQ<24>                                                
P  NNAMEm7929 M_C_CPU0_SA_DQ<23>                                                
P  NNAMEm7930 M_C_CPU0_SA_DQ<22>                                                
P  NNAMEm7931 M_C_CPU0_SA_DQ<21>                                                
P  NNAMEm7932 M_C_CPU0_SA_DQ<20>                                                
P  NNAMEm7933 M_C_CPU0_SA_DQ<1>                                                 
P  NNAMEm7934 M_C_CPU0_SA_DQ<19>                                                
P  NNAMEm7935 M_C_CPU0_SA_DQ<18>                                                
P  NNAMEm7936 M_C_CPU0_SA_DQ<17>                                                
P  NNAMEm7937 M_C_CPU0_SA_DQ<16>                                                
P  NNAMEm7938 M_C_CPU0_SA_DQ<15>                                                
P  NNAMEm7939 M_C_CPU0_SA_DQ<14>                                                
P  NNAMEm7940 M_C_CPU0_SA_DQ<13>                                                
P  NNAMEm7941 M_C_CPU0_SA_DQ<12>                                                
P  NNAMEm7942 M_C_CPU0_SA_DQ<11>                                                
P  NNAMEm7943 M_C_CPU0_SA_DQ<10>                                                
P  NNAMEm7944 M_C_CPU0_SA_DQ<0>                                                 
P  NNAMEm7945 M_C_CPU0_SA_CS_N<1>                                               
P  NNAMEm7946 M_C_CPU0_SA_CS_N<0>                                               
P  NNAMEm7947 M_C_CPU0_SA_CB<7>                                                 
P  NNAMEm7948 M_C_CPU0_SA_CB<6>                                                 
P  NNAMEm7949 M_C_CPU0_SA_CB<5>                                                 
P  NNAMEm7950 M_C_CPU0_SA_CB<4>                                                 
P  NNAMEm7951 M_C_CPU0_SA_CB<3>                                                 
P  NNAMEm7952 M_C_CPU0_SA_CB<2>                                                 
P  NNAMEm7953 M_C_CPU0_SA_CB<1>                                                 
P  NNAMEm7954 M_C_CPU0_SA_CB<0>                                                 
P  NNAMEm7955 M_C_CPU0_SA_CA<6>                                                 
P  NNAMEm7956 M_C_CPU0_SA_CA<5>                                                 
P  NNAMEm7957 M_C_CPU0_SA_CA<4>                                                 
P  NNAMEm7958 M_C_CPU0_SA_CA<3>                                                 
P  NNAMEm7959 M_C_CPU0_SA_CA<2>                                                 
P  NNAMEm7960 M_C_CPU0_SA_CA<1>                                                 
P  NNAMEm7961 M_C_CPU0_SA_CA<0>                                                 
P  NNAMEm7962 M_C_CPU0_RESET_N                                                  
P  NNAMEm7963 M_C_CPU0_CLK_DP<0>                                                
P  NNAMEm7964 M_C_CPU0_CLK_DN<0>                                                
P  NNAMEm7965 M_C_CPU0_ALERT_R_N                                                
P  NNAMEm7966 M_C_CPU0_ALERT_N                                                  
P  NNAMEm7967 M_B_CPU1_SB_RSP<0>                                                
P  NNAMEm7968 M_B_CPU1_SB_PAR                                                   
P  NNAMEm7969 M_B_CPU1_SB_DQS_DP<9>                                             
P  NNAMEm7970 M_B_CPU1_SB_DQS_DP<8>                                             
P  NNAMEm7971 M_B_CPU1_SB_DQS_DP<7>                                             
P  NNAMEm7972 M_B_CPU1_SB_DQS_DP<6>                                             
P  NNAMEm7973 M_B_CPU1_SB_DQS_DP<5>                                             
P  NNAMEm7974 M_B_CPU1_SB_DQS_DP<4>                                             
P  NNAMEm7975 M_B_CPU1_SB_DQS_DP<3>                                             
P  NNAMEm7976 M_B_CPU1_SB_DQS_DP<2>                                             
P  NNAMEm7977 M_B_CPU1_SB_DQS_DP<1>                                             
P  NNAMEm7978 M_B_CPU1_SB_DQS_DP<0>                                             
P  NNAMEm7979 M_B_CPU1_SB_DQS_DN<9>                                             
P  NNAMEm7980 M_B_CPU1_SB_DQS_DN<8>                                             
P  NNAMEm7981 M_B_CPU1_SB_DQS_DN<7>                                             
P  NNAMEm7982 M_B_CPU1_SB_DQS_DN<6>                                             
P  NNAMEm7983 M_B_CPU1_SB_DQS_DN<5>                                             
P  NNAMEm7984 M_B_CPU1_SB_DQS_DN<4>                                             
P  NNAMEm7985 M_B_CPU1_SB_DQS_DN<3>                                             
P  NNAMEm7986 M_B_CPU1_SB_DQS_DN<2>                                             
P  NNAMEm7987 M_B_CPU1_SB_DQS_DN<1>                                             
P  NNAMEm7988 M_B_CPU1_SB_DQS_DN<0>                                             
P  NNAMEm7989 M_B_CPU1_SB_DQ<9>                                                 
P  NNAMEm7990 M_B_CPU1_SB_DQ<8>                                                 
P  NNAMEm7991 M_B_CPU1_SB_DQ<7>                                                 
P  NNAMEm7992 M_B_CPU1_SB_DQ<6>                                                 
P  NNAMEm7993 M_B_CPU1_SB_DQ<5>                                                 
P  NNAMEm7994 M_B_CPU1_SB_DQ<4>                                                 
P  NNAMEm7995 M_B_CPU1_SB_DQ<3>                                                 
P  NNAMEm7996 M_B_CPU1_SB_DQ<31>                                                
P  NNAMEm7997 M_B_CPU1_SB_DQ<30>                                                
P  NNAMEm7998 M_B_CPU1_SB_DQ<2>                                                 
P  NNAMEm7999 M_B_CPU1_SB_DQ<29>                                                
P  NNAMEm8000 M_B_CPU1_SB_DQ<28>                                                
P  NNAMEm8001 M_B_CPU1_SB_DQ<27>                                                
P  NNAMEm8002 M_B_CPU1_SB_DQ<26>                                                
P  NNAMEm8003 M_B_CPU1_SB_DQ<25>                                                
P  NNAMEm8004 M_B_CPU1_SB_DQ<24>                                                
P  NNAMEm8005 M_B_CPU1_SB_DQ<23>                                                
P  NNAMEm8006 M_B_CPU1_SB_DQ<22>                                                
P  NNAMEm8007 M_B_CPU1_SB_DQ<21>                                                
P  NNAMEm8008 M_B_CPU1_SB_DQ<20>                                                
P  NNAMEm8009 M_B_CPU1_SB_DQ<1>                                                 
P  NNAMEm8010 M_B_CPU1_SB_DQ<19>                                                
P  NNAMEm8011 M_B_CPU1_SB_DQ<18>                                                
P  NNAMEm8012 M_B_CPU1_SB_DQ<17>                                                
P  NNAMEm8013 M_B_CPU1_SB_DQ<16>                                                
P  NNAMEm8014 M_B_CPU1_SB_DQ<15>                                                
P  NNAMEm8015 M_B_CPU1_SB_DQ<14>                                                
P  NNAMEm8016 M_B_CPU1_SB_DQ<13>                                                
P  NNAMEm8017 M_B_CPU1_SB_DQ<12>                                                
P  NNAMEm8018 M_B_CPU1_SB_DQ<11>                                                
P  NNAMEm8019 M_B_CPU1_SB_DQ<10>                                                
P  NNAMEm8020 M_B_CPU1_SB_DQ<0>                                                 
P  NNAMEm8021 M_B_CPU1_SB_CS_N<1>                                               
P  NNAMEm8022 M_B_CPU1_SB_CS_N<0>                                               
P  NNAMEm8023 M_B_CPU1_SB_CB<7>                                                 
P  NNAMEm8024 M_B_CPU1_SB_CB<6>                                                 
P  NNAMEm8025 M_B_CPU1_SB_CB<5>                                                 
P  NNAMEm8026 M_B_CPU1_SB_CB<4>                                                 
P  NNAMEm8027 M_B_CPU1_SB_CB<3>                                                 
P  NNAMEm8028 M_B_CPU1_SB_CB<2>                                                 
P  NNAMEm8029 M_B_CPU1_SB_CB<1>                                                 
P  NNAMEm8030 M_B_CPU1_SB_CB<0>                                                 
P  NNAMEm8031 M_B_CPU1_SB_CA<6>                                                 
P  NNAMEm8032 M_B_CPU1_SB_CA<5>                                                 
P  NNAMEm8033 M_B_CPU1_SB_CA<4>                                                 
P  NNAMEm8034 M_B_CPU1_SB_CA<3>                                                 
P  NNAMEm8035 M_B_CPU1_SB_CA<2>                                                 
P  NNAMEm8036 M_B_CPU1_SB_CA<1>                                                 
P  NNAMEm8037 M_B_CPU1_SB_CA<0>                                                 
P  NNAMEm8038 M_B_CPU1_SA_RSP<0>                                                
P  NNAMEm8039 M_B_CPU1_SA_PAR                                                   
P  NNAMEm8040 M_B_CPU1_SA_DQS_DP<9>                                             
P  NNAMEm8041 M_B_CPU1_SA_DQS_DP<8>                                             
P  NNAMEm8042 M_B_CPU1_SA_DQS_DP<7>                                             
P  NNAMEm8043 M_B_CPU1_SA_DQS_DP<6>                                             
P  NNAMEm8044 M_B_CPU1_SA_DQS_DP<5>                                             
P  NNAMEm8045 M_B_CPU1_SA_DQS_DP<4>                                             
P  NNAMEm8046 M_B_CPU1_SA_DQS_DP<3>                                             
P  NNAMEm8047 M_B_CPU1_SA_DQS_DP<2>                                             
P  NNAMEm8048 M_B_CPU1_SA_DQS_DP<1>                                             
P  NNAMEm8049 M_B_CPU1_SA_DQS_DP<0>                                             
P  NNAMEm8050 M_B_CPU1_SA_DQS_DN<9>                                             
P  NNAMEm8051 M_B_CPU1_SA_DQS_DN<8>                                             
P  NNAMEm8052 M_B_CPU1_SA_DQS_DN<7>                                             
P  NNAMEm8053 M_B_CPU1_SA_DQS_DN<6>                                             
P  NNAMEm8054 M_B_CPU1_SA_DQS_DN<5>                                             
P  NNAMEm8055 M_B_CPU1_SA_DQS_DN<4>                                             
P  NNAMEm8056 M_B_CPU1_SA_DQS_DN<3>                                             
P  NNAMEm8057 M_B_CPU1_SA_DQS_DN<2>                                             
P  NNAMEm8058 M_B_CPU1_SA_DQS_DN<1>                                             
P  NNAMEm8059 M_B_CPU1_SA_DQS_DN<0>                                             
P  NNAMEm8060 M_B_CPU1_SA_DQ<9>                                                 
P  NNAMEm8061 M_B_CPU1_SA_DQ<8>                                                 
P  NNAMEm8062 M_B_CPU1_SA_DQ<7>                                                 
P  NNAMEm8063 M_B_CPU1_SA_DQ<6>                                                 
P  NNAMEm8064 M_B_CPU1_SA_DQ<5>                                                 
P  NNAMEm8065 M_B_CPU1_SA_DQ<4>                                                 
P  NNAMEm8066 M_B_CPU1_SA_DQ<3>                                                 
P  NNAMEm8067 M_B_CPU1_SA_DQ<31>                                                
P  NNAMEm8068 M_B_CPU1_SA_DQ<30>                                                
P  NNAMEm8069 M_B_CPU1_SA_DQ<2>                                                 
P  NNAMEm8070 M_B_CPU1_SA_DQ<29>                                                
P  NNAMEm8071 M_B_CPU1_SA_DQ<28>                                                
P  NNAMEm8072 M_B_CPU1_SA_DQ<27>                                                
P  NNAMEm8073 M_B_CPU1_SA_DQ<26>                                                
P  NNAMEm8074 M_B_CPU1_SA_DQ<25>                                                
P  NNAMEm8075 M_B_CPU1_SA_DQ<24>                                                
P  NNAMEm8076 M_B_CPU1_SA_DQ<23>                                                
P  NNAMEm8077 M_B_CPU1_SA_DQ<22>                                                
P  NNAMEm8078 M_B_CPU1_SA_DQ<21>                                                
P  NNAMEm8079 M_B_CPU1_SA_DQ<20>                                                
P  NNAMEm8080 M_B_CPU1_SA_DQ<1>                                                 
P  NNAMEm8081 M_B_CPU1_SA_DQ<19>                                                
P  NNAMEm8082 M_B_CPU1_SA_DQ<18>                                                
P  NNAMEm8083 M_B_CPU1_SA_DQ<17>                                                
P  NNAMEm8084 M_B_CPU1_SA_DQ<16>                                                
P  NNAMEm8085 M_B_CPU1_SA_DQ<15>                                                
P  NNAMEm8086 M_B_CPU1_SA_DQ<14>                                                
P  NNAMEm8087 M_B_CPU1_SA_DQ<13>                                                
P  NNAMEm8088 M_B_CPU1_SA_DQ<12>                                                
P  NNAMEm8089 M_B_CPU1_SA_DQ<11>                                                
P  NNAMEm8090 M_B_CPU1_SA_DQ<10>                                                
P  NNAMEm8091 M_B_CPU1_SA_DQ<0>                                                 
P  NNAMEm8092 M_B_CPU1_SA_CS_N<1>                                               
P  NNAMEm8093 M_B_CPU1_SA_CS_N<0>                                               
P  NNAMEm8094 M_B_CPU1_SA_CB<7>                                                 
P  NNAMEm8095 M_B_CPU1_SA_CB<6>                                                 
P  NNAMEm8096 M_B_CPU1_SA_CB<5>                                                 
P  NNAMEm8097 M_B_CPU1_SA_CB<4>                                                 
P  NNAMEm8098 M_B_CPU1_SA_CB<3>                                                 
P  NNAMEm8099 M_B_CPU1_SA_CB<2>                                                 
P  NNAMEm8100 M_B_CPU1_SA_CB<1>                                                 
P  NNAMEm8101 M_B_CPU1_SA_CB<0>                                                 
P  NNAMEm8102 M_B_CPU1_SA_CA<6>                                                 
P  NNAMEm8103 M_B_CPU1_SA_CA<5>                                                 
P  NNAMEm8104 M_B_CPU1_SA_CA<4>                                                 
P  NNAMEm8105 M_B_CPU1_SA_CA<3>                                                 
P  NNAMEm8106 M_B_CPU1_SA_CA<2>                                                 
P  NNAMEm8107 M_B_CPU1_SA_CA<1>                                                 
P  NNAMEm8108 M_B_CPU1_SA_CA<0>                                                 
P  NNAMEm8109 M_B_CPU1_RESET_N                                                  
P  NNAMEm8110 M_B_CPU1_CLK_DP<0>                                                
P  NNAMEm8111 M_B_CPU1_CLK_DN<0>                                                
P  NNAMEm8112 M_B_CPU1_ALERT_R_N                                                
P  NNAMEm8113 M_B_CPU1_ALERT_N                                                  
P  NNAMEm8114 M_B_CPU0_SB_RSP<0>                                                
P  NNAMEm8115 M_B_CPU0_SB_PAR                                                   
P  NNAMEm8116 M_B_CPU0_SB_DQS_DP<9>                                             
P  NNAMEm8117 M_B_CPU0_SB_DQS_DP<8>                                             
P  NNAMEm8118 M_B_CPU0_SB_DQS_DP<7>                                             
P  NNAMEm8119 M_B_CPU0_SB_DQS_DP<6>                                             
P  NNAMEm8120 M_B_CPU0_SB_DQS_DP<5>                                             
P  NNAMEm8121 M_B_CPU0_SB_DQS_DP<4>                                             
P  NNAMEm8122 M_B_CPU0_SB_DQS_DP<3>                                             
P  NNAMEm8123 M_B_CPU0_SB_DQS_DP<2>                                             
P  NNAMEm8124 M_B_CPU0_SB_DQS_DP<1>                                             
P  NNAMEm8125 M_B_CPU0_SB_DQS_DP<0>                                             
P  NNAMEm8126 M_B_CPU0_SB_DQS_DN<9>                                             
P  NNAMEm8127 M_B_CPU0_SB_DQS_DN<8>                                             
P  NNAMEm8128 M_B_CPU0_SB_DQS_DN<7>                                             
P  NNAMEm8129 M_B_CPU0_SB_DQS_DN<6>                                             
P  NNAMEm8130 M_B_CPU0_SB_DQS_DN<5>                                             
P  NNAMEm8131 M_B_CPU0_SB_DQS_DN<4>                                             
P  NNAMEm8132 M_B_CPU0_SB_DQS_DN<3>                                             
P  NNAMEm8133 M_B_CPU0_SB_DQS_DN<2>                                             
P  NNAMEm8134 M_B_CPU0_SB_DQS_DN<1>                                             
P  NNAMEm8135 M_B_CPU0_SB_DQS_DN<0>                                             
P  NNAMEm8136 M_B_CPU0_SB_DQ<9>                                                 
P  NNAMEm8137 M_B_CPU0_SB_DQ<8>                                                 
P  NNAMEm8138 M_B_CPU0_SB_DQ<7>                                                 
P  NNAMEm8139 M_B_CPU0_SB_DQ<6>                                                 
P  NNAMEm8140 M_B_CPU0_SB_DQ<5>                                                 
P  NNAMEm8141 M_B_CPU0_SB_DQ<4>                                                 
P  NNAMEm8142 M_B_CPU0_SB_DQ<3>                                                 
P  NNAMEm8143 M_B_CPU0_SB_DQ<31>                                                
P  NNAMEm8144 M_B_CPU0_SB_DQ<30>                                                
P  NNAMEm8145 M_B_CPU0_SB_DQ<2>                                                 
P  NNAMEm8146 M_B_CPU0_SB_DQ<29>                                                
P  NNAMEm8147 M_B_CPU0_SB_DQ<28>                                                
P  NNAMEm8148 M_B_CPU0_SB_DQ<27>                                                
P  NNAMEm8149 M_B_CPU0_SB_DQ<26>                                                
P  NNAMEm8150 M_B_CPU0_SB_DQ<25>                                                
P  NNAMEm8151 M_B_CPU0_SB_DQ<24>                                                
P  NNAMEm8152 M_B_CPU0_SB_DQ<23>                                                
P  NNAMEm8153 M_B_CPU0_SB_DQ<22>                                                
P  NNAMEm8154 M_B_CPU0_SB_DQ<21>                                                
P  NNAMEm8155 M_B_CPU0_SB_DQ<20>                                                
P  NNAMEm8156 M_B_CPU0_SB_DQ<1>                                                 
P  NNAMEm8157 M_B_CPU0_SB_DQ<19>                                                
P  NNAMEm8158 M_B_CPU0_SB_DQ<18>                                                
P  NNAMEm8159 M_B_CPU0_SB_DQ<17>                                                
P  NNAMEm8160 M_B_CPU0_SB_DQ<16>                                                
P  NNAMEm8161 M_B_CPU0_SB_DQ<15>                                                
P  NNAMEm8162 M_B_CPU0_SB_DQ<14>                                                
P  NNAMEm8163 M_B_CPU0_SB_DQ<13>                                                
P  NNAMEm8164 M_B_CPU0_SB_DQ<12>                                                
P  NNAMEm8165 M_B_CPU0_SB_DQ<11>                                                
P  NNAMEm8166 M_B_CPU0_SB_DQ<10>                                                
P  NNAMEm8167 M_B_CPU0_SB_DQ<0>                                                 
P  NNAMEm8168 M_B_CPU0_SB_CS_N<1>                                               
P  NNAMEm8169 M_B_CPU0_SB_CS_N<0>                                               
P  NNAMEm8170 M_B_CPU0_SB_CB<7>                                                 
P  NNAMEm8171 M_B_CPU0_SB_CB<6>                                                 
P  NNAMEm8172 M_B_CPU0_SB_CB<5>                                                 
P  NNAMEm8173 M_B_CPU0_SB_CB<4>                                                 
P  NNAMEm8174 M_B_CPU0_SB_CB<3>                                                 
P  NNAMEm8175 M_B_CPU0_SB_CB<2>                                                 
P  NNAMEm8176 M_B_CPU0_SB_CB<1>                                                 
P  NNAMEm8177 M_B_CPU0_SB_CB<0>                                                 
P  NNAMEm8178 M_B_CPU0_SB_CA<6>                                                 
P  NNAMEm8179 M_B_CPU0_SB_CA<5>                                                 
P  NNAMEm8180 M_B_CPU0_SB_CA<4>                                                 
P  NNAMEm8181 M_B_CPU0_SB_CA<3>                                                 
P  NNAMEm8182 M_B_CPU0_SB_CA<2>                                                 
P  NNAMEm8183 M_B_CPU0_SB_CA<1>                                                 
P  NNAMEm8184 M_B_CPU0_SB_CA<0>                                                 
P  NNAMEm8185 M_B_CPU0_SA_RSP<0>                                                
P  NNAMEm8186 M_B_CPU0_SA_PAR                                                   
P  NNAMEm8187 M_B_CPU0_SA_DQS_DP<9>                                             
P  NNAMEm8188 M_B_CPU0_SA_DQS_DP<8>                                             
P  NNAMEm8189 M_B_CPU0_SA_DQS_DP<7>                                             
P  NNAMEm8190 M_B_CPU0_SA_DQS_DP<6>                                             
P  NNAMEm8191 M_B_CPU0_SA_DQS_DP<5>                                             
P  NNAMEm8192 M_B_CPU0_SA_DQS_DP<4>                                             
P  NNAMEm8193 M_B_CPU0_SA_DQS_DP<3>                                             
P  NNAMEm8194 M_B_CPU0_SA_DQS_DP<2>                                             
P  NNAMEm8195 M_B_CPU0_SA_DQS_DP<1>                                             
P  NNAMEm8196 M_B_CPU0_SA_DQS_DP<0>                                             
P  NNAMEm8197 M_B_CPU0_SA_DQS_DN<9>                                             
P  NNAMEm8198 M_B_CPU0_SA_DQS_DN<8>                                             
P  NNAMEm8199 M_B_CPU0_SA_DQS_DN<7>                                             
P  NNAMEm8200 M_B_CPU0_SA_DQS_DN<6>                                             
P  NNAMEm8201 M_B_CPU0_SA_DQS_DN<5>                                             
P  NNAMEm8202 M_B_CPU0_SA_DQS_DN<4>                                             
P  NNAMEm8203 M_B_CPU0_SA_DQS_DN<3>                                             
P  NNAMEm8204 M_B_CPU0_SA_DQS_DN<2>                                             
P  NNAMEm8205 M_B_CPU0_SA_DQS_DN<1>                                             
P  NNAMEm8206 M_B_CPU0_SA_DQS_DN<0>                                             
P  NNAMEm8207 M_B_CPU0_SA_DQ<9>                                                 
P  NNAMEm8208 M_B_CPU0_SA_DQ<8>                                                 
P  NNAMEm8209 M_B_CPU0_SA_DQ<7>                                                 
P  NNAMEm8210 M_B_CPU0_SA_DQ<6>                                                 
P  NNAMEm8211 M_B_CPU0_SA_DQ<5>                                                 
P  NNAMEm8212 M_B_CPU0_SA_DQ<4>                                                 
P  NNAMEm8213 M_B_CPU0_SA_DQ<3>                                                 
P  NNAMEm8214 M_B_CPU0_SA_DQ<31>                                                
P  NNAMEm8215 M_B_CPU0_SA_DQ<30>                                                
P  NNAMEm8216 M_B_CPU0_SA_DQ<2>                                                 
P  NNAMEm8217 M_B_CPU0_SA_DQ<29>                                                
P  NNAMEm8218 M_B_CPU0_SA_DQ<28>                                                
P  NNAMEm8219 M_B_CPU0_SA_DQ<27>                                                
P  NNAMEm8220 M_B_CPU0_SA_DQ<26>                                                
P  NNAMEm8221 M_B_CPU0_SA_DQ<25>                                                
P  NNAMEm8222 M_B_CPU0_SA_DQ<24>                                                
P  NNAMEm8223 M_B_CPU0_SA_DQ<23>                                                
P  NNAMEm8224 M_B_CPU0_SA_DQ<22>                                                
P  NNAMEm8225 M_B_CPU0_SA_DQ<21>                                                
P  NNAMEm8226 M_B_CPU0_SA_DQ<20>                                                
P  NNAMEm8227 M_B_CPU0_SA_DQ<1>                                                 
P  NNAMEm8228 M_B_CPU0_SA_DQ<19>                                                
P  NNAMEm8229 M_B_CPU0_SA_DQ<18>                                                
P  NNAMEm8230 M_B_CPU0_SA_DQ<17>                                                
P  NNAMEm8231 M_B_CPU0_SA_DQ<16>                                                
P  NNAMEm8232 M_B_CPU0_SA_DQ<15>                                                
P  NNAMEm8233 M_B_CPU0_SA_DQ<14>                                                
P  NNAMEm8234 M_B_CPU0_SA_DQ<13>                                                
P  NNAMEm8235 M_B_CPU0_SA_DQ<12>                                                
P  NNAMEm8236 M_B_CPU0_SA_DQ<11>                                                
P  NNAMEm8237 M_B_CPU0_SA_DQ<10>                                                
P  NNAMEm8238 M_B_CPU0_SA_DQ<0>                                                 
P  NNAMEm8239 M_B_CPU0_SA_CS_N<1>                                               
P  NNAMEm8240 M_B_CPU0_SA_CS_N<0>                                               
P  NNAMEm8241 M_B_CPU0_SA_CB<7>                                                 
P  NNAMEm8242 M_B_CPU0_SA_CB<6>                                                 
P  NNAMEm8243 M_B_CPU0_SA_CB<5>                                                 
P  NNAMEm8244 M_B_CPU0_SA_CB<4>                                                 
P  NNAMEm8245 M_B_CPU0_SA_CB<3>                                                 
P  NNAMEm8246 M_B_CPU0_SA_CB<2>                                                 
P  NNAMEm8247 M_B_CPU0_SA_CB<1>                                                 
P  NNAMEm8248 M_B_CPU0_SA_CB<0>                                                 
P  NNAMEm8249 M_B_CPU0_SA_CA<6>                                                 
P  NNAMEm8250 M_B_CPU0_SA_CA<5>                                                 
P  NNAMEm8251 M_B_CPU0_SA_CA<4>                                                 
P  NNAMEm8252 M_B_CPU0_SA_CA<3>                                                 
P  NNAMEm8253 M_B_CPU0_SA_CA<2>                                                 
P  NNAMEm8254 M_B_CPU0_SA_CA<1>                                                 
P  NNAMEm8255 M_B_CPU0_SA_CA<0>                                                 
P  NNAMEm8256 M_B_CPU0_RESET_N                                                  
P  NNAMEm8257 M_B_CPU0_CLK_DP<0>                                                
P  NNAMEm8258 M_B_CPU0_CLK_DN<0>                                                
P  NNAMEm8259 M_B_CPU0_ALERT_R_N                                                
P  NNAMEm8260 M_B_CPU0_ALERT_N                                                  
P  NNAMEm8261 M_A_CPU1_SB_RSP<0>                                                
P  NNAMEm8262 M_A_CPU1_SB_PAR                                                   
P  NNAMEm8263 M_A_CPU1_SB_DQS_DP<9>                                             
P  NNAMEm8264 M_A_CPU1_SB_DQS_DP<8>                                             
P  NNAMEm8265 M_A_CPU1_SB_DQS_DP<7>                                             
P  NNAMEm8266 M_A_CPU1_SB_DQS_DP<6>                                             
P  NNAMEm8267 M_A_CPU1_SB_DQS_DP<5>                                             
P  NNAMEm8268 M_A_CPU1_SB_DQS_DP<4>                                             
P  NNAMEm8269 M_A_CPU1_SB_DQS_DP<3>                                             
P  NNAMEm8270 M_A_CPU1_SB_DQS_DP<2>                                             
P  NNAMEm8271 M_A_CPU1_SB_DQS_DP<1>                                             
P  NNAMEm8272 M_A_CPU1_SB_DQS_DP<0>                                             
P  NNAMEm8273 M_A_CPU1_SB_DQS_DN<9>                                             
P  NNAMEm8274 M_A_CPU1_SB_DQS_DN<8>                                             
P  NNAMEm8275 M_A_CPU1_SB_DQS_DN<7>                                             
P  NNAMEm8276 M_A_CPU1_SB_DQS_DN<6>                                             
P  NNAMEm8277 M_A_CPU1_SB_DQS_DN<5>                                             
P  NNAMEm8278 M_A_CPU1_SB_DQS_DN<4>                                             
P  NNAMEm8279 M_A_CPU1_SB_DQS_DN<3>                                             
P  NNAMEm8280 M_A_CPU1_SB_DQS_DN<2>                                             
P  NNAMEm8281 M_A_CPU1_SB_DQS_DN<1>                                             
P  NNAMEm8282 M_A_CPU1_SB_DQS_DN<0>                                             
P  NNAMEm8283 M_A_CPU1_SB_DQ<9>                                                 
P  NNAMEm8284 M_A_CPU1_SB_DQ<8>                                                 
P  NNAMEm8285 M_A_CPU1_SB_DQ<7>                                                 
P  NNAMEm8286 M_A_CPU1_SB_DQ<6>                                                 
P  NNAMEm8287 M_A_CPU1_SB_DQ<5>                                                 
P  NNAMEm8288 M_A_CPU1_SB_DQ<4>                                                 
P  NNAMEm8289 M_A_CPU1_SB_DQ<3>                                                 
P  NNAMEm8290 M_A_CPU1_SB_DQ<31>                                                
P  NNAMEm8291 M_A_CPU1_SB_DQ<30>                                                
P  NNAMEm8292 M_A_CPU1_SB_DQ<2>                                                 
P  NNAMEm8293 M_A_CPU1_SB_DQ<29>                                                
P  NNAMEm8294 M_A_CPU1_SB_DQ<28>                                                
P  NNAMEm8295 M_A_CPU1_SB_DQ<27>                                                
P  NNAMEm8296 M_A_CPU1_SB_DQ<26>                                                
P  NNAMEm8297 M_A_CPU1_SB_DQ<25>                                                
P  NNAMEm8298 M_A_CPU1_SB_DQ<24>                                                
P  NNAMEm8299 M_A_CPU1_SB_DQ<23>                                                
P  NNAMEm8300 M_A_CPU1_SB_DQ<22>                                                
P  NNAMEm8301 M_A_CPU1_SB_DQ<21>                                                
P  NNAMEm8302 M_A_CPU1_SB_DQ<20>                                                
P  NNAMEm8303 M_A_CPU1_SB_DQ<1>                                                 
P  NNAMEm8304 M_A_CPU1_SB_DQ<19>                                                
P  NNAMEm8305 M_A_CPU1_SB_DQ<18>                                                
P  NNAMEm8306 M_A_CPU1_SB_DQ<17>                                                
P  NNAMEm8307 M_A_CPU1_SB_DQ<16>                                                
P  NNAMEm8308 M_A_CPU1_SB_DQ<15>                                                
P  NNAMEm8309 M_A_CPU1_SB_DQ<14>                                                
P  NNAMEm8310 M_A_CPU1_SB_DQ<13>                                                
P  NNAMEm8311 M_A_CPU1_SB_DQ<12>                                                
P  NNAMEm8312 M_A_CPU1_SB_DQ<11>                                                
P  NNAMEm8313 M_A_CPU1_SB_DQ<10>                                                
P  NNAMEm8314 M_A_CPU1_SB_DQ<0>                                                 
P  NNAMEm8315 M_A_CPU1_SB_CS_N<1>                                               
P  NNAMEm8316 M_A_CPU1_SB_CS_N<0>                                               
P  NNAMEm8317 M_A_CPU1_SB_CB<7>                                                 
P  NNAMEm8318 M_A_CPU1_SB_CB<6>                                                 
P  NNAMEm8319 M_A_CPU1_SB_CB<5>                                                 
P  NNAMEm8320 M_A_CPU1_SB_CB<4>                                                 
P  NNAMEm8321 M_A_CPU1_SB_CB<3>                                                 
P  NNAMEm8322 M_A_CPU1_SB_CB<2>                                                 
P  NNAMEm8323 M_A_CPU1_SB_CB<1>                                                 
P  NNAMEm8324 M_A_CPU1_SB_CB<0>                                                 
P  NNAMEm8325 M_A_CPU1_SB_CA<6>                                                 
P  NNAMEm8326 M_A_CPU1_SB_CA<5>                                                 
P  NNAMEm8327 M_A_CPU1_SB_CA<4>                                                 
P  NNAMEm8328 M_A_CPU1_SB_CA<3>                                                 
P  NNAMEm8329 M_A_CPU1_SB_CA<2>                                                 
P  NNAMEm8330 M_A_CPU1_SB_CA<1>                                                 
P  NNAMEm8331 M_A_CPU1_SB_CA<0>                                                 
P  NNAMEm8332 M_A_CPU1_SA_RSP<0>                                                
P  NNAMEm8333 M_A_CPU1_SA_PAR                                                   
P  NNAMEm8334 M_A_CPU1_SA_DQS_DP<9>                                             
P  NNAMEm8335 M_A_CPU1_SA_DQS_DP<8>                                             
P  NNAMEm8336 M_A_CPU1_SA_DQS_DP<7>                                             
P  NNAMEm8337 M_A_CPU1_SA_DQS_DP<6>                                             
P  NNAMEm8338 M_A_CPU1_SA_DQS_DP<5>                                             
P  NNAMEm8339 M_A_CPU1_SA_DQS_DP<4>                                             
P  NNAMEm8340 M_A_CPU1_SA_DQS_DP<3>                                             
P  NNAMEm8341 M_A_CPU1_SA_DQS_DP<2>                                             
P  NNAMEm8342 M_A_CPU1_SA_DQS_DP<1>                                             
P  NNAMEm8343 M_A_CPU1_SA_DQS_DP<0>                                             
P  NNAMEm8344 M_A_CPU1_SA_DQS_DN<9>                                             
P  NNAMEm8345 M_A_CPU1_SA_DQS_DN<8>                                             
P  NNAMEm8346 M_A_CPU1_SA_DQS_DN<7>                                             
P  NNAMEm8347 M_A_CPU1_SA_DQS_DN<6>                                             
P  NNAMEm8348 M_A_CPU1_SA_DQS_DN<5>                                             
P  NNAMEm8349 M_A_CPU1_SA_DQS_DN<4>                                             
P  NNAMEm8350 M_A_CPU1_SA_DQS_DN<3>                                             
P  NNAMEm8351 M_A_CPU1_SA_DQS_DN<2>                                             
P  NNAMEm8352 M_A_CPU1_SA_DQS_DN<1>                                             
P  NNAMEm8353 M_A_CPU1_SA_DQS_DN<0>                                             
P  NNAMEm8354 M_A_CPU1_SA_DQ<9>                                                 
P  NNAMEm8355 M_A_CPU1_SA_DQ<8>                                                 
P  NNAMEm8356 M_A_CPU1_SA_DQ<7>                                                 
P  NNAMEm8357 M_A_CPU1_SA_DQ<6>                                                 
P  NNAMEm8358 M_A_CPU1_SA_DQ<5>                                                 
P  NNAMEm8359 M_A_CPU1_SA_DQ<4>                                                 
P  NNAMEm8360 M_A_CPU1_SA_DQ<3>                                                 
P  NNAMEm8361 M_A_CPU1_SA_DQ<31>                                                
P  NNAMEm8362 M_A_CPU1_SA_DQ<30>                                                
P  NNAMEm8363 M_A_CPU1_SA_DQ<2>                                                 
P  NNAMEm8364 M_A_CPU1_SA_DQ<29>                                                
P  NNAMEm8365 M_A_CPU1_SA_DQ<28>                                                
P  NNAMEm8366 M_A_CPU1_SA_DQ<27>                                                
P  NNAMEm8367 M_A_CPU1_SA_DQ<26>                                                
P  NNAMEm8368 M_A_CPU1_SA_DQ<25>                                                
P  NNAMEm8369 M_A_CPU1_SA_DQ<24>                                                
P  NNAMEm8370 M_A_CPU1_SA_DQ<23>                                                
P  NNAMEm8371 M_A_CPU1_SA_DQ<22>                                                
P  NNAMEm8372 M_A_CPU1_SA_DQ<21>                                                
P  NNAMEm8373 M_A_CPU1_SA_DQ<20>                                                
P  NNAMEm8374 M_A_CPU1_SA_DQ<1>                                                 
P  NNAMEm8375 M_A_CPU1_SA_DQ<19>                                                
P  NNAMEm8376 M_A_CPU1_SA_DQ<18>                                                
P  NNAMEm8377 M_A_CPU1_SA_DQ<17>                                                
P  NNAMEm8378 M_A_CPU1_SA_DQ<16>                                                
P  NNAMEm8379 M_A_CPU1_SA_DQ<15>                                                
P  NNAMEm8380 M_A_CPU1_SA_DQ<14>                                                
P  NNAMEm8381 M_A_CPU1_SA_DQ<13>                                                
P  NNAMEm8382 M_A_CPU1_SA_DQ<12>                                                
P  NNAMEm8383 M_A_CPU1_SA_DQ<11>                                                
P  NNAMEm8384 M_A_CPU1_SA_DQ<10>                                                
P  NNAMEm8385 M_A_CPU1_SA_DQ<0>                                                 
P  NNAMEm8386 M_A_CPU1_SA_CS_N<1>                                               
P  NNAMEm8387 M_A_CPU1_SA_CS_N<0>                                               
P  NNAMEm8388 M_A_CPU1_SA_CB<7>                                                 
P  NNAMEm8389 M_A_CPU1_SA_CB<6>                                                 
P  NNAMEm8390 M_A_CPU1_SA_CB<5>                                                 
P  NNAMEm8391 M_A_CPU1_SA_CB<4>                                                 
P  NNAMEm8392 M_A_CPU1_SA_CB<3>                                                 
P  NNAMEm8393 M_A_CPU1_SA_CB<2>                                                 
P  NNAMEm8394 M_A_CPU1_SA_CB<1>                                                 
P  NNAMEm8395 M_A_CPU1_SA_CB<0>                                                 
P  NNAMEm8396 M_A_CPU1_SA_CA<6>                                                 
P  NNAMEm8397 M_A_CPU1_SA_CA<5>                                                 
P  NNAMEm8398 M_A_CPU1_SA_CA<4>                                                 
P  NNAMEm8399 M_A_CPU1_SA_CA<3>                                                 
P  NNAMEm8400 M_A_CPU1_SA_CA<2>                                                 
P  NNAMEm8401 M_A_CPU1_SA_CA<1>                                                 
P  NNAMEm8402 M_A_CPU1_SA_CA<0>                                                 
P  NNAMEm8403 M_A_CPU1_RESET_N                                                  
P  NNAMEm8404 M_A_CPU1_CLK_DP<0>                                                
P  NNAMEm8405 M_A_CPU1_CLK_DN<0>                                                
P  NNAMEm8406 M_A_CPU1_ALERT_R_N                                                
P  NNAMEm8407 M_A_CPU1_ALERT_N                                                  
P  NNAMEm8408 M_A_CPU0_SB_RSP<0>                                                
P  NNAMEm8409 M_A_CPU0_SB_PAR                                                   
P  NNAMEm8410 M_A_CPU0_SB_DQS_DP<9>                                             
P  NNAMEm8411 M_A_CPU0_SB_DQS_DP<8>                                             
P  NNAMEm8412 M_A_CPU0_SB_DQS_DP<7>                                             
P  NNAMEm8413 M_A_CPU0_SB_DQS_DP<6>                                             
P  NNAMEm8414 M_A_CPU0_SB_DQS_DP<5>                                             
P  NNAMEm8415 M_A_CPU0_SB_DQS_DP<4>                                             
P  NNAMEm8416 M_A_CPU0_SB_DQS_DP<3>                                             
P  NNAMEm8417 M_A_CPU0_SB_DQS_DP<2>                                             
P  NNAMEm8418 M_A_CPU0_SB_DQS_DP<1>                                             
P  NNAMEm8419 M_A_CPU0_SB_DQS_DP<0>                                             
P  NNAMEm8420 M_A_CPU0_SB_DQS_DN<9>                                             
P  NNAMEm8421 M_A_CPU0_SB_DQS_DN<8>                                             
P  NNAMEm8422 M_A_CPU0_SB_DQS_DN<7>                                             
P  NNAMEm8423 M_A_CPU0_SB_DQS_DN<6>                                             
P  NNAMEm8424 M_A_CPU0_SB_DQS_DN<5>                                             
P  NNAMEm8425 M_A_CPU0_SB_DQS_DN<4>                                             
P  NNAMEm8426 M_A_CPU0_SB_DQS_DN<3>                                             
P  NNAMEm8427 M_A_CPU0_SB_DQS_DN<2>                                             
P  NNAMEm8428 M_A_CPU0_SB_DQS_DN<1>                                             
P  NNAMEm8429 M_A_CPU0_SB_DQS_DN<0>                                             
P  NNAMEm8430 M_A_CPU0_SB_DQ<9>                                                 
P  NNAMEm8431 M_A_CPU0_SB_DQ<8>                                                 
P  NNAMEm8432 M_A_CPU0_SB_DQ<7>                                                 
P  NNAMEm8433 M_A_CPU0_SB_DQ<6>                                                 
P  NNAMEm8434 M_A_CPU0_SB_DQ<5>                                                 
P  NNAMEm8435 M_A_CPU0_SB_DQ<4>                                                 
P  NNAMEm8436 M_A_CPU0_SB_DQ<3>                                                 
P  NNAMEm8437 M_A_CPU0_SB_DQ<31>                                                
P  NNAMEm8438 M_A_CPU0_SB_DQ<30>                                                
P  NNAMEm8439 M_A_CPU0_SB_DQ<2>                                                 
P  NNAMEm8440 M_A_CPU0_SB_DQ<29>                                                
P  NNAMEm8441 M_A_CPU0_SB_DQ<28>                                                
P  NNAMEm8442 M_A_CPU0_SB_DQ<27>                                                
P  NNAMEm8443 M_A_CPU0_SB_DQ<26>                                                
P  NNAMEm8444 M_A_CPU0_SB_DQ<25>                                                
P  NNAMEm8445 M_A_CPU0_SB_DQ<24>                                                
P  NNAMEm8446 M_A_CPU0_SB_DQ<23>                                                
P  NNAMEm8447 M_A_CPU0_SB_DQ<22>                                                
P  NNAMEm8448 M_A_CPU0_SB_DQ<21>                                                
P  NNAMEm8449 M_A_CPU0_SB_DQ<20>                                                
P  NNAMEm8450 M_A_CPU0_SB_DQ<1>                                                 
P  NNAMEm8451 M_A_CPU0_SB_DQ<19>                                                
P  NNAMEm8452 M_A_CPU0_SB_DQ<18>                                                
P  NNAMEm8453 M_A_CPU0_SB_DQ<17>                                                
P  NNAMEm8454 M_A_CPU0_SB_DQ<16>                                                
P  NNAMEm8455 M_A_CPU0_SB_DQ<15>                                                
P  NNAMEm8456 M_A_CPU0_SB_DQ<14>                                                
P  NNAMEm8457 M_A_CPU0_SB_DQ<13>                                                
P  NNAMEm8458 M_A_CPU0_SB_DQ<12>                                                
P  NNAMEm8459 M_A_CPU0_SB_DQ<11>                                                
P  NNAMEm8460 M_A_CPU0_SB_DQ<10>                                                
P  NNAMEm8461 M_A_CPU0_SB_DQ<0>                                                 
P  NNAMEm8462 M_A_CPU0_SB_CS_N<1>                                               
P  NNAMEm8463 M_A_CPU0_SB_CS_N<0>                                               
P  NNAMEm8464 M_A_CPU0_SB_CB<7>                                                 
P  NNAMEm8465 M_A_CPU0_SB_CB<6>                                                 
P  NNAMEm8466 M_A_CPU0_SB_CB<5>                                                 
P  NNAMEm8467 M_A_CPU0_SB_CB<4>                                                 
P  NNAMEm8468 M_A_CPU0_SB_CB<3>                                                 
P  NNAMEm8469 M_A_CPU0_SB_CB<2>                                                 
P  NNAMEm8470 M_A_CPU0_SB_CB<1>                                                 
P  NNAMEm8471 M_A_CPU0_SB_CB<0>                                                 
P  NNAMEm8472 M_A_CPU0_SB_CA<6>                                                 
P  NNAMEm8473 M_A_CPU0_SB_CA<5>                                                 
P  NNAMEm8474 M_A_CPU0_SB_CA<4>                                                 
P  NNAMEm8475 M_A_CPU0_SB_CA<3>                                                 
P  NNAMEm8476 M_A_CPU0_SB_CA<2>                                                 
P  NNAMEm8477 M_A_CPU0_SB_CA<1>                                                 
P  NNAMEm8478 M_A_CPU0_SB_CA<0>                                                 
P  NNAMEm8479 M_A_CPU0_SA_RSP<0>                                                
P  NNAMEm8480 M_A_CPU0_SA_PAR                                                   
P  NNAMEm8481 M_A_CPU0_SA_DQS_DP<9>                                             
P  NNAMEm8482 M_A_CPU0_SA_DQS_DP<8>                                             
P  NNAMEm8483 M_A_CPU0_SA_DQS_DP<7>                                             
P  NNAMEm8484 M_A_CPU0_SA_DQS_DP<6>                                             
P  NNAMEm8485 M_A_CPU0_SA_DQS_DP<5>                                             
P  NNAMEm8486 M_A_CPU0_SA_DQS_DP<4>                                             
P  NNAMEm8487 M_A_CPU0_SA_DQS_DP<3>                                             
P  NNAMEm8488 M_A_CPU0_SA_DQS_DP<2>                                             
P  NNAMEm8489 M_A_CPU0_SA_DQS_DP<1>                                             
P  NNAMEm8490 M_A_CPU0_SA_DQS_DP<0>                                             
P  NNAMEm8491 M_A_CPU0_SA_DQS_DN<9>                                             
P  NNAMEm8492 M_A_CPU0_SA_DQS_DN<8>                                             
P  NNAMEm8493 M_A_CPU0_SA_DQS_DN<7>                                             
P  NNAMEm8494 M_A_CPU0_SA_DQS_DN<6>                                             
P  NNAMEm8495 M_A_CPU0_SA_DQS_DN<5>                                             
P  NNAMEm8496 M_A_CPU0_SA_DQS_DN<4>                                             
P  NNAMEm8497 M_A_CPU0_SA_DQS_DN<3>                                             
P  NNAMEm8498 M_A_CPU0_SA_DQS_DN<2>                                             
P  NNAMEm8499 M_A_CPU0_SA_DQS_DN<1>                                             
P  NNAMEm8500 M_A_CPU0_SA_DQS_DN<0>                                             
P  NNAMEm8501 M_A_CPU0_SA_DQ<9>                                                 
P  NNAMEm8502 M_A_CPU0_SA_DQ<8>                                                 
P  NNAMEm8503 M_A_CPU0_SA_DQ<7>                                                 
P  NNAMEm8504 M_A_CPU0_SA_DQ<6>                                                 
P  NNAMEm8505 M_A_CPU0_SA_DQ<5>                                                 
P  NNAMEm8506 M_A_CPU0_SA_DQ<4>                                                 
P  NNAMEm8507 M_A_CPU0_SA_DQ<3>                                                 
P  NNAMEm8508 M_A_CPU0_SA_DQ<31>                                                
P  NNAMEm8509 M_A_CPU0_SA_DQ<30>                                                
P  NNAMEm8510 M_A_CPU0_SA_DQ<2>                                                 
P  NNAMEm8511 M_A_CPU0_SA_DQ<29>                                                
P  NNAMEm8512 M_A_CPU0_SA_DQ<28>                                                
P  NNAMEm8513 M_A_CPU0_SA_DQ<27>                                                
P  NNAMEm8514 M_A_CPU0_SA_DQ<26>                                                
P  NNAMEm8515 M_A_CPU0_SA_DQ<25>                                                
P  NNAMEm8516 M_A_CPU0_SA_DQ<24>                                                
P  NNAMEm8517 M_A_CPU0_SA_DQ<23>                                                
P  NNAMEm8518 M_A_CPU0_SA_DQ<22>                                                
P  NNAMEm8519 M_A_CPU0_SA_DQ<21>                                                
P  NNAMEm8520 M_A_CPU0_SA_DQ<20>                                                
P  NNAMEm8521 M_A_CPU0_SA_DQ<1>                                                 
P  NNAMEm8522 M_A_CPU0_SA_DQ<19>                                                
P  NNAMEm8523 M_A_CPU0_SA_DQ<18>                                                
P  NNAMEm8524 M_A_CPU0_SA_DQ<17>                                                
P  NNAMEm8525 M_A_CPU0_SA_DQ<16>                                                
P  NNAMEm8526 M_A_CPU0_SA_DQ<15>                                                
P  NNAMEm8527 M_A_CPU0_SA_DQ<14>                                                
P  NNAMEm8528 M_A_CPU0_SA_DQ<13>                                                
P  NNAMEm8529 M_A_CPU0_SA_DQ<12>                                                
P  NNAMEm8530 M_A_CPU0_SA_DQ<11>                                                
P  NNAMEm8531 M_A_CPU0_SA_DQ<10>                                                
P  NNAMEm8532 M_A_CPU0_SA_DQ<0>                                                 
P  NNAMEm8533 M_A_CPU0_SA_CS_N<1>                                               
P  NNAMEm8534 M_A_CPU0_SA_CS_N<0>                                               
P  NNAMEm8535 M_A_CPU0_SA_CB<7>                                                 
P  NNAMEm8536 M_A_CPU0_SA_CB<6>                                                 
P  NNAMEm8537 M_A_CPU0_SA_CB<5>                                                 
P  NNAMEm8538 M_A_CPU0_SA_CB<4>                                                 
P  NNAMEm8539 M_A_CPU0_SA_CB<3>                                                 
P  NNAMEm8540 M_A_CPU0_SA_CB<2>                                                 
P  NNAMEm8541 M_A_CPU0_SA_CB<1>                                                 
P  NNAMEm8542 M_A_CPU0_SA_CB<0>                                                 
P  NNAMEm8543 M_A_CPU0_SA_CA<6>                                                 
P  NNAMEm8544 M_A_CPU0_SA_CA<5>                                                 
P  NNAMEm8545 M_A_CPU0_SA_CA<4>                                                 
P  NNAMEm8546 M_A_CPU0_SA_CA<3>                                                 
P  NNAMEm8547 M_A_CPU0_SA_CA<2>                                                 
P  NNAMEm8548 M_A_CPU0_SA_CA<1>                                                 
P  NNAMEm8549 M_A_CPU0_SA_CA<0>                                                 
P  NNAMEm8550 M_A_CPU0_RESET_N                                                  
P  NNAMEm8551 M_A_CPU0_CLK_DP<0>                                                
P  NNAMEm8552 M_A_CPU0_CLK_DN<0>                                                
P  NNAMEm8553 M_A_CPU0_ALERT_R_N                                                
P  NNAMEm8554 M_A_CPU0_ALERT_N                                                  
P  NNAMEm8555 MB0_P12V_STBY_PWRGD                                               
P  NNAMEm8556 M2_SSD0_CLKREQ_EN_N_BUF                                           
P  NNAMEm8557 M2_SSD0_CLKREQ_EN_N                                               
P  NNAMEm8558 LED_M2_SSD_0_ACT_N                                                
P  NNAMEm8559 LED_HDD_ACTIVITY_N                                                
P  NNAMEm8560 LED_HDD_ACTIVITY_B_N                                              
P  NNAMEm8561 LED_BIOS_DBG_MODE_R                                               
P  NNAMEm8562 LED_BIOS_DBG_MODE_N                                               
P  NNAMEm8563 LED_BIOS_DBG_MODE                                                 
P  NNAMEm8564 JTAG_SCM_TRST_R_N                                                 
P  NNAMEm8565 JTAG_SCM_TRST_N                                                   
P  NNAMEm8566 JTAG_SCM_PLD_TMS                                                  
P  NNAMEm8567 JTAG_SCM_PLD_TDO                                                  
P  NNAMEm8568 JTAG_SCM_PLD_TDI                                                  
P  NNAMEm8569 JTAG_SCM_PLD_TCK                                                  
P  NNAMEm8570 JTAG_SCM_PLD_R_TMS                                                
P  NNAMEm8571 JTAG_SCM_PLD_R_TDO                                                
P  NNAMEm8572 JTAG_SCM_PLD_R_TDI                                                
P  NNAMEm8573 JTAG_SCM_PLD_R_TCK                                                
P  NNAMEm8574 JTAG_SCM_MUX_TMS                                                  
P  NNAMEm8575 JTAG_SCM_MUX_TDO                                                  
P  NNAMEm8576 JTAG_SCM_MUX_TDI                                                  
P  NNAMEm8577 JTAG_SCM_MUX_TCK                                                  
P  NNAMEm8578 JTAG_SCM_MUX_R_TMS                                                
P  NNAMEm8579 JTAG_SCM_MUX_R_TDO                                                
P  NNAMEm8580 JTAG_SCM_MUX_R_TDI                                                
P  NNAMEm8581 JTAG_SCM_MUX_R_TCK                                                
P  NNAMEm8582 JTAG_SCM_DBREQ_N                                                  
P  NNAMEm8583 JTAG_P1_R_TRST_N                                                  
P  NNAMEm8584 JTAG_P1_R_DBREQ_N                                                 
P  NNAMEm8585 JTAG_P0_R_TRST_N                                                  
P  NNAMEm8586 JTAG_P0_R_DBREQ_N                                                 
P  NNAMEm8587 JTAG_CPU1_TRST_N                                                  
P  NNAMEm8588 JTAG_CPU1_R_TDO                                                   
P  NNAMEm8589 JTAG_CPU1_R_TDI                                                   
P  NNAMEm8590 JTAG_CPU1_DBREQ_N                                                 
P  NNAMEm8591 JTAG_CPU1_BYPASS                                                  
P  NNAMEm8592 JTAG_CPU0_TRST_N                                                  
P  NNAMEm8593 JTAG_CPU0_TDO_CPU1_TDI                                            
P  NNAMEm8594 JTAG_CPU0_R_TDO                                                   
P  NNAMEm8595 JTAG_CPU0_R_TDI                                                   
P  NNAMEm8596 JTAG_CPU0_DBREQ_N                                                 
P  NNAMEm8597 JTAG_CPU0_BYPASS                                                  
P  NNAMEm8598 JTAG_BMC_R_D_OE                                                   
P  NNAMEm8599 IRQ_UV_DETECT_N                                                   
P  NNAMEm8600 IRQ_SML1_PMBUS_ALERT_N                                            
P  NNAMEm8601 IRQ_SML1_PMBUS_ALERT                                              
P  NNAMEm8602 IRQ_LVC3_WAKE_N                                                   
P  NNAMEm8603 IRQ_LVC3_WAKE_BUF_N                                               
P  NNAMEm8604 IRQ_LVC3_V3_2_WAKE_BUF_N                                          
P  NNAMEm8605 IRQ_LVC3_OCP_V3_2_WAKE_N                                          
P  NNAMEm8606 IRQ_LVC3_OCP_SFF_WAKE_N                                           
P  NNAMEm8607 IRQ_HSC_FAULT_N                                                   
P  NNAMEm8608 INT_CPU1_HP_UBM_N                                                 
P  NNAMEm8609 IND_SOC_P1_CPL3                                                   
P  NNAMEm8610 IND_SOC_P1_CPL2                                                   
P  NNAMEm8611 IND_SOC_P1_CPL0                                                   
P  NNAMEm8612 IND_SOC_P0_CPL3                                                   
P  NNAMEm8613 IND_SOC_P0_CPL2                                                   
P  NNAMEm8614 IND_SOC_P0_CPL0                                                   
P  NNAMEm8615 IND_PVDDIO_P1_CPL4                                                
P  NNAMEm8616 IND_PVDDIO_P1_CPL3                                                
P  NNAMEm8617 IND_PVDDIO_P1_CPL2                                                
P  NNAMEm8618 IND_PVDDIO_P1_CPL0                                                
P  NNAMEm8619 IND_PVDDIO_P0_CPL4                                                
P  NNAMEm8620 IND_PVDDIO_P0_CPL3                                                
P  NNAMEm8621 IND_PVDDIO_P0_CPL2                                                
P  NNAMEm8622 IND_PVDDIO_P0_CPL0                                                
P  NNAMEm8623 IND_CPU1_P1_CPL6                                                  
P  NNAMEm8624 IND_CPU1_P1_CPL5                                                  
P  NNAMEm8625 IND_CPU1_P1_CPL3                                                  
P  NNAMEm8626 IND_CPU1_P1_CPL2                                                  
P  NNAMEm8627 IND_CPU1_P1_CPL1                                                  
P  NNAMEm8628 IND_CPU1_P1_CPL0                                                  
P  NNAMEm8629 IND_CPU1_P0_CPL6                                                  
P  NNAMEm8630 IND_CPU1_P0_CPL5                                                  
P  NNAMEm8631 IND_CPU1_P0_CPL3                                                  
P  NNAMEm8632 IND_CPU1_P0_CPL2                                                  
P  NNAMEm8633 IND_CPU1_P0_CPL1                                                  
P  NNAMEm8634 IND_CPU1_P0_CPL0                                                  
P  NNAMEm8635 IND_CPU0_P1_CPL6                                                  
P  NNAMEm8636 IND_CPU0_P1_CPL5                                                  
P  NNAMEm8637 IND_CPU0_P1_CPL3                                                  
P  NNAMEm8638 IND_CPU0_P1_CPL2                                                  
P  NNAMEm8639 IND_CPU0_P1_CPL1                                                  
P  NNAMEm8640 IND_CPU0_P1_CPL0                                                  
P  NNAMEm8641 IND_CPU0_P0_CPL6                                                  
P  NNAMEm8642 IND_CPU0_P0_CPL5                                                  
P  NNAMEm8643 IND_CPU0_P0_CPL3                                                  
P  NNAMEm8644 IND_CPU0_P0_CPL2                                                  
P  NNAMEm8645 IND_CPU0_P0_CPL1                                                  
P  NNAMEm8646 IND_CPU0_P0_CPL0                                                  
P  NNAMEm8647 I3C_SPD_DDRL_CPU1_SCL                                             
P  NNAMEm8648 I3C_SPD_DDRL_CPU0_SCL                                             
P  NNAMEm8649 I3C_SPD_DDRK_CPU1_SCL                                             
P  NNAMEm8650 I3C_SPD_DDRK_CPU0_SCL                                             
P  NNAMEm8651 I3C_SPD_DDRJ_CPU1_SCL                                             
P  NNAMEm8652 I3C_SPD_DDRJ_CPU0_SCL                                             
P  NNAMEm8653 I3C_SPD_DDRI_CPU1_SCL                                             
P  NNAMEm8654 I3C_SPD_DDRI_CPU0_SCL                                             
P  NNAMEm8655 I3C_SPD_DDRH_CPU1_SCL                                             
P  NNAMEm8656 I3C_SPD_DDRH_CPU0_SCL                                             
P  NNAMEm8657 I3C_SPD_DDRG_CPU1_SCL                                             
P  NNAMEm8658 I3C_SPD_DDRG_CPU0_SCL                                             
P  NNAMEm8659 I3C_SPD_DDRGL_CPU1_SDA                                            
P  NNAMEm8660 I3C_SPD_DDRGL_CPU1_SCL                                            
P  NNAMEm8661 I3C_SPD_DDRGL_CPU1_LVC1_SDA                                       
P  NNAMEm8662 I3C_SPD_DDRGL_CPU1_LVC1_SCL                                       
P  NNAMEm8663 I3C_SPD_DDRGL_CPU1_BYPASS_SDA                                     
P  NNAMEm8664 I3C_SPD_DDRGL_CPU1_BYPASS_SCL                                     
P  NNAMEm8665 I3C_SPD_DDRGL_CPU0_SDA                                            
P  NNAMEm8666 I3C_SPD_DDRGL_CPU0_SCL                                            
P  NNAMEm8667 I3C_SPD_DDRGL_CPU0_LVC1_SDA                                       
P  NNAMEm8668 I3C_SPD_DDRGL_CPU0_LVC1_SCL                                       
P  NNAMEm8669 I3C_SPD_DDRGL_CPU0_BYPASS_SDA                                     
P  NNAMEm8670 I3C_SPD_DDRGL_CPU0_BYPASS_SCL                                     
P  NNAMEm8671 I3C_SPD_DDRF_CPU1_SCL                                             
P  NNAMEm8672 I3C_SPD_DDRF_CPU0_SCL                                             
P  NNAMEm8673 I3C_SPD_DDRE_CPU1_SCL                                             
P  NNAMEm8674 I3C_SPD_DDRE_CPU0_SCL                                             
P  NNAMEm8675 I3C_SPD_DDRD_CPU1_SCL                                             
P  NNAMEm8676 I3C_SPD_DDRD_CPU0_SCL                                             
P  NNAMEm8677 I3C_SPD_DDRC_CPU1_SCL                                             
P  NNAMEm8678 I3C_SPD_DDRC_CPU0_SCL                                             
P  NNAMEm8679 I3C_SPD_DDRB_CPU1_SCL                                             
P  NNAMEm8680 I3C_SPD_DDRB_CPU0_SCL                                             
P  NNAMEm8681 I3C_SPD_DDRA_CPU1_SCL                                             
P  NNAMEm8682 I3C_SPD_DDRA_CPU0_SCL                                             
P  NNAMEm8683 I3C_SPD_DDRAF_CPU1_SDA                                            
P  NNAMEm8684 I3C_SPD_DDRAF_CPU1_SCL                                            
P  NNAMEm8685 I3C_SPD_DDRAF_CPU1_LVC1_SDA                                       
P  NNAMEm8686 I3C_SPD_DDRAF_CPU1_LVC1_SCL                                       
P  NNAMEm8687 I3C_SPD_DDRAF_CPU1_BYPASS_SDA                                     
P  NNAMEm8688 I3C_SPD_DDRAF_CPU1_BYPASS_SCL                                     
P  NNAMEm8689 I3C_SPD_DDRAF_CPU0_SDA                                            
P  NNAMEm8690 I3C_SPD_DDRAF_CPU0_SCL                                            
P  NNAMEm8691 I3C_SPD_DDRAF_CPU0_LVC1_SDA                                       
P  NNAMEm8692 I3C_SPD_DDRAF_CPU0_LVC1_SCL                                       
P  NNAMEm8693 I3C_SPD_DDRAF_CPU0_BYPASS_SDA                                     
P  NNAMEm8694 I3C_SPD_DDRAF_CPU0_BYPASS_SCL                                     
P  NNAMEm8695 I3C_SCM_3_R_SDA                                                   
P  NNAMEm8696 I3C_SCM_3_R_SCL                                                   
P  NNAMEm8697 I3C_SCM_2_R_SDA                                                   
P  NNAMEm8698 I3C_SCM_2_R_SCL                                                   
P  NNAMEm8699 I3C_SCM_1_R_SDA                                                   
P  NNAMEm8700 I3C_SCM_1_R_SCL                                                   
P  NNAMEm8701 I3C_SCM_0_R_SDA                                                   
P  NNAMEm8702 I3C_SCM_0_R_SCL                                                   
P  NNAMEm8703 I3C_MUX_CPU0_VIO                                                  
P  NNAMEm8704 I3C_BMC_SWB_SDA                                                   
P  NNAMEm8705 I3C_BMC_SWB_SCL                                                   
P  NNAMEm8706 I3C_BMC_SWB_BUF_SDA                                               
P  NNAMEm8707 I3C_BMC_SWB_BUF_SCL                                               
P  NNAMEm8708 I3C_1_SPD_DDRGL_CPU1_SDA                                          
P  NNAMEm8709 I3C_1_SPD_DDRGL_CPU1_SCL                                          
P  NNAMEm8710 I3C_1_SPD_DDRGL_CPU1_R_SDA                                        
P  NNAMEm8711 I3C_1_SPD_DDRGL_CPU1_R_SCL                                        
P  NNAMEm8712 I3C_1_SPD_DDRGL_CPU0_SDA                                          
P  NNAMEm8713 I3C_1_SPD_DDRGL_CPU0_SCL                                          
P  NNAMEm8714 I3C_1_SPD_DDRGL_CPU0_R_SDA                                        
P  NNAMEm8715 I3C_1_SPD_DDRGL_CPU0_R_SCL                                        
P  NNAMEm8716 I3C_0_SPD_DDRAF_CPU1_SDA                                          
P  NNAMEm8717 I3C_0_SPD_DDRAF_CPU1_SCL                                          
P  NNAMEm8718 I3C_0_SPD_DDRAF_CPU1_R_SDA                                        
P  NNAMEm8719 I3C_0_SPD_DDRAF_CPU1_R_SCL                                        
P  NNAMEm8720 I3C_0_SPD_DDRAF_CPU0_SDA                                          
P  NNAMEm8721 I3C_0_SPD_DDRAF_CPU0_SCL                                          
P  NNAMEm8722 I3C_0_SPD_DDRAF_CPU0_R_SDA                                        
P  NNAMEm8723 I3C_0_SPD_DDRAF_CPU0_R_SCL                                        
P  NNAMEm8724 FPGA_IO3V3_RSVD_1                                                 
P  NNAMEm8725 HP_LVC3_OCP_V3_2_PRSNT2_N_R                                       
P  NNAMEm8726 HP_LVC3_OCP_V3_2_PRSNT2_PLD_N                                     
P  NNAMEm8727 HP_LVC3_OCP_V3_2_P12V_PWRGD                                       
P  NNAMEm8728 HP_LVC3_OCP_V3_1_PRSNT2_N_R                                       
P  NNAMEm8729 HP_LVC3_OCP_SFF_PRSNT2_PLD_N                                      
P  NNAMEm8730 HP_LVC3_OCP_V3_1_P12V_PWRGD                                       
P  NNAMEm8731 P3V3_OCP_SFF_EN_R                                                 
P  NNAMEm8732 HP_LVC3_E1S_0_HSC_PWRGD                                           
P  NNAMEm8733 HGX_DETECT_N_ISO                                                  
P  NNAMEm8734 HDT_HDR_TRST_N_R                                                  
P  NNAMEm8735 HDT_HDR_RESET_N                                                   
P  NNAMEm8736 HDT_HDR_DBREQ_R_N                                                 
P  NNAMEm8737 HDT_HDR_DBREQ_N                                                   
P  NNAMEm8738 HDT_CPU0_XTRIG_L7                                                 
P  NNAMEm8739 HDT_CPU0_XTRIG_L6                                                 
P  NNAMEm8740 HDT_CPU0_XTRIG_L5                                                 
P  NNAMEm8741 HDT_CPU0_HDT_CONN_TESTEN                                          
P  NNAMEm8742 HDD_ACTIVITY_BUF_N                                                
P  NNAMEm8743 HDD_ACTIVITY_BUF                                                  
P  NNAMEm8744 GPU_WP_HW_CTRL_N                                                  
P  NNAMEm8745 GPU_WP_HW_CTRL_ISO                                                
P  NNAMEm8746 GPU_PRSNT_N_ISO                                                   
P  NNAMEm8747 GPU_NVS_PWR_BRAKE_N_R                                             
P  NNAMEm8748 GPU_NVS_PWR_BRAKE_N_BUF                                           
P  NNAMEm8749 GPU_NVS_PWR_BRAKE_N                                               
P  NNAMEm8750 GPU_HMC_PRSNT_N                                                   
P  NNAMEm8751 GPU_HMC_PRSNT_ISO_N                                               
P  NNAMEm8752 GPU_FPGA_THERM_OVERT_N                                            
P  NNAMEm8753 GPU_FPGA_THERM_OVERT_ISO_N                                        
P  NNAMEm8754 GPU_FPGA_THERM_OVERT                                              
P  NNAMEm8755 GPU_FPGA_RST_R_N                                                  
P  NNAMEm8756 GPU_FPGA_RST_R_BUF_N                                              
P  NNAMEm8757 GPU_FPGA_RST_R1_BUF_N                                             
P  NNAMEm8758 GPU_FPGA_READY_N                                                  
P  NNAMEm8759 GPU_FPGA_READY_ISO                                                
P  NNAMEm8760 GPU_FPGA_OVERT_N                                                  
P  NNAMEm8761 GPU_FPGA_OVERT_ISO_N                                              
P  NNAMEm8762 GPU_FPGA_EROT_RST_N                                               
P  NNAMEm8763 GPU_FPGA_EROT_RST_BUF_R_N                                         
P  NNAMEm8764 GPU_FPGA_EROT_RST_BUF_N                                           
P  NNAMEm8765 GPU_FPGA_EROT_RECOV_N                                             
P  NNAMEm8766 GPU_FPGA_EROT_RECOV_BUF_R_N                                       
P  NNAMEm8767 GPU_FPGA_EROT_RECOV_BUF_N                                         
P  NNAMEm8768 GPU_FPGA_EROT_FATALERR_N                                          
P  NNAMEm8769 GPU_FPGA_EROT_FATALERR_ISO_N                                      
P  NNAMEm8770 GPU_FPGA_EROT_FATALERR                                            
P  NNAMEm8771 GPU_FPGA_BOOT_EN_BUF_R                                            
P  NNAMEm8772 GPU_FPGA_BOOT_EN_BUF                                              
P  NNAMEm8773 GPU_FPGA_BOOT_EN                                                  
P  NNAMEm8774 PRSNT_CABLE_GPU_A1                                                
P  NNAMEm8775 PRSNT_CABLE_GPU_A1_N                                              
P  NNAMEm8776 GPU_BASE_STBY_EN_BUF_R                                            
P  NNAMEm8777 GPU_BASE_STBY_EN_BUF                                              
P  NNAMEm8778 GPU_BASE_STBY_EN                                                  
P  NNAMEm8779 GPU_BASE_HMC_READY_N                                              
P  NNAMEm8780 GPU_BASE_HMC_READY_ISO                                            
P  NNAMEm8781 GPU_BASE_HMC_READY                                                
P  NNAMEm8782 GPU_3V3IO_RSVD5_FFU_N                                             
P  NNAMEm8783 GPU_3V3IO_RSVD5_FFU_ISO                                           
P  NNAMEm8784 GPU_3V3IO_RSVD5_FFU                                               
P  NNAMEm8785 GPU_3V3IO_RSVD4_N                                                 
P  NNAMEm8786 GPU_3V3IO_RSVD4_ISO                                               
P  NNAMEm8787 PRSNT_CABLE_GPU_A2                                                
P  NNAMEm8788 PRSNT_CABLE_GPU_A2_N                                              
P  NNAMEm8789 GPU_3V3IO_RSVD4                                                   
P  NNAMEm8790 GPU_3V3IO_RSVD3_N                                                 
P  NNAMEm8791 GPU_3V3IO_RSVD3_ISO                                               
P  NNAMEm8792 GPU_3V3IO_RSVD3_FFU_N                                             
P  NNAMEm8793 GPU_3V3IO_RSVD3_FFU_ISO                                           
P  NNAMEm8794 GPU_3V3IO_RSVD3_FFU                                               
P  NNAMEm8795 GPU_3V3IO_RSVD3                                                   
P  NNAMEm8796 PRSNT_CABLE_GPU_B3                                                
P  NNAMEm8797 PRSNT_CABLE_GPU_B3_N                                              
P  NNAMEm8798 GPU_3V3IO_RSVD1_N                                                 
P  NNAMEm8799 GPU_3V3IO_RSVD1_ISO                                               
P  NNAMEm8800 GPU_3V3IO_RSVD1_FFU_N                                             
P  NNAMEm8801 GPU_3V3IO_RSVD1_FFU_ISO                                           
P  NNAMEm8802 GPU_3V3IO_RSVD1_FFU                                               
P  NNAMEm8803 GPU_3V3IO_RSVD1                                                   
P  NNAMEm8804 GPU_3V3IO_RSVD0_FFU_N                                             
P  NNAMEm8805 GPU_3V3IO_RSVD0_FFU_ISO                                           
P  NNAMEm8806 GPU_3V3IO_RSVD0_FFU                                               
P  NNAMEm8807 GMI_CPU1_G3_CPU0_G1_TX_DP<9>                                      
P  NNAMEm8808 GMI_CPU1_G3_CPU0_G1_TX_DP<8>                                      
P  NNAMEm8809 GMI_CPU1_G3_CPU0_G1_TX_DP<7>                                      
P  NNAMEm8810 GMI_CPU1_G3_CPU0_G1_TX_DP<6>                                      
P  NNAMEm8811 GMI_CPU1_G3_CPU0_G1_TX_DP<5>                                      
P  NNAMEm8812 GMI_CPU1_G3_CPU0_G1_TX_DP<4>                                      
P  NNAMEm8813 GMI_CPU1_G3_CPU0_G1_TX_DP<3>                                      
P  NNAMEm8814 GMI_CPU1_G3_CPU0_G1_TX_DP<2>                                      
P  NNAMEm8815 GMI_CPU1_G3_CPU0_G1_TX_DP<1>                                      
P  NNAMEm8816 GMI_CPU1_G3_CPU0_G1_TX_DP<15>                                     
P  NNAMEm8817 GMI_CPU1_G3_CPU0_G1_TX_DP<14>                                     
P  NNAMEm8818 GMI_CPU1_G3_CPU0_G1_TX_DP<13>                                     
P  NNAMEm8819 GMI_CPU1_G3_CPU0_G1_TX_DP<12>                                     
P  NNAMEm8820 GMI_CPU1_G3_CPU0_G1_TX_DP<11>                                     
P  NNAMEm8821 GMI_CPU1_G3_CPU0_G1_TX_DP<10>                                     
P  NNAMEm8822 GMI_CPU1_G3_CPU0_G1_TX_DP<0>                                      
P  NNAMEm8823 GMI_CPU1_G3_CPU0_G1_TX_DN<9>                                      
P  NNAMEm8824 GMI_CPU1_G3_CPU0_G1_TX_DN<8>                                      
P  NNAMEm8825 GMI_CPU1_G3_CPU0_G1_TX_DN<7>                                      
P  NNAMEm8826 GMI_CPU1_G3_CPU0_G1_TX_DN<6>                                      
P  NNAMEm8827 GMI_CPU1_G3_CPU0_G1_TX_DN<5>                                      
P  NNAMEm8828 GMI_CPU1_G3_CPU0_G1_TX_DN<4>                                      
P  NNAMEm8829 GMI_CPU1_G3_CPU0_G1_TX_DN<3>                                      
P  NNAMEm8830 GMI_CPU1_G3_CPU0_G1_TX_DN<2>                                      
P  NNAMEm8831 GMI_CPU1_G3_CPU0_G1_TX_DN<1>                                      
P  NNAMEm8832 GMI_CPU1_G3_CPU0_G1_TX_DN<15>                                     
P  NNAMEm8833 GMI_CPU1_G3_CPU0_G1_TX_DN<14>                                     
P  NNAMEm8834 GMI_CPU1_G3_CPU0_G1_TX_DN<13>                                     
P  NNAMEm8835 GMI_CPU1_G3_CPU0_G1_TX_DN<12>                                     
P  NNAMEm8836 GMI_CPU1_G3_CPU0_G1_TX_DN<11>                                     
P  NNAMEm8837 GMI_CPU1_G3_CPU0_G1_TX_DN<10>                                     
P  NNAMEm8838 GMI_CPU1_G3_CPU0_G1_TX_DN<0>                                      
P  NNAMEm8839 GMI_CPU1_G2_CPU0_G0_TX_DP<9>                                      
P  NNAMEm8840 GMI_CPU1_G2_CPU0_G0_TX_DP<8>                                      
P  NNAMEm8841 GMI_CPU1_G2_CPU0_G0_TX_DP<7>                                      
P  NNAMEm8842 GMI_CPU1_G2_CPU0_G0_TX_DP<6>                                      
P  NNAMEm8843 GMI_CPU1_G2_CPU0_G0_TX_DP<5>                                      
P  NNAMEm8844 GMI_CPU1_G2_CPU0_G0_TX_DP<4>                                      
P  NNAMEm8845 GMI_CPU1_G2_CPU0_G0_TX_DP<3>                                      
P  NNAMEm8846 GMI_CPU1_G2_CPU0_G0_TX_DP<2>                                      
P  NNAMEm8847 GMI_CPU1_G2_CPU0_G0_TX_DP<1>                                      
P  NNAMEm8848 GMI_CPU1_G2_CPU0_G0_TX_DP<15>                                     
P  NNAMEm8849 GMI_CPU1_G2_CPU0_G0_TX_DP<14>                                     
P  NNAMEm8850 GMI_CPU1_G2_CPU0_G0_TX_DP<13>                                     
P  NNAMEm8851 GMI_CPU1_G2_CPU0_G0_TX_DP<12>                                     
P  NNAMEm8852 GMI_CPU1_G2_CPU0_G0_TX_DP<11>                                     
P  NNAMEm8853 GMI_CPU1_G2_CPU0_G0_TX_DP<10>                                     
P  NNAMEm8854 GMI_CPU1_G2_CPU0_G0_TX_DP<0>                                      
P  NNAMEm8855 GMI_CPU1_G2_CPU0_G0_TX_DN<9>                                      
P  NNAMEm8856 GMI_CPU1_G2_CPU0_G0_TX_DN<8>                                      
P  NNAMEm8857 GMI_CPU1_G2_CPU0_G0_TX_DN<7>                                      
P  NNAMEm8858 GMI_CPU1_G2_CPU0_G0_TX_DN<6>                                      
P  NNAMEm8859 GMI_CPU1_G2_CPU0_G0_TX_DN<5>                                      
P  NNAMEm8860 GMI_CPU1_G2_CPU0_G0_TX_DN<4>                                      
P  NNAMEm8861 GMI_CPU1_G2_CPU0_G0_TX_DN<3>                                      
P  NNAMEm8862 GMI_CPU1_G2_CPU0_G0_TX_DN<2>                                      
P  NNAMEm8863 GMI_CPU1_G2_CPU0_G0_TX_DN<1>                                      
P  NNAMEm8864 GMI_CPU1_G2_CPU0_G0_TX_DN<15>                                     
P  NNAMEm8865 GMI_CPU1_G2_CPU0_G0_TX_DN<14>                                     
P  NNAMEm8866 GMI_CPU1_G2_CPU0_G0_TX_DN<13>                                     
P  NNAMEm8867 GMI_CPU1_G2_CPU0_G0_TX_DN<12>                                     
P  NNAMEm8868 GMI_CPU1_G2_CPU0_G0_TX_DN<11>                                     
P  NNAMEm8869 GMI_CPU1_G2_CPU0_G0_TX_DN<10>                                     
P  NNAMEm8870 GMI_CPU1_G2_CPU0_G0_TX_DN<0>                                      
P  NNAMEm8871 GMI_CPU1_G0_CPU0_G2_TX_DP<9>                                      
P  NNAMEm8872 GMI_CPU1_G0_CPU0_G2_TX_DP<8>                                      
P  NNAMEm8873 GMI_CPU1_G0_CPU0_G2_TX_DP<7>                                      
P  NNAMEm8874 GMI_CPU1_G0_CPU0_G2_TX_DP<6>                                      
P  NNAMEm8875 GMI_CPU1_G0_CPU0_G2_TX_DP<5>                                      
P  NNAMEm8876 GMI_CPU1_G0_CPU0_G2_TX_DP<4>                                      
P  NNAMEm8877 GMI_CPU1_G0_CPU0_G2_TX_DP<3>                                      
P  NNAMEm8878 GMI_CPU1_G0_CPU0_G2_TX_DP<2>                                      
P  NNAMEm8879 GMI_CPU1_G0_CPU0_G2_TX_DP<1>                                      
P  NNAMEm8880 GMI_CPU1_G0_CPU0_G2_TX_DP<15>                                     
P  NNAMEm8881 GMI_CPU1_G0_CPU0_G2_TX_DP<14>                                     
P  NNAMEm8882 GMI_CPU1_G0_CPU0_G2_TX_DP<13>                                     
P  NNAMEm8883 GMI_CPU1_G0_CPU0_G2_TX_DP<12>                                     
P  NNAMEm8884 GMI_CPU1_G0_CPU0_G2_TX_DP<11>                                     
P  NNAMEm8885 GMI_CPU1_G0_CPU0_G2_TX_DP<10>                                     
P  NNAMEm8886 GMI_CPU1_G0_CPU0_G2_TX_DP<0>                                      
P  NNAMEm8887 GMI_CPU1_G0_CPU0_G2_TX_DN<9>                                      
P  NNAMEm8888 GMI_CPU1_G0_CPU0_G2_TX_DN<8>                                      
P  NNAMEm8889 GMI_CPU1_G0_CPU0_G2_TX_DN<7>                                      
P  NNAMEm8890 GMI_CPU1_G0_CPU0_G2_TX_DN<6>                                      
P  NNAMEm8891 GMI_CPU1_G0_CPU0_G2_TX_DN<5>                                      
P  NNAMEm8892 GMI_CPU1_G0_CPU0_G2_TX_DN<4>                                      
P  NNAMEm8893 GMI_CPU1_G0_CPU0_G2_TX_DN<3>                                      
P  NNAMEm8894 GMI_CPU1_G0_CPU0_G2_TX_DN<2>                                      
P  NNAMEm8895 GMI_CPU1_G0_CPU0_G2_TX_DN<1>                                      
P  NNAMEm8896 GMI_CPU1_G0_CPU0_G2_TX_DN<15>                                     
P  NNAMEm8897 GMI_CPU1_G0_CPU0_G2_TX_DN<14>                                     
P  NNAMEm8898 GMI_CPU1_G0_CPU0_G2_TX_DN<13>                                     
P  NNAMEm8899 GMI_CPU1_G0_CPU0_G2_TX_DN<12>                                     
P  NNAMEm8900 GMI_CPU1_G0_CPU0_G2_TX_DN<11>                                     
P  NNAMEm8901 GMI_CPU1_G0_CPU0_G2_TX_DN<10>                                     
P  NNAMEm8902 GMI_CPU1_G0_CPU0_G2_TX_DN<0>                                      
P  NNAMEm8903 P5E_CPU1_G1_RX_DP<6>                                              
P  NNAMEm8904 P5E_CPU1_G1_RX_DP<7>                                              
P  NNAMEm8905 P5E_CPU1_G1_RX_DP<8>                                              
P  NNAMEm8906 P5E_CPU1_G1_RX_DP<9>                                              
P  NNAMEm8907 P5E_CPU1_G1_RX_DP<10>                                             
P  NNAMEm8908 P5E_CPU1_G1_RX_DP<11>                                             
P  NNAMEm8909 P5E_CPU1_G1_RX_DP<12>                                             
P  NNAMEm8910 P5E_CPU1_G1_RX_DP<13>                                             
P  NNAMEm8911 P5E_CPU1_G1_RX_DP<14>                                             
P  NNAMEm8912 P5E_CPU1_G1_RX_DP<0>                                              
P  NNAMEm8913 P5E_CPU1_G1_RX_DP<1>                                              
P  NNAMEm8914 P5E_CPU1_G1_RX_DP<2>                                              
P  NNAMEm8915 P5E_CPU1_G1_RX_DP<3>                                              
P  NNAMEm8916 P5E_CPU1_G1_RX_DP<4>                                              
P  NNAMEm8917 P5E_CPU1_G1_RX_DP<5>                                              
P  NNAMEm8918 P5E_CPU1_G1_RX_DP<15>                                             
P  NNAMEm8919 P5E_CPU1_G1_RX_DN<6>                                              
P  NNAMEm8920 P5E_CPU1_G1_RX_DN<7>                                              
P  NNAMEm8921 P5E_CPU1_G1_RX_DN<8>                                              
P  NNAMEm8922 P5E_CPU1_G1_RX_DN<9>                                              
P  NNAMEm8923 P5E_CPU1_G1_RX_DN<10>                                             
P  NNAMEm8924 P5E_CPU1_G1_RX_DN<11>                                             
P  NNAMEm8925 P5E_CPU1_G1_RX_DN<12>                                             
P  NNAMEm8926 P5E_CPU1_G1_RX_DN<13>                                             
P  NNAMEm8927 P5E_CPU1_G1_RX_DN<14>                                             
P  NNAMEm8928 P5E_CPU1_G1_RX_DN<0>                                              
P  NNAMEm8929 P5E_CPU1_G1_RX_DN<1>                                              
P  NNAMEm8930 P5E_CPU1_G1_RX_DN<2>                                              
P  NNAMEm8931 P5E_CPU1_G1_RX_DN<3>                                              
P  NNAMEm8932 P5E_CPU1_G1_RX_DN<4>                                              
P  NNAMEm8933 P5E_CPU1_G1_RX_DN<5>                                              
P  NNAMEm8934 P5E_CPU1_G1_RX_DN<15>                                             
P  NNAMEm8935 GMI_CPU0_G2_CPU1_G0_TX_DP<9>                                      
P  NNAMEm8936 GMI_CPU0_G2_CPU1_G0_TX_DP<8>                                      
P  NNAMEm8937 GMI_CPU0_G2_CPU1_G0_TX_DP<7>                                      
P  NNAMEm8938 GMI_CPU0_G2_CPU1_G0_TX_DP<6>                                      
P  NNAMEm8939 GMI_CPU0_G2_CPU1_G0_TX_DP<5>                                      
P  NNAMEm8940 GMI_CPU0_G2_CPU1_G0_TX_DP<4>                                      
P  NNAMEm8941 GMI_CPU0_G2_CPU1_G0_TX_DP<3>                                      
P  NNAMEm8942 GMI_CPU0_G2_CPU1_G0_TX_DP<2>                                      
P  NNAMEm8943 GMI_CPU0_G2_CPU1_G0_TX_DP<1>                                      
P  NNAMEm8944 GMI_CPU0_G2_CPU1_G0_TX_DP<15>                                     
P  NNAMEm8945 GMI_CPU0_G2_CPU1_G0_TX_DP<14>                                     
P  NNAMEm8946 GMI_CPU0_G2_CPU1_G0_TX_DP<13>                                     
P  NNAMEm8947 GMI_CPU0_G2_CPU1_G0_TX_DP<12>                                     
P  NNAMEm8948 GMI_CPU0_G2_CPU1_G0_TX_DP<11>                                     
P  NNAMEm8949 GMI_CPU0_G2_CPU1_G0_TX_DP<10>                                     
P  NNAMEm8950 GMI_CPU0_G2_CPU1_G0_TX_DP<0>                                      
P  NNAMEm8951 GMI_CPU0_G2_CPU1_G0_TX_DN<9>                                      
P  NNAMEm8952 GMI_CPU0_G2_CPU1_G0_TX_DN<8>                                      
P  NNAMEm8953 GMI_CPU0_G2_CPU1_G0_TX_DN<7>                                      
P  NNAMEm8954 GMI_CPU0_G2_CPU1_G0_TX_DN<6>                                      
P  NNAMEm8955 GMI_CPU0_G2_CPU1_G0_TX_DN<5>                                      
P  NNAMEm8956 GMI_CPU0_G2_CPU1_G0_TX_DN<4>                                      
P  NNAMEm8957 GMI_CPU0_G2_CPU1_G0_TX_DN<3>                                      
P  NNAMEm8958 GMI_CPU0_G2_CPU1_G0_TX_DN<2>                                      
P  NNAMEm8959 GMI_CPU0_G2_CPU1_G0_TX_DN<1>                                      
P  NNAMEm8960 GMI_CPU0_G2_CPU1_G0_TX_DN<15>                                     
P  NNAMEm8961 GMI_CPU0_G2_CPU1_G0_TX_DN<14>                                     
P  NNAMEm8962 GMI_CPU0_G2_CPU1_G0_TX_DN<13>                                     
P  NNAMEm8963 GMI_CPU0_G2_CPU1_G0_TX_DN<12>                                     
P  NNAMEm8964 GMI_CPU0_G2_CPU1_G0_TX_DN<11>                                     
P  NNAMEm8965 GMI_CPU0_G2_CPU1_G0_TX_DN<10>                                     
P  NNAMEm8966 GMI_CPU0_G2_CPU1_G0_TX_DN<0>                                      
P  NNAMEm8967 GMI_CPU0_G1_CPU1_G3_TX_DP<9>                                      
P  NNAMEm8968 GMI_CPU0_G1_CPU1_G3_TX_DP<8>                                      
P  NNAMEm8969 GMI_CPU0_G1_CPU1_G3_TX_DP<7>                                      
P  NNAMEm8970 GMI_CPU0_G1_CPU1_G3_TX_DP<6>                                      
P  NNAMEm8971 GMI_CPU0_G1_CPU1_G3_TX_DP<5>                                      
P  NNAMEm8972 GMI_CPU0_G1_CPU1_G3_TX_DP<4>                                      
P  NNAMEm8973 GMI_CPU0_G1_CPU1_G3_TX_DP<3>                                      
P  NNAMEm8974 GMI_CPU0_G1_CPU1_G3_TX_DP<2>                                      
P  NNAMEm8975 GMI_CPU0_G1_CPU1_G3_TX_DP<1>                                      
P  NNAMEm8976 GMI_CPU0_G1_CPU1_G3_TX_DP<15>                                     
P  NNAMEm8977 GMI_CPU0_G1_CPU1_G3_TX_DP<14>                                     
P  NNAMEm8978 GMI_CPU0_G1_CPU1_G3_TX_DP<13>                                     
P  NNAMEm8979 GMI_CPU0_G1_CPU1_G3_TX_DP<12>                                     
P  NNAMEm8980 GMI_CPU0_G1_CPU1_G3_TX_DP<11>                                     
P  NNAMEm8981 GMI_CPU0_G1_CPU1_G3_TX_DP<10>                                     
P  NNAMEm8982 GMI_CPU0_G1_CPU1_G3_TX_DP<0>                                      
P  NNAMEm8983 GMI_CPU0_G1_CPU1_G3_TX_DN<9>                                      
P  NNAMEm8984 GMI_CPU0_G1_CPU1_G3_TX_DN<8>                                      
P  NNAMEm8985 GMI_CPU0_G1_CPU1_G3_TX_DN<7>                                      
P  NNAMEm8986 GMI_CPU0_G1_CPU1_G3_TX_DN<6>                                      
P  NNAMEm8987 GMI_CPU0_G1_CPU1_G3_TX_DN<5>                                      
P  NNAMEm8988 GMI_CPU0_G1_CPU1_G3_TX_DN<4>                                      
P  NNAMEm8989 GMI_CPU0_G1_CPU1_G3_TX_DN<3>                                      
P  NNAMEm8990 GMI_CPU0_G1_CPU1_G3_TX_DN<2>                                      
P  NNAMEm8991 GMI_CPU0_G1_CPU1_G3_TX_DN<1>                                      
P  NNAMEm8992 GMI_CPU0_G1_CPU1_G3_TX_DN<15>                                     
P  NNAMEm8993 GMI_CPU0_G1_CPU1_G3_TX_DN<14>                                     
P  NNAMEm8994 GMI_CPU0_G1_CPU1_G3_TX_DN<13>                                     
P  NNAMEm8995 GMI_CPU0_G1_CPU1_G3_TX_DN<12>                                     
P  NNAMEm8996 GMI_CPU0_G1_CPU1_G3_TX_DN<11>                                     
P  NNAMEm8997 GMI_CPU0_G1_CPU1_G3_TX_DN<10>                                     
P  NNAMEm8998 GMI_CPU0_G1_CPU1_G3_TX_DN<0>                                      
P  NNAMEm8999 GMI_CPU0_G0_CPU1_G2_TX_DP<9>                                      
P  NNAMEm9000 GMI_CPU0_G0_CPU1_G2_TX_DP<8>                                      
P  NNAMEm9001 GMI_CPU0_G0_CPU1_G2_TX_DP<7>                                      
P  NNAMEm9002 GMI_CPU0_G0_CPU1_G2_TX_DP<6>                                      
P  NNAMEm9003 GMI_CPU0_G0_CPU1_G2_TX_DP<5>                                      
P  NNAMEm9004 GMI_CPU0_G0_CPU1_G2_TX_DP<4>                                      
P  NNAMEm9005 GMI_CPU0_G0_CPU1_G2_TX_DP<3>                                      
P  NNAMEm9006 GMI_CPU0_G0_CPU1_G2_TX_DP<2>                                      
P  NNAMEm9007 GMI_CPU0_G0_CPU1_G2_TX_DP<1>                                      
P  NNAMEm9008 GMI_CPU0_G0_CPU1_G2_TX_DP<15>                                     
P  NNAMEm9009 GMI_CPU0_G0_CPU1_G2_TX_DP<14>                                     
P  NNAMEm9010 GMI_CPU0_G0_CPU1_G2_TX_DP<13>                                     
P  NNAMEm9011 GMI_CPU0_G0_CPU1_G2_TX_DP<12>                                     
P  NNAMEm9012 GMI_CPU0_G0_CPU1_G2_TX_DP<11>                                     
P  NNAMEm9013 GMI_CPU0_G0_CPU1_G2_TX_DP<10>                                     
P  NNAMEm9014 GMI_CPU0_G0_CPU1_G2_TX_DP<0>                                      
P  NNAMEm9015 GMI_CPU0_G0_CPU1_G2_TX_DN<9>                                      
P  NNAMEm9016 GMI_CPU0_G0_CPU1_G2_TX_DN<8>                                      
P  NNAMEm9017 GMI_CPU0_G0_CPU1_G2_TX_DN<7>                                      
P  NNAMEm9018 GMI_CPU0_G0_CPU1_G2_TX_DN<6>                                      
P  NNAMEm9019 GMI_CPU0_G0_CPU1_G2_TX_DN<5>                                      
P  NNAMEm9020 GMI_CPU0_G0_CPU1_G2_TX_DN<4>                                      
P  NNAMEm9021 GMI_CPU0_G0_CPU1_G2_TX_DN<3>                                      
P  NNAMEm9022 GMI_CPU0_G0_CPU1_G2_TX_DN<2>                                      
P  NNAMEm9023 GMI_CPU0_G0_CPU1_G2_TX_DN<1>                                      
P  NNAMEm9024 GMI_CPU0_G0_CPU1_G2_TX_DN<15>                                     
P  NNAMEm9025 GMI_CPU0_G0_CPU1_G2_TX_DN<14>                                     
P  NNAMEm9026 GMI_CPU0_G0_CPU1_G2_TX_DN<13>                                     
P  NNAMEm9027 GMI_CPU0_G0_CPU1_G2_TX_DN<12>                                     
P  NNAMEm9028 GMI_CPU0_G0_CPU1_G2_TX_DN<11>                                     
P  NNAMEm9029 GMI_CPU0_G0_CPU1_G2_TX_DN<10>                                     
P  NNAMEm9030 GMI_CPU0_G0_CPU1_G2_TX_DN<0>                                      
P  NNAMEm9031 FM_UV_ADR_TRIGGER_N                                               
P  NNAMEm9032 FM_UARTSW_MSB_R                                                   
P  NNAMEm9033 FM_UARTSW_MSB_N                                                   
P  NNAMEm9034 FM_UARTSW_LSB_R                                                   
P  NNAMEm9035 FM_UARTSW_LSB_N                                                   
P  NNAMEm9036 FM_SYS_THROTTLE_R_N                                               
P  NNAMEm9037 FM_SYS_THROTTLE_N                                                 
P  NNAMEm9038 FM_SWB_PWR_EN_R_BUF                                               
P  NNAMEm9039 FM_SWB_PWR_EN_R1_BUF                                              
P  NNAMEm9040 FM_SWB_PWR_EN_R                                                   
P  NNAMEm9041 FM_SWB_PWRGD_ISO                                                  
P  NNAMEm9042 FM_SWB_BIC_READY_N                                                
P  NNAMEm9043 FM_SWB_BIC_READY_ISO_N                                            
P  NNAMEm9044 FM_SWB_BIC_READY                                                  
P  NNAMEm9045 FM_SPD_CPU0_SWITCH_CTRL_R_N                                       
P  NNAMEm9046 FM_SPD_CPU0_SWITCH_CTRL_N                                         
P  NNAMEm9047 FM_SOL_UART_CH_SEL_R                                              
P  NNAMEm9048 FM_SOL_UART_CH_SEL                                                
P  NNAMEm9049 FM_SMERR_LED_R_N                                                  
P  NNAMEm9050 FM_SMERR_BUF_R_LED_N                                              
P  NNAMEm9051 FM_SMERR_BUF_LED_N                                                
P  NNAMEm9052 FM_SMB_RST_E1S_0_N                                                
P  NNAMEm9053 FM_SMB_2_ALERT_GPU_N                                              
P  NNAMEm9054 FM_SMB_2_ALERT_GPU_ISO_N                                          
P  NNAMEm9055 FM_SMB_2_ALERT_GPU                                                
P  NNAMEm9056 FM_SMB_1_ALERT_GPU_N                                              
P  NNAMEm9057 FM_SMB_1_ALERT_GPU_ISO_N                                          
P  NNAMEm9058 FM_SMB_1_ALERT_GPU                                                
P  NNAMEm9059 FM_SCM_PRSNT1_R_N                                                 
P  NNAMEm9060 FM_SCM_PRSNT1_N                                                   
P  NNAMEm9061 FM_RST_PERST_SCM_R_N                                              
P  NNAMEm9062 FM_RST_PERST_SCM_N                                                
P  NNAMEm9063 FM_RST_CPU1_RESETL_N                                              
P  NNAMEm9064 FM_RST_CPU0_RESETL_N                                              
P  NNAMEm9065 FM_ROM_SD_LS_OE                                                   
P  NNAMEm9066 FM_PWRGD_PVDDIO_P1                                                
P  NNAMEm9067 FM_PWRGD_PVDDIO_P0                                                
P  NNAMEm9068 FM_PWRGD_PVDDCR_CPU1_P1                                           
P  NNAMEm9069 FM_PWRGD_PVDDCR_CPU1_P0                                           
P  NNAMEm9070 FM_PWRGD_PVDDCR_CPU0_P1                                           
P  NNAMEm9071 FM_PWRGD_PVDD33_S5                                                
P  NNAMEm9072 FM_PWRGD_PVDD18_S5_P0                                             
P  NNAMEm9073 FM_PWRGD_PVDD11_S3_P1                                             
P  NNAMEm9074 FM_PWRGD_PVDD11_S3_P0                                             
P  NNAMEm9075 FM_PWRGD_CPU1_PWROK                                               
P  NNAMEm9076 FM_PWRGD_CPU0_PWROK                                               
P  NNAMEm9077 FM_PVDDIO_P1_EN                                                   
P  NNAMEm9078 FM_PVDDIO_P0_EN                                                   
P  NNAMEm9079 FM_PVDDCR_CPU1_P1_R_EN                                            
P  NNAMEm9080 FM_PVDDCR_CPU1_P1_OCP_N                                           
P  NNAMEm9081 FM_PVDDCR_CPU1_P1_EN                                              
P  NNAMEm9082 FM_PVDDCR_CPU1_P0_R_EN                                            
P  NNAMEm9083 FM_PVDDCR_CPU1_P0_OCP_N                                           
P  NNAMEm9084 FM_PVDDCR_CPU1_P0_EN                                              
P  NNAMEm9085 FM_PVDDCR_CPU0_P1_R_EN                                            
P  NNAMEm9086 FM_PVDDCR_CPU0_P1_OCP_N                                           
P  NNAMEm9087 FM_PVDDCR_CPU0_P0_OCP_N                                           
P  NNAMEm9088 FM_PVDD33_S5_EN                                                   
P  NNAMEm9089 FM_PVDD18_S5_P0_EN                                                
P  NNAMEm9090 FM_PVDD11_S3_P1_OCP_N                                             
P  NNAMEm9091 FM_PVDD11_S3_P1_EN                                                
P  NNAMEm9092 FM_PVDD11_S3_P0_OCP_N                                             
P  NNAMEm9093 FM_PVDD11_S3_P0_EN                                                
P  NNAMEm9094 FM_PRSNT_CPU1_R_N                                                 
P  NNAMEm9095 FM_PRSNT_CPU1_N                                                   
P  NNAMEm9096 FM_PRSNT_CPU0_R_N                                                 
P  NNAMEm9097 FM_PRSNT_CPU0_N                                                   
P  NNAMEm9098 FM_PLD_OCP_SFF_PWR_GOOD_R                                         
P  NNAMEm9099 FM_PLD_OCP_SFF_MAIN_PWR_EN_R                                      
P  NNAMEm9100 FM_PLD_OCP_SFF_AUX_PWR_R_EN                                       
P  NNAMEm9101 FM_PLD_CPU1_PRSNT_HDT_N                                           
P  NNAMEm9102 FM_PLD_CPU1_PRSNT_HDT                                             
P  NNAMEm9103 FM_PLD_CPU0_PRSNT_HDT_N                                           
P  NNAMEm9104 FM_PLD_CPU0_PRSNT_HDT                                             
P  NNAMEm9105 FM_PASSWORD_CLEAR_R_N                                             
P  NNAMEm9106 FM_PASSWORD_CLEAR_N                                               
P  NNAMEm9107 FM_OCP_V3_2_PWR_GOOD                                              
P  NNAMEm9108 FM_OCP_SFF_PWR_GOOD                                               
P  NNAMEm9109 FM_NCSI_OCP_V3_2_R_OE                                             
P  NNAMEm9110 FM_NCSI_OCP_SFF_R_OE                                              
P  NNAMEm9111 FM_M2_SSD_0_PEDET                                                 
P  NNAMEm9112 FM_LPC_ESPI_SEL                                                   
P  NNAMEm9113 FM_INT_CPU0_HP_UBM_R_N                                            
P  NNAMEm9114 FM_INT_CPU0_HP_UBM_N                                              
P  NNAMEm9115 FM_I3C_CPU1_MUX1_SEL                                              
P  NNAMEm9116 FM_I3C_CPU1_MUX1_R_SEL                                            
P  NNAMEm9117 FM_I3C_CPU1_MUX1_OE_R_N                                           
P  NNAMEm9118 FM_I3C_CPU1_MUX1_OE_N                                             
P  NNAMEm9119 FM_I3C_CPU1_MUX0_SEL                                              
P  NNAMEm9120 FM_I3C_CPU1_MUX0_R_SEL                                            
P  NNAMEm9121 FM_I3C_CPU1_MUX0_OE_R_N                                           
P  NNAMEm9122 FM_I3C_CPU1_MUX0_OE_N                                             
P  NNAMEm9123 FM_I3C_CPU0_MUX1_SEL                                              
P  NNAMEm9124 FM_I3C_CPU0_MUX1_R_SEL                                            
P  NNAMEm9125 FM_I3C_CPU0_MUX1_OE_R_N                                           
P  NNAMEm9126 FM_I3C_CPU0_MUX1_OE_N                                             
P  NNAMEm9127 FM_I3C_CPU0_MUX0_SEL                                              
P  NNAMEm9128 FM_I3C_CPU0_MUX0_R_SEL                                            
P  NNAMEm9129 FM_I3C_CPU0_MUX0_OE_R_N                                           
P  NNAMEm9130 FM_I3C_CPU0_MUX0_OE_N                                             
P  NNAMEm9131 FM_HDT_HDR_RESET_N                                                
P  NNAMEm9132 FM_HDT_HDR_PWROK                                                  
P  NNAMEm9133 FM_GPU_PWR_EN_R_BUF                                               
P  NNAMEm9134 FM_GPU_PWR_EN_R1                                                  
P  NNAMEm9135 FM_GPU_PWR_EN_R                                                   
P  NNAMEm9136 FM_GPU_PWRGD_ISO                                                  
P  NNAMEm9137 FM_FORCE_ALL_PWRON_R                                              
P  NNAMEm9138 FM_FORCE_ALL_PWRON                                                
P  NNAMEm9139 FM_CPU1_XTRIG_L7                                                  
P  NNAMEm9140 FM_CPU1_XTRIG_L6                                                  
P  NNAMEm9141 FM_CPU1_XTRIG_L5                                                  
P  NNAMEm9142 FM_CPU1_XTRIG_L4                                                  
P  NNAMEm9143 FM_CPU1_SYS_RESET_N                                               
P  NNAMEm9144 FM_CPU1_SMERR_N                                                   
P  NNAMEm9145 FM_CPU1_SLP_S5_N                                                  
P  NNAMEm9146 FM_CPU1_SLP_S3_N                                                  
P  NNAMEm9147 FM_CPU1_RSMRST_N                                                  
P  NNAMEm9148 FM_CPU1_PWR_GD_IN                                                 
P  NNAMEm9149 FM_CPU1_PWRGD_OUT                                                 
P  NNAMEm9150 FM_CPU1_PROCHOT_R_N                                               
P  NNAMEm9151 FM_CPU1_NV_SAVE_N                                                 
P  NNAMEm9152 FM_CPU1_NMI_SYNC_FLOOD_N                                          
P  NNAMEm9153 FM_CPU1_BMC_RST_R_N                                               
P  NNAMEm9154 FM_BMC_TPM_PRES_N_R                                               
P  NNAMEm9155 IRQ_CPU_BMC_NMI_R_N                                               
P  NNAMEm9156 FM_CPU1_FORCE_SELFREFRESH                                         
P  NNAMEm9157 FM_CPU1_CORETYPE2                                                 
P  NNAMEm9158 FM_CPU1_CORETYPE1                                                 
P  NNAMEm9159 FM_CPU1_CORETYPE0                                                 
P  NNAMEm9160 FM_CPU0_XTRIG_L7                                                  
P  NNAMEm9161 FM_CPU0_XTRIG_L6                                                  
P  NNAMEm9162 FM_CPU0_XTRIG_L5                                                  
P  NNAMEm9163 FM_CPU0_XTRIG_L4                                                  
P  NNAMEm9164 FM_CPU0_SYS_RESET_N                                               
P  NNAMEm9165 FM_CPU0_SMERR_N                                                   
P  NNAMEm9166 FM_CPU0_SLP_S5_N                                                  
P  NNAMEm9167 FM_CPU0_SLP_S3_N                                                  
P  NNAMEm9168 FM_CPU0_RSMRST_N                                                  
P  NNAMEm9169 FM_CPU0_PWR_GOOD                                                  
P  NNAMEm9170 FM_CPU0_PWR_BTN_N                                                 
P  NNAMEm9171 FM_CPU0_PROCHOT_R_N                                               
P  NNAMEm9172 FM_CPU0_NV_SAVE_N                                                 
P  NNAMEm9173 FM_CPU0_NMI_SYNC_FLOOD_N                                          
P  NNAMEm9174 FM_CPU0_HDT_CONN_TESTEN                                           
P  NNAMEm9175 IRQ_TPM_SPI_R1_N                                                  
P  NNAMEm9176 IRQ_SMI_ACTIVE_N_R                                                
P  NNAMEm9177 IRQ_BMC_SMI_R_N                                                   
P  NNAMEm9178 FM_SMM_CRASHDUMP_R                                                
P  NNAMEm9179 FM_CPU0_FORCE_SELFREFRESH                                         
P  NNAMEm9180 FM_CPU0_CORETYPE2                                                 
P  NNAMEm9181 FM_CPU0_CORETYPE1                                                 
P  NNAMEm9182 FM_CPU0_CORETYPE0                                                 
P  NNAMEm9183 FM_FPGA_DEBUG_LED_CTRL                                            
P  NNAMEm9184 FM_CLKREQ_M2_1_N                                                  
P  NNAMEm9185 FM_PDB_BUF_EN_R1                                                  
P  NNAMEm9186 SCM_SYS_PWRBTN_R_N                                                
P  NNAMEm9187 FM_BIOS_USB_RECOVERY_R                                            
P  NNAMEm9188 FM_BIOS_USB_RECOVERY                                              
P  NNAMEm9189 FM_BIOS_POST_CMPLT_R_N                                            
P  NNAMEm9190 FM_BIOS_POST_CMPLT_N                                              
P  NNAMEm9191 FM_BIOS_POST_CMPLT_BUF_R_N                                        
P  NNAMEm9192 FM_BIOS_POST_CMPLT_BUF_N                                          
P  NNAMEm9193 FB_BMC_ISOLATE_R2                                                 
P  NNAMEm9194 FB_BMC_ISOLATE_R1                                                 
P  NNAMEm9195 FB_BMC_ISOLATE1                                                   
P  NNAMEm9196 ESPI_CPU0_R_CS1_N                                                 
P  NNAMEm9197 ESPI_CPU0_R_ALERT_N                                               
P  NNAMEm9198 ESPI_CPU0_R1_D3                                                   
P  NNAMEm9199 ESPI_CPU0_R1_D2                                                   
P  NNAMEm9200 ESPI_CPU0_R1_D1                                                   
P  NNAMEm9201 ESPI_CPU0_R1_D0                                                   
P  NNAMEm9202 ESPI_CPU0_CS1_R_N                                                 
P  NNAMEm9203 ESPI_CPU0_CS1_N                                                   
P  NNAMEm9204 ESPI_CPU0_ALERT_R_N                                               
P  NNAMEm9205 ESPI_CPU0_ALERT_N                                                 
P  NNAMEm9206 E1S_0_PERST1_CLKREQ_N                                             
P  NNAMEm9207 CPU1_XTRIG_R2_L7                                                  
P  NNAMEm9208 CPU1_XTRIG_R2_L6                                                  
P  NNAMEm9209 CPU1_XTRIG_R2_L5                                                  
P  NNAMEm9210 CPU1_XTRIG_R2_L4                                                  
P  NNAMEm9211 CPU1_XTRIG_R1_L7                                                  
P  NNAMEm9212 CPU1_XTRIG_R1_L6                                                  
P  NNAMEm9213 CPU1_XTRIG_R1_L5                                                  
P  NNAMEm9214 CPU1_XTRIG_R1_L4                                                  
P  NNAMEm9215 CPU1_VDDBT_RTC_G                                                  
P  NNAMEm9216 CPU1_THERMTRIP_R_N                                                
P  NNAMEm9217 CPU1_THERMTRIP_N                                                  
P  NNAMEm9218 CPU1_SPD_HOST_CTRL_R_N                                            
P  NNAMEm9219 CPU1_SPD_HOST_CTRL_R1_N                                           
P  NNAMEm9220 CPU1_SPD_HOST_CTRL_N                                              
P  NNAMEm9221 CPU1_NMI_SYNC_FLOOD_N                                             
P  NNAMEm9222 CPU1_JTAG_BUF_R_OE                                                
P  NNAMEm9223 CPU1_JTAG_BUF_OE                                                  
P  NNAMEm9224 CPU1_HDT_BYPASS_SEL                                               
P  NNAMEm9225 FM_CPU1_BMC_RST_N                                                 
P  NNAMEm9226 CPU1_FORCE_SELFREFRESH                                            
P  NNAMEm9227 CPU0_XTRIG_R2_L7                                                  
P  NNAMEm9228 CPU0_XTRIG_R2_L6                                                  
P  NNAMEm9229 CPU0_XTRIG_R2_L5                                                  
P  NNAMEm9230 CPU0_XTRIG_R2_L4                                                  
P  NNAMEm9231 CPU0_XTRIG_R1_L7                                                  
P  NNAMEm9232 CPU0_XTRIG_R1_L6                                                  
P  NNAMEm9233 CPU0_XTRIG_R1_L5                                                  
P  NNAMEm9234 CPU0_XTRIG_R1_L4                                                  
P  NNAMEm9235 CPU0_THERMTRIP_R_N                                                
P  NNAMEm9236 CPU0_THERMTRIP_N                                                  
P  NNAMEm9237 CPU0_SPD_HOST_CTRL_R1_N                                           
P  NNAMEm9238 CPU0_SPD_HOST_CTRL_N                                              
P  NNAMEm9239 CPU0_ROM_TYPE_SELECT                                              
P  NNAMEm9240 CPU0_PWR_GD_OUT                                                   
P  NNAMEm9241 CPU0_NMI_SYNC_FLOOD_N                                             
P  NNAMEm9242 CPU0_JTAG_BUF_R_OE                                                
P  NNAMEm9243 CPU0_JTAG_BUF_OE                                                  
P  NNAMEm9244 CPU0_HDT_CONN_TESTEN                                              
P  NNAMEm9245 CPU0_HDT_BYPASS_SEL                                               
P  NNAMEm9246 CPU0_FORCE_SELFREFRESH                                            
P  NNAMEm9247 CPU0_ESPI_CS0_N                                                   
P  NNAMEm9248 CPU0_ESPI0_ALERT_N                                                
P  NNAMEm9249 CLK_ESPI_CPU0_R_CLK1                                              
P  NNAMEm9250 CLK_ESPI_CPU0_R1_CLK1                                             
P  NNAMEm9251 CLK_ESPI_CPU0_CLK1                                                
P  NNAMEm9252 CLK_CPU1_RTCCLK                                                   
P  NNAMEm9253 CLK_CPU0_RTCCLK                                                   
P  NNAMEm9254 CLK_50M_RMII_BMC_OCP                                              
P  NNAMEm9255 CLK_50M_NCSI_OCP_V3_2_ISO_R                                       
P  NNAMEm9256 CLK_50M_NCSI_OCP_V3_2_ISO                                         
P  NNAMEm9257 CLK_50M_NCSI_OCP_V3_2                                             
P  NNAMEm9258 CLK_50M_NCSI_OCP_SFF_ISO_R                                        
P  NNAMEm9259 CLK_50M_NCSI_OCP_SFF_ISO                                          
P  NNAMEm9260 CLK_50M_NCSI_OCP_SFF                                              
P  NNAMEm9261 CLK_50M_NCSI_OCP_2                                                
P  NNAMEm9262 CLK_50M_NCSI_OCP_1                                                
P  NNAMEm9263 CLK_50M_BMC_MAC_R                                                 
P  NNAMEm9264 CLK_100M_REF_OUT_DP                                               
P  NNAMEm9265 CLK_100M_REF_OUT_DN                                               
P  NNAMEm9266 CLK_100M_REF_IN_DP                                                
P  NNAMEm9267 CLK_100M_REF_IN_DN                                                
P  NNAMEm9268 CLK_100M_GPU_FPGA_DP                                              
P  NNAMEm9269 CLK_100M_GPU_FPGA_DN                                              
P  NNAMEm9270 CLK_100M_CPU1_CLK11_R_DP                                          
P  NNAMEm9271 CLK_100M_CPU1_CLK11_R_DN                                          
P  NNAMEm9272 CLK_100M_CPU1_CLK11_DP                                            
P  NNAMEm9273 CLK_100M_CPU1_CLK11_DN                                            
P  NNAMEm9274 CLK_100M_CPU0_CLK11_R_DP                                          
P  NNAMEm9275 CLK_100M_CPU0_CLK11_R_DN                                          
P  NNAMEm9276 CLK_100M_CPU0_CLK11_DP                                            
P  NNAMEm9277 CLK_100M_CPU0_CLK11_DN                                            
P  NNAMEm9278 CLK_100M_BMC_RC_DP                                                
P  NNAMEm9279 CLK_100M_BMC_RC_DN                                                
P  NNAMEm9280 CLK_100M_CPU0_CLK01_DP                                            
P  NNAMEm9281 CLK_100M_CPU0_CLK01_DN                                            
P  NNAMEm9282 BOOT_RDY_BUF_R_LED                                                
P  NNAMEm9283 BOOT_RDY_BUF_LED                                                  
P  NNAMEm9284 BMC_MONITER_BUF_R                                                 
P  NNAMEm9285 BMC_MONITER_BUF                                                   
P  NNAMEm9286 BMC_FPGA_LED2_R_N                                                 
P  NNAMEm9287 BMC_FPGA_LED2_N                                                   
P  NNAMEm9288 BMC_FPGA_LED1_R_N                                                 
P  NNAMEm9289 BMC_FPGA_LED1_N                                                   
P  NNAMEm9290 BIOS_DEBUG_MODE_R                                                 
P  NNAMEm9291 BIOS_DEBUG_MODE                                                   
P  NNAMEm9292 BIC_MONITER_ISO                                                   
P  NNAMEm9293 A_P12V_STBY_FP_TRIGGER                                            
P  NNAMEm9294 A_P12V_STBY_FPH_GATE                                              
P  NNAMEm9295 A_P12V_STBY_ADR_TRIGGER                                           
P  NNAMEm9296 APML_CPU1_ALERT_R_N                                               
P  NNAMEm9297 APML_CPU1_ALERT_N                                                 
P  NNAMEm9298 APML_CPU0_ALERT_R_N                                               
P  NNAMEm9299 APML_CPU0_ALERT_N                                                 
C                                                                               
C  ****************************************                                     
C      SIGNAL PINS & VIAS ON THE BOARD                                          
C  ****************************************                                     
C                                                                               
317PDB_PRSNT_R_N    VIA   -    M      A01X+105329Y+165208X0200Y         S2      
017PDB_PRSNT_R_N    VIA   -    M      A18X+105329Y+165208X0260Y         S2      
017PDB_PRSNT_R_N          -    MD0100PA00X+105329Y+165208                       
327PDB_PRSNT_R_N    C1797 -1   M      A01X+106422Y+165684X0198Y0197R090 S1      
317PDB_PRSNT_R_N    JP4003-2    D0410PA00X+108097Y+165096X0610Y         S3      
327PDB_PRSNT_R_N    R3907 -1   M      A01X+106822Y+165684X0198Y0197R090 S1      
327PDB_PRSNT_R_N    R3923 -2   M      A01X+104554Y+165208X0198Y0197     S1      
327PDB_PRSNT_R_N    U290  -G   M      A01X+105835Y+165610X0320Y0360R180 S1      
327PDB_PRSNT_R_N    R1526 -2          A01X+105010Y+166231X0198Y0197R270 S1      
327PDB_PRSNT_R_N    C1115 -1   M      A01X+104439Y+165815X0400Y0500     S1      
327m0000            R1525 -2   M      A01X+025062Y+022437X0198Y0197     S1      
317m0000            VIA   -    MD0100PA00X+026636Y+020307X0200Y         S0      
327m0000            R1524 -2   M      A01X+026328Y+020766X0198Y0197     S1      
327m0000            R1173 -1          A01X+028895Y+024949X0198Y0197R270 S1      
317m0000            VIA   -    M      A01X+026992Y+021770X0200Y         S2      
017m0000            VIA   -    M      A18X+026992Y+021770X0260Y         S2      
017m0000                  -    MD0100PA00X+026992Y+021770                       
327m0000            R1178 -1          A01X+026992Y+021500X0198Y0197     S1      
327m0001            VIA   -    M      A01X+086537Y+039371X0300Y         S1      
327m0001            R9022 -1          A01X+084850Y+045492X0198Y0197R090 S1      
327m0001            R9034 -1   M      A01X+086208Y+039150X0198Y0197R180 S1      
317m0001            VIA   -    MD0100PA00X+086483Y+041156X0200Y         S0      
317m0001            VIA   -    MD0100PA00X+084850Y+045213X0200Y         S0      
327m0001            R1518 -2          A01X+087160Y+041872X0198Y0197     S1      
327m0001            R1519 -1          A01X+086719Y+038468X0198Y0197R090 S1      
327m0002            VIA   -    M      A01X+025609Y+020654X0300Y         S1      
327m0002            R1524 -1          A01X+026014Y+020766X0198Y0197     S1      
327m0002            U9051 -4          A01X+025016Y+020765X0220Y0320R270 S1      
327m0003            VIA   -    M      A01X+023378Y+020894X0300Y         S1      
327m0003            R1523 -2          A01X+022760Y+020682X0198Y0197     S1      
327m0003            U9051 -2          A01X+024071Y+021139X0220Y0320R270 S1      
327m0004            VIA   -    M      A01X+086439Y+041719X0300Y         S1      
327m0004            U9050 -4          A01X+086142Y+040993X0220Y0320R090 S1      
327m0004            R1518 -1          A01X+086844Y+041872X0198Y0197     S1      
327m0005            VIA   -    M      A01X+087119Y+039176X0300Y         S1      
327m0005            R1509 -2          A01X+087119Y+038784X0198Y0197R090 S1      
327m0005            U9050 -2          A01X+087086Y+040619X0220Y0320R090 S1      
327m0006            R954  -1          A01X+018941Y+039374X0198Y0197R270 S1      
327m0006            U60   -1          A01X+018939Y+040006X0240Y0320     S1      
317m0006            VIA   -           A01X+018929Y+039673X0200Y         S2      
017m0006            VIA   -           A18X+018929Y+039673X0260Y         S2      
017m0006                  -     D0100PA00X+018929Y+039673                       
327m0006            R896  -2          A01X+018389Y+039374X0198Y0197R090 S1      
327m0007            U60   -3          A01X+018683Y+040636X0240Y0320     S1      
327m0007            C1114 -1          A01X+018514Y+041371X0400Y0500R180 S1      
317m0007            VIA   -           A01X+018516Y+041922X0200Y    R090 S2      
017m0007            VIA   -           A18X+018516Y+041922X0260Y    R090 S2      
017m0007                  -     D0100PA00X+018516Y+041922                       
327m0007            Q7002 -S          A01X+018516Y+042356X0320Y0360     S1      
327m0008            Q7002 -D          A01X+018142Y+043144X0320Y0360     S1      
327m0008            R1475 -1          A01X+018156Y+043827X0198Y0197R180 S1      
317m0008            VIA   -           A01X+018155Y+044129X0200Y    R090 S2      
017m0008            VIA   -           A18X+018155Y+044129X0260Y    R090 S2      
017m0008                  -     D0100PA00X+018155Y+044129                       
327m0008            Q7003 -4          A01X+018155Y+044528X0280Y0460     S1      
327m0009            Q7002 -G          A01X+017768Y+042356X0320Y0360     S1      
317m0009            VIA   -           A01X+017768Y+041926X0200Y    R090 S2      
017m0009            VIA   -           A18X+017768Y+041926X0260Y    R090 S2      
017m0009                  -     D0100PA00X+017768Y+041926                       
327m0009            R1092 -1          A01X+017768Y+041660X0198Y0197R180 S1      
327m0009            R1052 -2          A01X+017768Y+041235X0198Y0197     S1      
317P3V3_AUX_DSC     VIA   -           A01X+017201Y+047490X0200Y         S2      
017P3V3_AUX_DSC     VIA   -           A18X+017201Y+047490X0260Y         S2      
017P3V3_AUX_DSC           -     D0100PA00X+017201Y+047490                       
327P3V3_AUX_DSC     R1481 -2          A01X+017407Y+048138X0850Y1150R270 S1      
327P3V3_AUX_DSC     Q7003 -5          A01X+017405Y+046073X1850Y1811     S1      
327m0010            R700  -2          A01X+016828Y+039504X0198Y0197R180 S1      
317m0010            VIA   -           A01X+016283Y+039693X0200Y         S2      
017m0010            VIA   -           A18X+016283Y+039693X0260Y         S2      
017m0010                  -     D0100PA00X+016283Y+039693                       
327m0010            U57   -1          A01X+016261Y+040060X0240Y0320     S1      
327m0010            R855  -1          A01X+016828Y+040056X0198Y0197     S1      
317m0011            VIA   -           A01X+015838Y+041976X0200Y         S2      
017m0011            VIA   -           A18X+015838Y+041976X0260Y         S2      
017m0011                  -     D0100PA00X+015838Y+041976                       
327m0011            Q7000 -S          A01X+015838Y+042410X0320Y0360     S1      
327m0011            C1113 -1          A01X+015836Y+041425X0400Y0500R180 S1      
327m0011            U57   -3          A01X+016005Y+040690X0240Y0320     S1      
317m0012            VIA   -           A01X+015477Y+044183X0200Y         S2      
017m0012            VIA   -           A18X+015477Y+044183X0260Y         S2      
017m0012                  -     D0100PA00X+015477Y+044183                       
327m0012            Q7001 -4          A01X+015477Y+044582X0280Y0460     S1      
327m0012            Q7000 -D          A01X+015464Y+043198X0320Y0360     S1      
327m0012            R1474 -1          A01X+015478Y+043881X0198Y0197R180 S1      
327m0013            R1049 -1          A01X+014461Y+042400X0198Y0197R090 S1      
327m0013            R1007 -2          A01X+014036Y+042400X0198Y0197R270 S1      
327m0013            Q7000 -G          A01X+015090Y+042410X0320Y0360     S1      
317m0013            VIA   -           A01X+014745Y+042386X0200Y         S2      
017m0013            VIA   -           A18X+014745Y+042386X0260Y         S2      
017m0013                  -     D0100PA00X+014745Y+042386                       
317P12V_AUX_DSC     VIA   -           A01X+014781Y+047571X0200Y         S2      
017P12V_AUX_DSC     VIA   -           A18X+014781Y+047571X0260Y         S2      
017P12V_AUX_DSC           -     D0100PA00X+014781Y+047571                       
327P12V_AUX_DSC     R1480 -2          A01X+014729Y+048192X0850Y1150R270 S1      
327P12V_AUX_DSC     Q7001 -5          A01X+014727Y+046127X1850Y1811     S1      
327m0014            J37   -5          A01X+081200Y+077022X0205Y0590R090 S1      
327m0014            R1711 -2          A18X+081032Y+077146X0198Y0197     S2      
317m0014            VIA   -    MD0100PA00X+080713Y+077096X0200Y    R180 S0      
327m0015            J67   -5          A01X+178814Y+077022X0205Y0590R090 S1      
327m0015            R1686 -2          A18X+178674Y+077136X0198Y0197R180 S2      
317m0015            VIA   -    MD0100PA00X+179269Y+077022X0190Y         S0      
327m0016            J99   -5          A01X+078230Y+077022X0205Y0590R090 S1      
327m0016            R1710 -2          A18X+078090Y+077110X0198Y0197R180 S2      
317m0016            VIA   -    MD0100PA00X+078685Y+077022X0190Y         S0      
327m0017            J20   -5          A01X+175844Y+077022X0205Y0590R090 S1      
327m0017            R1685 -2          A18X+175704Y+077110X0198Y0197R180 S2      
317m0017            VIA   -    MD0100PA00X+176299Y+077022X0190Y         S0      
327m0018            J29   -5          A01X+075260Y+077022X0205Y0590R090 S1      
327m0018            R1709 -2          A18X+075120Y+077110X0198Y0197R180 S2      
317m0018            VIA   -    MD0100PA00X+075715Y+077022X0190Y         S0      
327m0019            J68   -5          A01X+172874Y+077022X0205Y0590R090 S1      
327m0019            R1684 -2          A18X+172734Y+077110X0198Y0197R180 S2      
317m0019            VIA   -    MD0100PA00X+173329Y+077022X0190Y         S0      
327m0020            J100  -5          A01X+072290Y+077022X0205Y0590R090 S1      
327m0020            R1708 -2          A18X+072150Y+077110X0198Y0197R180 S2      
317m0020            VIA   -    MD0100PA00X+072745Y+077022X0190Y         S0      
327m0021            J18   -5          A01X+169904Y+077022X0205Y0590R090 S1      
327m0021            R1683 -2          A18X+169764Y+077106X0198Y0197R180 S2      
317m0021            VIA   -    MD0100PA00X+170359Y+077022X0190Y         S0      
327m0022            J27   -5          A01X+069320Y+077022X0205Y0590R090 S1      
327m0022            R1707 -2          A18X+069180Y+077110X0198Y0197R180 S2      
317m0022            VIA   -    MD0100PA00X+069775Y+077022X0190Y         S0      
327m0023            J69   -5          A01X+166934Y+077022X0205Y0590R090 S1      
327m0023            R1681 -2          A18X+166794Y+077106X0198Y0197R180 S2      
317m0023            VIA   -    MD0100PA00X+167389Y+077022X0190Y         S0      
327m0024            J102  -5          A01X+066350Y+077022X0205Y0590R090 S1      
327m0024            R1705 -2          A18X+066210Y+077110X0198Y0197R180 S2      
317m0024            VIA   -    MD0100PA00X+066805Y+077022X0190Y         S0      
327m0025            J16   -5          A01X+163964Y+077022X0205Y0590R090 S1      
327m0025            R1680 -2          A18X+163824Y+077106X0198Y0197R180 S2      
317m0025            VIA   -    MD0100PA00X+164419Y+077022X0190Y         S0      
327m0026            J33   -5          A01X+008546Y+077022X0205Y0590R090 S1      
327m0026            R1704 -2          A18X+008393Y+077137X0198Y0197R180 S2      
317m0026            VIA   -    MD0100PA00X+009002Y+077022X0190Y         S0      
327m0027            J23   -5          A01X+106161Y+077022X0205Y0590R090 S1      
327m0027            R1679 -2          A18X+106021Y+077110X0198Y0197R180 S2      
317m0027            VIA   -    MD0100PA00X+106616Y+077022X0190Y         S0      
327m0028            J32   -5          A01X+011517Y+077022X0205Y0590R090 S1      
327m0028            R1701 -2          A18X+011364Y+077137X0198Y0197R180 S2      
317m0028            VIA   -    MD0100PA00X+011972Y+077022X0190Y         S0      
327m0029            J21   -5          A01X+109131Y+077022X0205Y0590R090 S1      
327m0029            R1678 -2          A18X+108991Y+077110X0198Y0197R180 S2      
317m0029            VIA   -    MD0100PA00X+109586Y+077022X0190Y         S0      
327m0030            J30   -5          A01X+014487Y+077022X0205Y0590R090 S1      
327m0030            R1699 -2          A18X+014347Y+077120X0198Y0197R180 S2      
317m0030            VIA   -    MD0100PA00X+014942Y+077022X0190Y         S0      
327m0031            J19   -5          A01X+112101Y+077022X0205Y0590R090 S1      
327m0031            R1676 -2          A18X+111961Y+077110X0198Y0197R180 S2      
317m0031            VIA   -    MD0100PA00X+112556Y+077022X0190Y         S0      
327m0032            J28   -5          A01X+017457Y+077022X0205Y0590R090 S1      
327m0032            R1697 -2          A18X+017314Y+077127X0198Y0197R180 S2      
317m0032            VIA   -    MD0100PA00X+017912Y+077022X0190Y         S0      
327m0033            J17   -5          A01X+115071Y+077022X0205Y0590R090 S1      
327m0033            R1677 -2          A18X+114931Y+077110X0198Y0197R180 S2      
317m0033            VIA   -    MD0100PA00X+115526Y+077022X0190Y         S0      
327m0034            J26   -5          A01X+020427Y+077022X0205Y0590R090 S1      
327m0034            R1696 -2          A18X+020284Y+077137X0198Y0197R180 S2      
317m0034            VIA   -    MD0100PA00X+020882Y+077022X0190Y         S0      
327m0035            J15   -5          A01X+118041Y+077022X0205Y0590R090 S1      
327m0035            R1675 -2          A18X+117901Y+077110X0198Y0197R180 S2      
317m0035            VIA   -    MD0100PA00X+118496Y+077022X0190Y         S0      
327m0036            J24   -5          A01X+023397Y+077022X0205Y0590R090 S1      
327m0036            R1687 -2          A18X+023544Y+077137X0198Y0197R180 S2      
317m0036            VIA   -    MD0100PA00X+023852Y+077022X0190Y         S0      
327m0037            J1    -5          A01X+121011Y+077022X0205Y0590R090 S1      
327m0037            R1674 -2          A18X+121158Y+077146X0198Y0197R180 S2      
317m0037            VIA   -    MD0100PA00X+121484Y+077228X0190Y         S0      
327m0038            R1515 -2          A18X+096865Y+130420X0120Y0150     S2      
317m0038            JP6500-2    D0410PA00X+107286Y+141918X0610Y         S3      
327m0039            R1514 -2          A18X+096865Y+130740X0120Y0150     S2      
317m0039            JP6500-1    D0410PA00X+107286Y+142918X0610Y0610     S3      
327m0040            R1517 -2          A18X+040758Y+163122X0198Y0197R180 S2      
317m0040            VIA   -    M      A01X+109677Y+163508X0200Y         S2      
017m0040            VIA   -    M      A18X+109677Y+163508X0260Y         S2      
017m0040                  -    MD0100PA00X+109677Y+163508                       
327m0040            R6863 -1          A01X+040443Y+163122X0198Y0197     S1      
317m0040            VIA   -    MD0100PA00X+040466Y+163414X0200Y         S0      
327m0040            R6783 -2          A01X+109441Y+163373X0198Y0197     S1      
327m0040            R6865 -1          A01X+109945Y+163440X0198Y0197     S1      
327m0041            R1516 -2          A18X+040258Y+162680X0198Y0197R180 S2      
317m0041            VIA   -    M      A01X+109700Y+162950X0200Y         S2      
017m0041            VIA   -    M      A18X+109700Y+162950X0260Y         S2      
017m0041                  -    MD0100PA00X+109700Y+162950                       
327m0041            R6862 -1          A01X+040297Y+162275X0198Y0197R090 S1      
327m0041            R6782 -2          A01X+109446Y+162994X0198Y0197     S1      
327m0041            R6864 -1          A01X+109964Y+163012X0198Y0197     S1      
317m0041            VIA   -    MD0100PA00X+040575Y+162335X0200Y         S0      
327m0042            R1434 -2          A01X+055828Y+153285X0120Y0150     S1      
327m0042            U6017 -E11        A01X+052730Y+153044X0120Y         S1      
327m0042            R1435 -1   M      A01X+054410Y+153154X0120Y0150R090 S1      
317m0043            VIA   -    MD0080PA00X+066088Y+153016X0160Y         S0      
327m0043            R1426 -2          A01X+070109Y+153625X0120Y0150R180 S1      
327m0043            R1427 -1          A01X+070915Y+153850X0120Y0150     S1      
317m0043            VIA   -    M      A01X+070915Y+153625X0200Y         S2      
017m0043            VIA   -    M      A18X+070915Y+153625X0260Y         S2      
017m0043                  -    MD0100PA00X+070915Y+153625                       
327m0043            U6016 -E11        A01X+065536Y+153044X0120Y         S1      
327m0044            R1378 -1   M      A01X+041140Y+153344X0120Y0150     S1      
327m0044            R1377 -2          A01X+041125Y+153800X0120Y0150R180 S1      
327m0044            U6015 -E11        A01X+039119Y+153044X0120Y         S1      
327m0044            VIA   -    M      A01X+040478Y+153598X0300Y         S1      
327m0045            R1388 -2          A01X+029411Y+153285X0120Y0150     S1      
327m0045            U6014 -E11        A01X+026313Y+153044X0120Y         S1      
327m0045            R1389 -1   M      A01X+027335Y+153527X0120Y0150     S1      
327m0046            R1413 -2          A01X+156615Y+156585X0120Y0150     S1      
327m0046            U6013 -E11        A01X+153518Y+156344X0120Y         S1      
327m0046            R1414 -1   M      A01X+154540Y+156827X0120Y0150     S1      
317m0047            VIA   -    MD0080PA00X+166875Y+156316X0160Y         S0      
327m0047            R1405 -2          A01X+170305Y+159810X0120Y0150R180 S1      
327m0047            U6012 -E11        A01X+166324Y+156344X0120Y         S1      
317m0047            VIA   -    M      A01X+170996Y+159749X0200Y         S2      
017m0047            VIA   -    M      A18X+170996Y+159749X0260Y         S2      
017m0047                  -    MD0100PA00X+170996Y+159749                       
327m0047            R1406 -1          A01X+171569Y+159974X0120Y0150     S1      
327m0048            VIA   -    M      A01X+141265Y+156898X0300Y         S1      
327m0048            U6011 -E11        A01X+139906Y+156344X0120Y         S1      
327m0048            R1397 -2          A01X+141912Y+157100X0120Y0150R180 S1      
327m0048            R1398 -1   M      A01X+141927Y+156644X0120Y0150     S1      
327m0049            R1370 -1   M      A01X+128122Y+156827X0120Y0150     S1      
327m0049            U6010 -E11        A01X+127100Y+156344X0120Y         S1      
327m0049            R1369 -2          A01X+130198Y+156585X0120Y0150     S1      
327m0050            C1094 -1          A18X+084115Y+128132X0198Y0197     S2      
327m0050            VIA   -           A18X+084612Y+128218X0260Y         S2      
327m0050            U51   -5          A18X+086460Y+128685X0140Y0630R270 S2      
327m0050            R1267 -1          A18X+085247Y+128744X0198Y0197     S2      
327m0050            C1095 -1          A18X+084128Y+128547X0198Y0197     S2      
327m0050            L25   -2          A18X+084156Y+127662X0280Y0320R270 S2      
327m0051            R1429 -1          A01X+053755Y+153471X0120Y0150     S1      
327m0051            U6017 -E8         A01X+052730Y+153280X0120Y         S1      
317m0052            VIA   -    MD0080PA00X+066235Y+153441X0160Y         S0      
327m0052            R1416 -1          A01X+070915Y+154510X0120Y0150     S1      
317m0052            VIA   -    M      A01X+070329Y+154510X0200Y         S2      
017m0052            VIA   -    M      A18X+070329Y+154510X0260Y         S2      
017m0052                  -    MD0100PA00X+070329Y+154510                       
327m0052            U6016 -E8         A01X+065536Y+153280X0120Y         S1      
327m0053            R1372 -1          A01X+040915Y+154420X0120Y0150     S1      
327m0053            U6015 -E8         A01X+039119Y+153280X0120Y         S1      
327m0053            VIA   -    M      A01X+040478Y+154098X0300Y         S1      
327m0054            R1380 -1          A01X+027335Y+153837X0120Y0150     S1      
327m0054            U6014 -E8         A01X+026313Y+153280X0120Y         S1      
327m0055            R1408 -1          A01X+154540Y+157137X0120Y0150     S1      
327m0055            U6013 -E8         A01X+153518Y+156580X0120Y         S1      
317m0056            VIA   -    MD0080PA00X+167023Y+156741X0160Y         S0      
327m0056            R1400 -1          A01X+171569Y+160634X0120Y0150     S1      
317m0056            VIA   -    M      A01X+170983Y+160634X0200Y         S2      
017m0056            VIA   -    M      A18X+170983Y+160634X0260Y         S2      
017m0056                  -    MD0100PA00X+170983Y+160634                       
327m0056            U6012 -E8         A01X+166324Y+156580X0120Y         S1      
327m0057            VIA   -    M      A01X+141265Y+157398X0300Y         S1      
327m0057            R1391 -1          A01X+141702Y+157720X0120Y0150     S1      
327m0057            U6011 -E8         A01X+139906Y+156580X0120Y         S1      
327m0058            R1364 -1          A01X+128122Y+157137X0120Y0150     S1      
327m0058            U6010 -E8         A01X+127100Y+156580X0120Y         S1      
317m0059            VIA   -    MD0080PA00X+053121Y+152870X0160Y         S0      
327m0059            VIA   -           A18X+064330Y+167769X0260Y         S2      
327m0059            U6017 -B12        A01X+052935Y+152926X0100Y0130R090 S1      
317m0059            VIA   -    MD0100PA00X+064330Y+167480X0200Y         S0      
327m0059            R1511 -2          A18X+064380Y+167270X0120Y0150R090 S2      
317m0060            VIA   -    MD0080PA00X+065927Y+152870X0160Y         S0      
327m0060            R1489 -2          A01X+070109Y+153170X0120Y0150R180 S1      
317m0060            VIA   -    M      A01X+070705Y+153170X0200Y         S2      
017m0060            VIA   -    M      A18X+070705Y+153170X0260Y         S2      
017m0060                  -    MD0100PA00X+070705Y+153170                       
327m0060            U6016 -B12        A01X+065741Y+152926X0100Y0130R090 S1      
317m0061            VIA   -    MD0080PA00X+039510Y+152870X0160Y         S0      
317m0061            VIA   -    M      A01X+037295Y+165320X0200Y         S2      
017m0061            VIA   -    M      A18X+037295Y+165320X0260Y         S2      
017m0061                  -    MD0100PA00X+037295Y+165320                       
327m0061            U6015 -B12        A01X+039324Y+152926X0100Y0130R090 S1      
327m0061            R1455 -2          A01X+037715Y+164900X0120Y0150     S1      
317m0062            VIA   -    MD0080PA00X+026704Y+152870X0160Y         S0      
317m0062            VIA   -    M      A01X+018414Y+165109X0200Y         S2      
017m0062            VIA   -    M      A18X+018414Y+165109X0260Y         S2      
017m0062                  -    MD0100PA00X+018414Y+165109                       
327m0062            U6014 -B12        A01X+026517Y+152926X0100Y0130R090 S1      
327m0062            R1465 -2          A01X+018189Y+164917X0120Y0150R180 S1      
317m0063            VIA   -    MD0080PA00X+153908Y+156170X0160Y         S0      
317m0063            VIA   -    M      A01X+168668Y+165929X0200Y         S2      
017m0063            VIA   -    M      A18X+168668Y+165929X0260Y         S2      
017m0063                  -    MD0100PA00X+168668Y+165929                       
327m0063            R1483 -2          A01X+168100Y+166105X0120Y0150R270 S1      
327m0063            U6013 -B12        A01X+153722Y+156226X0100Y0130R090 S1      
317m0064            VIA   -    MD0080PA00X+166714Y+156170X0160Y         S0      
327m0064            R1477 -2          A01X+170305Y+159500X0120Y0150R180 S1      
327m0064            U6012 -B12        A01X+166528Y+156226X0100Y0130R090 S1      
317m0064            VIA   -    M      A01X+171569Y+159719X0200Y         S2      
017m0064            VIA   -    M      A18X+171569Y+159719X0260Y         S2      
017m0064                  -    MD0100PA00X+171569Y+159719                       
317m0065            VIA   -    MD0080PA00X+140297Y+156170X0160Y         S0      
317m0065            VIA   -    M      A01X+141686Y+158287X0200Y         S2      
017m0065            VIA   -    M      A18X+141686Y+158287X0260Y         S2      
017m0065                  -    MD0100PA00X+141686Y+158287                       
327m0065            R1471 -2          A01X+138700Y+160685X0120Y0150R270 S1      
327m0065            U6011 -B12        A01X+140111Y+156226X0100Y0130R090 S1      
327m0066            U6010 -B12        A01X+127305Y+156226X0100Y0130R090 S1      
317m0066            VIA   -    MD0080PA00X+127491Y+156170X0160Y         S0      
327m0066            VIA   -           A18X+120782Y+167358X0260Y         S2      
317m0066            VIA   -    MD0100PA00X+120560Y+167580X0200Y         S0      
327m0066            R1439 -2          A18X+120350Y+167580X0120Y0150     S2      
317m0067            VIA   -    MD0080PA00X+053154Y+153162X0160Y         S0      
327m0067            VIA   -           A18X+063721Y+167680X0260Y         S2      
327m0067            U6017 -B9         A01X+052935Y+153162X0100Y0130R090 S1      
317m0067            VIA   -    MD0100PA00X+064060Y+167480X0200Y         S0      
327m0067            R1512 -2          A18X+064060Y+167270X0120Y0150R090 S2      
317m0068            VIA   -    MD0080PA00X+065936Y+153162X0160Y         S0      
327m0068            R1490 -2          A01X+070109Y+154180X0120Y0150R180 S1      
317m0068            VIA   -    M      A01X+070705Y+154180X0200Y         S2      
017m0068            VIA   -    M      A18X+070705Y+154180X0260Y         S2      
017m0068                  -    MD0100PA00X+070705Y+154180                       
327m0068            U6016 -B9         A01X+065741Y+153162X0100Y0130R090 S1      
317m0069            VIA   -    MD0080PA00X+039519Y+153162X0160Y         S0      
317m0069            VIA   -    M      A01X+037496Y+164851X0200Y         S2      
017m0069            VIA   -    M      A18X+037496Y+164851X0260Y         S2      
017m0069                  -    MD0100PA00X+037496Y+164851                       
327m0069            U6015 -B9         A01X+039324Y+153162X0100Y0130R090 S1      
327m0069            R1456 -2          A01X+037715Y+164580X0120Y0150     S1      
317m0070            VIA   -    MD0080PA00X+026712Y+153162X0160Y         S0      
327m0070            VIA   -           A18X+017593Y+165151X0260Y         S2      
327m0070            U6014 -B9         A01X+026517Y+153162X0100Y0130R090 S1      
327m0070            R1466 -2          A01X+018189Y+165237X0120Y0150R180 S1      
317m0070            VIA   -    MD0100PA00X+018392Y+165397X0200Y         S0      
317m0071            VIA   -    MD0080PA00X+153917Y+156462X0160Y         S0      
317m0071            VIA   -    M      A01X+168037Y+166337X0200Y         S2      
017m0071            VIA   -    M      A18X+168037Y+166337X0260Y         S2      
017m0071                  -    MD0100PA00X+168037Y+166337                       
327m0071            U6013 -B9         A01X+153722Y+156462X0100Y0130R090 S1      
327m0071            R1484 -2          A01X+167780Y+166105X0120Y0150R270 S1      
317m0072            VIA   -    MD0080PA00X+166723Y+156462X0160Y         S0      
327m0072            R1478 -2          A01X+170305Y+160120X0120Y0150R180 S1      
317m0072            VIA   -    M      A01X+171359Y+160304X0200Y         S2      
017m0072            VIA   -    M      A18X+171359Y+160304X0260Y         S2      
017m0072                  -    MD0100PA00X+171359Y+160304                       
327m0072            U6012 -B9         A01X+166528Y+156462X0100Y0130R090 S1      
317m0073            VIA   -    MD0080PA00X+140306Y+156462X0160Y         S0      
317m0073            VIA   -    M      A01X+141384Y+158694X0200Y         S2      
017m0073            VIA   -    M      A18X+141384Y+158694X0260Y         S2      
017m0073                  -    MD0100PA00X+141384Y+158694                       
327m0073            R1472 -2          A01X+139020Y+160685X0120Y0150R270 S1      
327m0073            U6011 -B9         A01X+140111Y+156462X0100Y0130R090 S1      
327m0074            U6010 -B9         A01X+127305Y+156462X0100Y0130R090 S1      
317m0074            VIA   -    MD0080PA00X+127500Y+156462X0160Y         S0      
327m0074            VIA   -           A18X+121255Y+167590X0260Y         S2      
317m0074            VIA   -    MD0100PA00X+120560Y+167900X0200Y         S0      
327m0074            R1445 -2          A18X+120350Y+167900X0120Y0150     S2      
317m0075            VIA   -    MD0100PA00X+064519Y+159505X0200Y         S0      
327m0075            VIA   -           A18X+065238Y+167698X0260Y         S2      
317m0075            VIA   -    MD0100PA00X+065020Y+167480X0200Y         S0      
327m0075            R1510 -2          A18X+065020Y+167270X0120Y0150R090 S2      
327m0075            U6017 -B6         A01X+052935Y+153398X0100Y0130R090 S1      
317m0075            VIA   -    MD0080PA00X+053193Y+153454X0160Y         S0      
317m0076            VIA   -    MD0080PA00X+065936Y+153454X0160Y         S0      
327m0076            R1488 -2          A01X+070109Y+154840X0120Y0150R180 S1      
317m0076            VIA   -    M      A01X+070705Y+154840X0200Y         S2      
017m0076            VIA   -    M      A18X+070705Y+154840X0260Y         S2      
017m0076                  -    MD0100PA00X+070705Y+154840                       
327m0076            U6016 -B6         A01X+065741Y+153398X0100Y0130R090 S1      
317m0077            VIA   -    MD0080PA00X+039518Y+153454X0160Y         S0      
317m0077            VIA   -    M      A01X+037182Y+164452X0200Y         S2      
017m0077            VIA   -    M      A18X+037182Y+164452X0260Y         S2      
017m0077                  -    MD0100PA00X+037182Y+164452                       
327m0077            U6015 -B6         A01X+039324Y+153398X0100Y0130R090 S1      
327m0077            R1454 -2          A01X+037715Y+164260X0120Y0150     S1      
317m0078            VIA   -    MD0080PA00X+026712Y+153454X0160Y         S0      
327m0078            VIA   -           A18X+018110Y+165680X0260Y         S2      
327m0078            U6014 -B6         A01X+026517Y+153398X0100Y0130R090 S1      
327m0078            R1464 -2          A01X+018189Y+165557X0120Y0150R180 S1      
317m0078            VIA   -    MD0100PA00X+018397Y+165680X0200Y         S0      
317m0079            VIA   -    MD0080PA00X+153917Y+156754X0160Y         S0      
317m0079            VIA   -    M      A01X+167529Y+166316X0200Y         S2      
017m0079            VIA   -    M      A18X+167529Y+166316X0260Y         S2      
017m0079                  -    MD0100PA00X+167529Y+166316                       
327m0079            U6013 -B6         A01X+153722Y+156698X0100Y0130R090 S1      
327m0079            R1482 -2          A01X+167460Y+166105X0120Y0150R270 S1      
317m0080            VIA   -    MD0080PA00X+166723Y+156754X0160Y         S0      
327m0080            R1476 -2          A01X+170305Y+160430X0120Y0150R180 S1      
317m0080            VIA   -    M      A01X+171359Y+160964X0200Y         S2      
017m0080            VIA   -    M      A18X+171359Y+160964X0260Y         S2      
017m0080                  -    MD0100PA00X+171359Y+160964                       
327m0080            U6012 -B6         A01X+166528Y+156698X0100Y0130R090 S1      
317m0081            VIA   -    MD0080PA00X+140306Y+156754X0160Y         S0      
317m0081            VIA   -    M      A01X+141671Y+159282X0200Y         S2      
017m0081            VIA   -    M      A18X+141671Y+159282X0260Y         S2      
017m0081                  -    MD0100PA00X+141671Y+159282                       
327m0081            R1470 -2          A01X+138380Y+160685X0120Y0150R270 S1      
327m0081            U6011 -B6         A01X+140111Y+156698X0100Y0130R090 S1      
327m0082            U6010 -B6         A01X+127305Y+156698X0100Y0130R090 S1      
317m0082            VIA   -    MD0080PA00X+127500Y+156754X0160Y         S0      
327m0082            VIA   -           A18X+121114Y+168085X0260Y         S2      
317m0082            VIA   -    MD0100PA00X+120560Y+168220X0200Y         S0      
327m0082            R1438 -2          A18X+120350Y+168220X0120Y0150     S2      
317m0083            VIA   -    MD0100PA00X+064518Y+159780X0200Y         S0      
317m0083            VIA   -    MD0080PA00X+053231Y+153664X0160Y         S0      
327m0083            VIA   -           A18X+065050Y+168198X0260Y         S2      
327m0083            U6017 -B3         A01X+052935Y+153634X0100Y0130R090 S1      
327m0083            R1430 -1   M      A18X+064750Y+167775X0120Y0150R270 S2      
317m0083            VIA   -    MD0100PA00X+064750Y+167480X0200Y         S0      
327m0083            R1513 -2          A18X+064700Y+167270X0120Y0150R090 S2      
317m0084            VIA   -    MD0080PA00X+065936Y+153664X0160Y         S0      
327m0084            R1499 -2          A01X+070109Y+155170X0120Y0150R180 S1      
327m0084            R1417 -1          A01X+070915Y+155170X0120Y0150     S1      
317m0084            VIA   -    M      A01X+070329Y+155170X0200Y         S2      
017m0084            VIA   -    M      A18X+070329Y+155170X0260Y         S2      
017m0084                  -    MD0100PA00X+070329Y+155170                       
327m0084            U6016 -B3         A01X+065741Y+153634X0100Y0130R090 S1      
317m0085            VIA   -    MD0080PA00X+039518Y+153664X0160Y         S0      
317m0085            VIA   -    M      A01X+037505Y+163940X0200Y         S2      
017m0085            VIA   -    M      A18X+037505Y+163940X0260Y         S2      
017m0085                  -    MD0100PA00X+037505Y+163940                       
327m0085            R1373 -1          A01X+037295Y+163940X0120Y0150R180 S1      
327m0085            U6015 -B3         A01X+039324Y+153634X0100Y0130R090 S1      
327m0085            R1461 -2          A01X+037715Y+163940X0120Y0150     S1      
317m0086            VIA   -    MD0080PA00X+026712Y+153664X0160Y         S0      
327m0086            VIA   -           A18X+017944Y+166158X0260Y         S2      
327m0086            U6014 -B3         A01X+026517Y+153634X0100Y0130R090 S1      
327m0086            R1381 -1          A01X+018639Y+165877X0120Y0150     S1      
327m0086            R1467 -2          A01X+018189Y+165877X0120Y0150R180 S1      
317m0086            VIA   -    MD0100PA00X+018399Y+165955X0200Y         S0      
317m0087            VIA   -    MD0080PA00X+153917Y+156964X0160Y         S0      
317m0087            VIA   -    M      A01X+167020Y+166315X0200Y         S2      
017m0087            VIA   -    M      A18X+167020Y+166315X0260Y         S2      
017m0087                  -    MD0100PA00X+167020Y+166315                       
327m0087            U6013 -B3         A01X+153722Y+156934X0100Y0130R090 S1      
327m0087            R1409 -1          A01X+167140Y+166525X0120Y0150R090 S1      
327m0087            R1485 -2          A01X+167140Y+166105X0120Y0150R270 S1      
317m0088            VIA   -    MD0080PA00X+166723Y+156964X0160Y         S0      
327m0088            R1479 -2          A01X+170305Y+160740X0120Y0150R180 S1      
317m0088            VIA   -    M      A01X+170983Y+161294X0200Y         S2      
017m0088            VIA   -    M      A18X+170983Y+161294X0260Y         S2      
017m0088                  -    MD0100PA00X+170983Y+161294                       
327m0088            R1401 -1          A01X+171569Y+161294X0120Y0150     S1      
327m0088            U6012 -B3         A01X+166528Y+156934X0100Y0130R090 S1      
327m0089            VIA   -    M      A01X+139802Y+160530X0300Y         S1      
327m0089            R1392 -1   M      A01X+141695Y+158040X0120Y0150     S1      
327m0089            U6011 -B3         A01X+140111Y+156934X0100Y0130R090 S1      
327m0089            R1473 -2          A01X+139340Y+160685X0120Y0150R270 S1      
327m0090            VIA   -           A18X+120775Y+168851X0260Y         S2      
327m0090            R1365 -1   M      A18X+120775Y+168540X0120Y0150R180 S2      
327m0090            R1446 -2          A18X+120350Y+168540X0120Y0150     S2      
317m0090            VIA   -    MD0100PA00X+120560Y+168540X0200Y         S0      
327m0090            U6010 -B3         A01X+127305Y+156934X0100Y0130R090 S1      
317m0090            VIA   -    MD0080PA00X+127500Y+156964X0160Y         S0      
327m0091            R1433 -1          A01X+054252Y+150310X0120Y0150     S1      
327m0091            U6017 -G35        A01X+052527Y+150946X0100Y0130     S1      
327m0092            R1421 -1          A01X+066821Y+150514X0120Y0150R270 S1      
327m0092            U6016 -G35        A01X+065333Y+150946X0100Y0130     S1      
327m0093            U6015 -G35        A01X+038916Y+150946X0100Y0130     S1      
327m0093            VIA   -           A01X+041993Y+150898X0300Y         S1      
327m0093            R1376 -1   M      A01X+040641Y+150310X0120Y0150R180 S1      
327m0094            R1387 -1          A01X+027835Y+150310X0120Y0150     S1      
327m0094            U6014 -G35        A01X+026110Y+150946X0100Y0130     S1      
327m0095            R1412 -1          A01X+155040Y+153610X0120Y0150     S1      
327m0095            U6013 -G35        A01X+153314Y+154246X0100Y0130     S1      
317m0096            VIA   -    M      A01X+167668Y+153789X0200Y         S2      
017m0096            VIA   -    M      A18X+167668Y+153789X0260Y         S2      
017m0096                  -    MD0100PA00X+167668Y+153789                       
327m0096            R1404 -1          A01X+167634Y+153570X0120Y0150R270 S1      
327m0096            U6012 -G35        A01X+166120Y+154246X0100Y0130     S1      
327m0097            U6011 -G35        A01X+139703Y+154246X0100Y0130     S1      
327m0097            R1395 -1   M      A01X+141428Y+153610X0120Y0150R180 S1      
327m0097            VIA   -           A01X+142781Y+154198X0300Y         S1      
327m0098            R1368 -1          A01X+128622Y+153610X0120Y0150     S1      
327m0098            U6010 -G35        A01X+126897Y+154246X0100Y0130     S1      
327SMB_ADC_SDA_R    R1341 -2          A01X+107472Y+046700X0198Y0197R180 S1      
327SMB_ADC_SDA_R    VIA   -    M      A18X+094705Y+126826X0260Y         S2      
327SMB_ADC_SDA_R    R1243 -1          A18X+084931Y+127397X0198Y0197R180 S2      
317SMB_ADC_SDA_R    VIA   -    MD0100PA00X+095500Y+128700X0200Y         S0      
327SMB_ADC_SDA_R    R1227 -1          A18X+095792Y+128700X0198Y0197R180 S2      
317SMB_ADC_SDA_R    VIA   -    MD0100PA00X+107167Y+046700X0200Y         S0      
327SMB_ADC_SDA_R    R1312 -2          A01X+106887Y+046700X0198Y0197     S1      
317SMB_ADC_SDA_R    VIA   -    MD0100PA00X+095436Y+063006X0200Y         S0      
327SMB_ADC_SDA      VIA   -    M      A01X+106226Y+046792X0300Y         S1      
327SMB_ADC_SDA      R1312 -1          A01X+106572Y+046700X0198Y0197     S1      
327SMB_ADC_SDA      U39   -17         A01X+105108Y+046548X0120Y0630R270 S1      
327SMB_ADC_SCL_R    R1244 -1          A18X+084922Y+127814X0198Y0197R180 S2      
327SMB_ADC_SCL_R    VIA   -    M      A18X+083829Y+126530X0260Y         S2      
317SMB_ADC_SCL_R    VIA   -    MD0100PA00X+095500Y+128300X0200Y         S0      
327SMB_ADC_SCL_R    R1228 -1          A18X+095792Y+128300X0198Y0197R180 S2      
317SMB_ADC_SCL_R    VIA   -    MD0100PA00X+107167Y+047150X0200Y         S0      
327SMB_ADC_SCL_R    R1315 -2          A01X+106887Y+047150X0198Y0197     S1      
327SMB_ADC_SCL_R    R1316 -2          A01X+107472Y+047150X0198Y0197R180 S1      
317SMB_ADC_SCL_R    VIA   -    MD0100PA00X+095436Y+063331X0200Y         S0      
327SMB_ADC_SCL      U39   -18         A01X+105108Y+046804X0120Y0630R270 S1      
327SMB_ADC_SCL      R1315 -1          A01X+106572Y+047150X0198Y0197     S1      
327SMB_ADC_SCL      VIA   -    M      A01X+105820Y+047150X0300Y         S1      
317m0099            VIA   -    MD0100PA00X+026060Y+015106X0200Y         S0      
327m0099            R1339 -1          A01X+073965Y+039327X0198Y0197R090 S1      
327m0099            R1328 -2          A01X+007418Y+014519X0198Y0197R180 S1      
327m0099            R1271 -2   M      A01X+007418Y+014919X0198Y0197R180 S1      
317m0099            VIA   -    M      A01X+007166Y+014919X0200Y         S2      
017m0099            VIA   -    M      A18X+007166Y+014919X0260Y         S2      
017m0099                  -    MD0100PA00X+007166Y+014919                       
317m0099            VIA   -    MD0100PA00X+073550Y+039933X0200Y         S0      
327m0099            R3559 -2          A01X+026698Y+014720X0198Y0197R180 S1      
317m0099            VIA   -    MD0100PA00X+067904Y+020418X0200Y         S0      
327m0100            R1339 -2          A01X+073965Y+039642X0198Y0197R090 S1      
327m0100            VIA   -    M      A01X+073742Y+040200X0300Y         S1      
327m0100            U18   -P1         A01X+073828Y+041989X0160Y    R090 S1      
317m0101            VIA   -    MD0100PA00X+175693Y+037245X0200Y         S0      
327m0101            R1340 -2          A01X+083026Y+040535X0198Y0197     S1      
327m0101            R1327 -2          A01X+153894Y+028882X0198Y0197R180 S1      
327m0101            R1270 -2   M      A01X+153894Y+029282X0198Y0197R180 S1      
317m0101            VIA   -    M      A01X+153642Y+029282X0200Y         S2      
017m0101            VIA   -    M      A18X+153642Y+029282X0260Y         S2      
017m0101                  -    MD0100PA00X+153642Y+029282                       
317m0101            VIA   -    MD0100PA00X+083785Y+040535X0200Y         S0      
327m0101            R3563 -2          A01X+175430Y+037245X0198Y0197     S1      
317m0101            VIA   -    MD0100PA00X+100676Y+039621X0200Y         S0      
317m0101            VIA   -    MD0100PA00X+101025Y+036344X0200Y         S0      
327m0102            R1340 -1          A01X+082711Y+040535X0198Y0197     S1      
327m0102            U18   -AA1        A01X+076032Y+041989X0160Y    R090 S1      
317m0102            VIA   -    MD0100PA00X+076186Y+041836X0180Y    R090 S0      
317m0102            VIA   -    M      A01X+082465Y+040535X0200Y         S2      
017m0102            VIA   -    M      A18X+082465Y+040535X0260Y         S2      
017m0102                  -    MD0100PA00X+082465Y+040535                       
327m0103            R1329 -1          A18X+069950Y+039329X0198Y0197R270 S2      
317m0103            VIA   -    MD0100PA00X+109950Y+031800X0200Y         S0      
317m0103            VIA   -    MD0100PA00X+070348Y+036941X0200Y         S0      
327m0103            R3752 -2          A18X+083344Y+022629X0198Y0197R270 S2      
317m0103            VIA   -    MD0100PA00X+067301Y+016902X0200Y         S0      
317m0103            VIA   -    M      A01X+084758Y+023222X0200Y         S2      
017m0103            VIA   -    M      A18X+084758Y+023222X0260Y         S2      
017m0103                  -    MD0100PA00X+084758Y+023222                       
327m0103            R1326 -2          A01X+126262Y+039512X0198Y0197R180 S1      
327m0103            R1269 -2   M      A01X+126263Y+039912X0198Y0197R180 S1      
317m0103            VIA   -    M      A01X+126011Y+039912X0200Y         S2      
017m0103            VIA   -    M      A18X+126011Y+039912X0260Y         S2      
017m0103                  -    MD0100PA00X+126011Y+039912                       
327m0104            R1329 -2          A18X+069950Y+039644X0198Y0197R270 S2      
317m0104            VIA   -    M      A01X+070858Y+040487X0200Y         S2      
017m0104            VIA   -    M      A18X+070858Y+040487X0260Y         S2      
017m0104                  -    MD0100PA00X+070858Y+040487                       
317m0104            VIA   -    MD0100PA00X+072414Y+042466X0180Y    R090 S0      
327m0104            U18   -K3         A01X+072568Y+042619X0160Y    R090 S1      
317m0105            VIA   -    M      A01X+128935Y+042195X0200Y         S2      
017m0105            VIA   -    M      A18X+128935Y+042195X0260Y         S2      
017m0105                  -    MD0100PA00X+128935Y+042195                       
327m0105            U52   -13         A01X+128286Y+041224X0090Y0240     S1      
317m0105            VIA   -    MD0100PA00X+096481Y+020512X0200Y         S0      
327m0105            R1283 -2          A01X+096505Y+019817X0198Y0197R180 S1      
327m0105            C1110 -1   M      A01X+096470Y+020210X0198Y0197R180 S1      
317m0106            VIA   -    M      A01X+096141Y+020512X0200Y         S2      
017m0106            VIA   -    M      A18X+096141Y+020512X0260Y         S2      
017m0106                  -    MD0100PA00X+096141Y+020512                       
317m0106            VIA   -    MD0100PA00X+128935Y+041855X0200Y         S0      
327m0106            U52   -12         A01X+128541Y+040968X0090Y0240R270 S1      
327m0106            R1292 -2          A01X+096120Y+019817X0198Y0197     S1      
327m0106            C1110 -2   M      A01X+096155Y+020210X0198Y0197R180 S1      
317m0107            VIA   -    M      A01X+010082Y+016891X0200Y         S2      
017m0107            VIA   -    M      A18X+010082Y+016891X0260Y         S2      
017m0107                  -    MD0100PA00X+010082Y+016891                       
317m0107            VIA   -    MD0100PA00X+027864Y+008302X0200Y    R270 S0      
327m0107            R1291 -2          A01X+027888Y+007454X0198Y0197R180 S1      
327m0107            C1112 -1   M      A01X+027853Y+007846X0198Y0197R180 S1      
327m0107            U56   -13         A01X+009441Y+016230X0090Y0240     S1      
317m0108            VIA   -    M      A01X+010082Y+016551X0300Y         S1      
017m0108            VIA   -    M      A18X+010082Y+016551X0200Y         S1      
017m0108                  -    MD0100PA00X+010082Y+016551                       
317m0108            VIA   -    MD0100PA00X+027524Y+008302X0200Y    R270 S0      
327m0108            R1302 -2          A01X+027503Y+007454X0198Y0197     S1      
327m0108            C1112 -2   M      A01X+027538Y+007846X0198Y0197R180 S1      
327m0108            U56   -12         A01X+009697Y+015974X0090Y0240R270 S1      
317m0109            VIA   -    M      A01X+174349Y+009283X0200Y         S2      
017m0109            VIA   -    M      A18X+174349Y+009283X0260Y         S2      
017m0109                  -    MD0100PA00X+174349Y+009283                       
327m0109            R1284 -2          A01X+174373Y+008534X0198Y0197R180 S1      
327m0109            C1111 -1   M      A01X+174338Y+008926X0198Y0197R180 S1      
327m0109            U55   -13         A01X+155917Y+030593X0090Y0240     S1      
317m0109            VIA   -    MD0100PA00X+156451Y+031373X0200Y         S0      
317m0110            VIA   -    M      A01X+156451Y+031033X0200Y         S2      
017m0110            VIA   -    M      A18X+156451Y+031033X0260Y         S2      
017m0110                  -    MD0100PA00X+156451Y+031033                       
327m0110            R1301 -2          A01X+173988Y+008534X0198Y0197     S1      
327m0110            C1111 -2   M      A01X+174023Y+008926X0198Y0197R180 S1      
327m0110            U55   -12         A01X+156173Y+030337X0090Y0240R270 S1      
317m0110            VIA   -    MD0100PA00X+174009Y+009283X0200Y         S0      
327m0111            U51   -6          A18X+086460Y+128941X0140Y0630R270 S2      
327m0111            VIA   -           A18X+086964Y+129904X0260Y         S2      
327m0112            VIA   -    M      A18X+085632Y+127553X0260Y         S2      
327m0112            R1243 -2          A18X+085246Y+127397X0198Y0197R180 S2      
327m0112            U51   -2          A18X+086460Y+127917X0140Y0630R270 S2      
327m0113            R1244 -2          A18X+085237Y+127814X0198Y0197R180 S2      
327m0113            VIA   -    M      A18X+085550Y+128173X0260Y         S2      
327m0113            U51   -3          A18X+086460Y+128173X0140Y0630R270 S2      
327m0114            R1227 -2          A18X+096108Y+128700X0198Y0197R180 S2      
327m0114            VIA   -    M      A18X+096445Y+128740X0260Y         S2      
327m0114            U50   -14         A18X+097342Y+128569X0150Y0630R270 S2      
327m0115            VIA   -    M      A18X+096657Y+128218X0260Y         S2      
327m0115            U50   -13         A18X+097342Y+128319X0150Y0630R270 S2      
327m0115            R1228 -2          A18X+096108Y+128300X0198Y0197R180 S2      
317m0116            VIA   -    MD0100PA00X+065568Y+166421X0200Y         S0      
327m0116            U41   -4          A18X+066022Y+166723X0120Y0210R180 S2      
327m0116            VIA   -    M      A18X+093041Y+134741X0260Y         S2      
317m0116            VIA   -    MD0100PA00X+068954Y+142747X0200Y         S0      
317m0116            VIA   -    MD0100PA00X+087504Y+140725X0200Y         S0      
317m0116            VIA   -    MD0100PA00X+066173Y+156108X0200Y         S0      
327m0116            R806  -1          A18X+093845Y+133250X0120Y0150R180 S2      
327m0117            R807  -1          A18X+093845Y+133700X0120Y0150R180 S2      
317m0117            VIA   -    MD0100PA00X+065865Y+166417X0200Y         S0      
327m0117            U41   -3          A18X+066219Y+166723X0100Y0210R180 S2      
317m0117            VIA   -    M      A01X+087499Y+141044X0200Y         S2      
017m0117            VIA   -    M      A18X+087499Y+141044X0260Y         S2      
017m0117                  -    MD0100PA00X+087499Y+141044                       
317m0117            VIA   -    MD0100PA00X+069159Y+142952X0200Y         S0      
317m0117            VIA   -    MD0100PA00X+066425Y+156101X0200Y         S0      
327m0118            R1462 -2   M      A18X+066260Y+165962X0120Y0150R090 S2      
327m0118            U41   -2          A18X+066416Y+166723X0100Y0210R180 S2      
317m0118            VIA   -    M      A01X+064085Y+166519X0200Y         S2      
017m0118            VIA   -    M      A18X+064085Y+166519X0260Y         S2      
017m0118                  -    MD0100PA00X+064085Y+166519                       
317m0118            VIA   -    MD0100PA00X+045018Y+161495X0200Y         S0      
327m0118            R696  -1          A18X+044234Y+160991X0120Y0150R090 S2      
327m0119            U41   -1          A18X+066613Y+166723X0120Y0210R180 S2      
327m0119            R1463 -2   M      A18X+066620Y+165962X0120Y0150R090 S2      
317m0119            VIA   -    M      A01X+064746Y+166295X0200Y         S2      
017m0119            VIA   -    M      A18X+064746Y+166295X0260Y         S2      
017m0119                  -    MD0100PA00X+064746Y+166295                       
317m0119            VIA   -    MD0100PA00X+045050Y+161245X0200Y         S0      
327m0119            R695  -1          A18X+044557Y+160978X0120Y0150R090 S2      
327m0120            R808  -1          A18X+093845Y+134150X0120Y0150R180 S2      
327m0120            U43   -4          A18X+062781Y+164667X0120Y0210R090 S2      
317m0120            VIA   -    MD0100PA00X+063164Y+167095X0200Y         S0      
317m0120            VIA   -    M      A01X+088338Y+141788X0200Y         S2      
017m0120            VIA   -    M      A18X+088338Y+141788X0260Y         S2      
017m0120                  -    MD0100PA00X+088338Y+141788                       
327m0121            R809  -1          A18X+093845Y+134600X0120Y0150R180 S2      
327m0121            U43   -3          A18X+062781Y+164470X0100Y0210R090 S2      
317m0121            VIA   -    MD0100PA00X+088328Y+142173X0200Y         S0      
317m0121            VIA   -    M      A01X+063342Y+167349X0200Y         S2      
017m0121            VIA   -    M      A18X+063342Y+167349X0260Y         S2      
017m0121                  -    MD0100PA00X+063342Y+167349                       
327m0122            R692  -1          A18X+064340Y+162384X0120Y0150R090 S2      
327m0122            R1468 -2   M      A18X+062005Y+164160X0120Y0150     S2      
327m0122            VIA   -    M      A18X+062318Y+164423X0260Y         S2      
327m0122            U43   -2          A18X+062781Y+164274X0100Y0210R090 S2      
327m0123            R691  -1          A18X+064358Y+162915X0120Y0150R090 S2      
327m0123            VIA   -    M      A18X+062320Y+163910X0260Y         S2      
327m0123            U43   -1          A18X+062781Y+164077X0120Y0210R090 S2      
327m0123            R1469 -2   M      A18X+062005Y+163840X0120Y0150     S2      
317m0124            VIA   -    MD0100PA00X+044691Y+156210X0200Y         S0      
327m0124            U42   -4          A01X+045681Y+158309X0120Y0210R270 S1      
327m0124            R803  -1          A18X+093845Y+132350X0120Y0150R180 S2      
317m0124            VIA   -    M      A01X+093122Y+132305X0200Y         S2      
017m0124            VIA   -    M      A18X+093122Y+132305X0260Y         S2      
017m0124                  -    MD0100PA00X+093122Y+132305                       
317m0125            VIA   -    MD0100PA00X+044681Y+156502X0200Y         S0      
327m0125            U42   -3          A01X+045681Y+158112X0100Y0210R270 S1      
317m0125            VIA   -    M      A01X+093133Y+132847X0200Y         S2      
017m0125            VIA   -    M      A18X+093133Y+132847X0260Y         S2      
017m0125                  -    MD0100PA00X+093133Y+132847                       
327m0125            R805  -1          A18X+093845Y+132800X0120Y0150R180 S2      
327m0126            R671  -1          A01X+041132Y+155525X0120Y0150R270 S1      
327m0126            R1448 -2   M      A01X+046605Y+157940X0120Y0150R180 S1      
327m0126            VIA   -    M      A01X+046358Y+158422X0300Y         S1      
327m0126            U42   -2          A01X+045681Y+157915X0100Y0210R270 S1      
327m0127            R670  -1          A01X+041809Y+155731X0120Y0150R180 S1      
327m0127            R1451 -2   M      A01X+046605Y+157620X0120Y0150R180 S1      
327m0127            VIA   -    M      A01X+045967Y+157260X0300Y         S1      
327m0127            U42   -1          A01X+045681Y+157718X0120Y0210R270 S1      
327m0128            R801  -1          A18X+093845Y+131450X0120Y0150R180 S2      
327m0128            U45   -4          A01X+038028Y+158127X0120Y0210R090 S1      
317m0128            VIA   -    MD0100PA00X+042128Y+157192X0200Y         S0      
317m0128            VIA   -    M      A01X+093503Y+131377X0200Y         S2      
017m0128            VIA   -    M      A18X+093503Y+131377X0260Y         S2      
017m0128                  -    MD0100PA00X+093503Y+131377                       
327m0129            R802  -1          A18X+093845Y+131900X0120Y0150R180 S2      
327m0129            U45   -3          A01X+038028Y+158324X0100Y0210R090 S1      
317m0129            VIA   -    M      A01X+041925Y+156683X0200Y         S2      
017m0129            VIA   -    M      A18X+041925Y+156683X0260Y         S2      
017m0129                  -    MD0100PA00X+041925Y+156683                       
317m0129            VIA   -    MD0100PA00X+093530Y+131752X0200Y         S0      
317m0130            VIA   -    M      A01X+038928Y+156841X0200Y         S2      
017m0130            VIA   -    M      A18X+038928Y+156841X0260Y         S2      
017m0130                  -    MD0100PA00X+038928Y+156841                       
327m0130            R1436 -2   M      A01X+036975Y+157940X0120Y0150     S1      
327m0130            VIA   -    M      A01X+037620Y+157620X0300Y         S1      
327m0130            U45   -2          A01X+038028Y+158520X0100Y0210R090 S1      
317m0130            VIA   -    MD0100PA00X+017349Y+154254X0200Y         S0      
317m0130            VIA   -    MD0100PA00X+016332Y+149434X0200Y         S0      
327m0130            R675  -1          A01X+016564Y+149434X0120Y0150     S1      
317m0131            VIA   -    MD0100PA00X+038794Y+156553X0200Y         S0      
327m0131            R1437 -2   M      A01X+036975Y+158260X0120Y0150     S1      
327m0131            U45   -1          A01X+038028Y+158717X0120Y0210R090 S1      
327m0131            VIA   -    M      A01X+037551Y+158717X0300Y         S1      
317m0131            VIA   -    MD0100PA00X+017023Y+154296X0200Y         S0      
317m0131            VIA   -    MD0100PA00X+016346Y+149101X0200Y         S0      
327m0131            R674  -1          A01X+016575Y+149101X0120Y0150     S1      
317m0132            VIA   -    M      A01X+098078Y+145154X0200Y         S2      
017m0132            VIA   -    M      A18X+098078Y+145154X0260Y         S2      
017m0132                  -    MD0100PA00X+098078Y+145154                       
317m0132            VIA   -    MD0100PA00X+101250Y+132850X0200Y         S0      
327m0132            R830  -2          A18X+100855Y+132826X0120Y0150     S2      
317m0132            VIA   -    MD0100PA00X+142771Y+155365X0200Y         S0      
327m0132            U46   -4          A01X+147001Y+168192X0120Y0210     S1      
317m0132            VIA   -    MD0100PA00X+146611Y+168510X0200Y         S0      
327m0133            R831  -2          A18X+100855Y+132384X0120Y0150     S2      
317m0133            VIA   -    MD0100PA00X+097570Y+145137X0200Y         S0      
317m0133            VIA   -    MD0100PA00X+143021Y+155365X0200Y         S0      
327m0133            U46   -3          A01X+147198Y+168192X0100Y0210     S1      
317m0133            VIA   -    MD0100PA00X+147050Y+168550X0200Y         S0      
317m0133            VIA   -    M      A01X+101250Y+132250X0200Y         S2      
017m0133            VIA   -    M      A18X+101250Y+132250X0260Y         S2      
017m0133                  -    MD0100PA00X+101250Y+132250                       
327m0134            R1420 -2          A01X+144115Y+167954X0120Y0150R180 S1      
327m0134            VIA   -    M      A01X+144575Y+168999X0300Y         S1      
327m0134            U46   -2          A01X+147394Y+168192X0100Y0210     S1      
327m0134            R686  -1   M      A01X+144119Y+168266X0120Y0150R180 S1      
327m0135            R1428 -2   M      A01X+144117Y+168927X0120Y0150R180 S1      
327m0135            R684  -1          A01X+144119Y+168616X0120Y0150R180 S1      
327m0135            VIA   -    M      A01X+147415Y+168785X0300Y         S1      
327m0135            U46   -1          A01X+147591Y+168192X0120Y0210     S1      
327m0136            R832  -2          A18X+100855Y+131942X0120Y0150     S2      
317m0136            VIA   -    MD0100PA00X+101353Y+131895X0200Y         S0      
327m0136            U47   -4          A18X+166356Y+167723X0120Y0210R270 S2      
317m0136            VIA   -    MD0100PA00X+171607Y+147204X0200Y         S0      
317m0136            VIA   -    M      A01X+097326Y+145671X0200Y         S2      
017m0136            VIA   -    M      A18X+097326Y+145671X0260Y         S2      
017m0136                  -    MD0100PA00X+097326Y+145671                       
317m0136            VIA   -    MD0100PA00X+166938Y+167524X0200Y         S0      
327m0137            R833  -2          A18X+100855Y+131500X0120Y0150     S2      
317m0137            VIA   -    MD0100PA00X+101360Y+131605X0200Y         S0      
327m0137            U47   -3          A18X+166356Y+167920X0100Y0210R270 S2      
317m0137            VIA   -    M      A01X+096952Y+145278X0200Y         S2      
017m0137            VIA   -    M      A18X+096952Y+145278X0260Y         S2      
017m0137                  -    MD0100PA00X+096952Y+145278                       
317m0137            VIA   -    MD0100PA00X+172235Y+147125X0200Y         S0      
317m0137            VIA   -    MD0100PA00X+167190Y+167627X0200Y         S0      
327m0138            R681  -1          A18X+166230Y+166256X0120Y0150     S2      
327m0138            R1431 -2   M      A18X+167199Y+168104X0120Y0150R090 S2      
327m0138            U47   -2          A18X+166356Y+168116X0100Y0210R270 S2      
327m0138            VIA   -    M      A18X+166826Y+167999X0260Y         S2      
327m0139            R680  -1          A18X+165841Y+165565X0120Y0150     S2      
327m0139            VIA   -    M      A18X+166848Y+168626X0260Y         S2      
327m0139            U47   -1          A18X+166356Y+168313X0120Y0210R270 S2      
327m0139            R1432 -2   M      A18X+167191Y+168446X0120Y0150R270 S2      
317m0140            VIA   -    MD0100PA00X+101350Y+133716X0200Y         S0      
317m0140            VIA   -    M      A01X+115434Y+155598X0200Y         S2      
017m0140            VIA   -    M      A18X+115434Y+155598X0260Y         S2      
017m0140                  -    MD0100PA00X+115434Y+155598                       
327m0140            R828  -2          A18X+100855Y+133716X0120Y0150     S2      
327m0140            U48   -4          A01X+114819Y+155351X0120Y0210R180 S1      
327m0141            R829  -2          A18X+100855Y+133274X0120Y0150     S2      
327m0141            U48   -3          A01X+114622Y+155351X0100Y0210R180 S1      
317m0141            VIA   -    MD0100PA00X+115726Y+155600X0200Y         S0      
317m0141            VIA   -    M      A01X+101350Y+133274X0200Y         S2      
017m0141            VIA   -    M      A18X+101350Y+133274X0260Y         S2      
017m0141                  -    MD0100PA00X+101350Y+133274                       
327m0142            R1415 -2   M      A01X+115872Y+155402X0120Y0150     S1      
327m0142            U48   -2          A01X+114425Y+155351X0100Y0210R180 S1      
317m0142            VIA   -    M      A01X+116149Y+155118X0200Y         S2      
017m0142            VIA   -    M      A18X+116149Y+155118X0260Y         S2      
017m0142                  -    MD0100PA00X+116149Y+155118                       
317m0142            VIA   -    MD0100PA00X+129762Y+152953X0200Y         S0      
327m0142            R677  -1          A01X+130183Y+152815X0120Y0150     S1      
317m0143            VIA   -    MD0100PA00X+129749Y+152691X0200Y         S0      
327m0143            R676  -1          A01X+130183Y+152500X0120Y0150     S1      
317m0143            VIA   -    M      A01X+116348Y+154620X0200Y         S2      
017m0143            VIA   -    M      A18X+116348Y+154620X0260Y         S2      
017m0143                  -    MD0100PA00X+116348Y+154620                       
327m0143            R1418 -2   M      A01X+115942Y+154458X0120Y0150     S1      
327m0143            U48   -1          A01X+114228Y+155351X0120Y0210R180 S1      
327m0144            R797  -2          A18X+100855Y+134600X0120Y0150     S2      
317m0144            VIA   -    M      A01X+101250Y+134750X0200Y         S2      
017m0144            VIA   -    M      A18X+101250Y+134750X0260Y         S2      
017m0144                  -    MD0100PA00X+101250Y+134750                       
327m0144            U49   -4          A18X+117797Y+167141X0120Y0210R270 S2      
317m0144            VIA   -    MD0100PA00X+118138Y+167031X0200Y         S0      
327m0145            R799  -2          A18X+100855Y+134158X0120Y0150     S2      
317m0145            VIA   -    M      A01X+101250Y+134158X0200Y         S2      
017m0145            VIA   -    M      A18X+101250Y+134158X0260Y         S2      
017m0145                  -    MD0100PA00X+101250Y+134158                       
327m0145            U49   -3          A18X+117797Y+167338X0100Y0210R270 S2      
317m0145            VIA   -    MD0100PA00X+118436Y+167025X0200Y         S0      
327m0146            R1410 -2          A18X+118715Y+167211X0120Y0150R090 S2      
327m0146            VIA   -    M      A18X+118255Y+167465X0260Y         S2      
327m0146            U49   -2          A18X+117797Y+167535X0100Y0210R270 S2      
327m0146            R667  -1   M      A18X+118552Y+167519X0120Y0150R180 S2      
327m0147            R1411 -2          A18X+118536Y+168268X0120Y0150R270 S2      
327m0147            R666  -1   M      A18X+118548Y+167913X0120Y0150R180 S2      
327m0147            VIA   -    M      A18X+118255Y+167965X0260Y         S2      
327m0147            U49   -1          A18X+117797Y+167732X0120Y0210R270 S2      
327m0148            R1350 -2          A01X+126558Y+039050X0198Y0197     S1      
327m0148            R1275 -2   M      A01X+127362Y+039088X0198Y0197     S1      
327m0148            VIA   -    M      A01X+127246Y+039456X0300Y         S1      
327m0148            U52   -4          A01X+127439Y+040377X0090Y0240R270 S1      
327m0149            R1349 -2          A01X+118400Y+042585X0198Y0197R270 S1      
327m0149            VIA   -    M      A01X+125850Y+039250X0300Y         S1      
327m0149            R1275 -1          A01X+127047Y+039088X0198Y0197     S1      
327m0150            U52   -5          A01X+127695Y+040121X0090Y0240     S1      
317m0150            VIA   -    M      A01X+127558Y+039360X0200Y         S2      
017m0150            VIA   -    M      A18X+127558Y+039360X0260Y         S2      
017m0150                  -    MD0100PA00X+127558Y+039360                       
327m0150            R1272 -2          A01X+127737Y+039088X0198Y0197R180 S1      
327m0151            R1348 -2          A01X+117200Y+042742X0198Y0197R270 S1      
327m0151            VIA   -    M      A01X+127400Y+038500X0300Y         S1      
327m0151            R1272 -1          A01X+128052Y+039088X0198Y0197R180 S1      
327m0152            R1277 -2          A01X+008518Y+014095X0198Y0197     S1      
327m0152            VIA   -    M      A01X+008401Y+014656X0300Y         S1      
327m0152            U56   -4          A01X+008594Y+015384X0090Y0240R270 S1      
327m0153            R1347 -2          A01X+057863Y+019748X0198Y0197     S1      
327m0153            R1277 -1          A01X+008203Y+014095X0198Y0197     S1      
317m0153            VIA   -    M      A01X+008203Y+014349X0200Y         S2      
017m0153            VIA   -    M      A18X+008203Y+014349X0260Y         S2      
017m0153                  -    MD0100PA00X+008203Y+014349                       
317m0153            VIA   -    MD0100PA00X+058200Y+019748X0200Y         S0      
327m0154            R1360 -2          A01X+007418Y+015319X0198Y0197R180 S1      
327m0154            U56   -5          A01X+008850Y+015128X0090Y0240     S1      
327m0154            R1274 -2          A01X+008893Y+014095X0198Y0197R180 S1      
317m0154            VIA   -    M      A01X+008714Y+014366X0200Y         S2      
017m0154            VIA   -    M      A18X+008714Y+014366X0260Y         S2      
017m0154                  -    MD0100PA00X+008714Y+014366                       
317m0154            VIA   -    MD0100PA00X+007178Y+015319X0200Y         S0      
327m0155            R1346 -2          A01X+057861Y+019352X0198Y0197     S1      
327m0155            R1274 -1          A01X+009208Y+014095X0198Y0197R180 S1      
317m0155            VIA   -    M      A01X+009220Y+014385X0200Y         S2      
017m0155            VIA   -    M      A18X+009220Y+014385X0260Y         S2      
017m0155                  -    MD0100PA00X+009220Y+014385                       
317m0155            VIA   -    MD0100PA00X+058212Y+019415X0200Y         S0      
327m0156            R1355 -2          A01X+153894Y+029682X0198Y0197R180 S1      
317m0156            VIA   -    M      A01X+154877Y+029192X0200Y         S2      
017m0156            VIA   -    M      A18X+154877Y+029192X0260Y         S2      
017m0156                  -    MD0100PA00X+154877Y+029192                       
327m0156            R1276 -2          A01X+154994Y+028458X0198Y0197     S1      
327m0156            U55   -4          A01X+155070Y+029746X0090Y0240R270 S1      
317m0156            VIA   -    MD0100PA00X+153654Y+029682X0200Y         S0      
327m0157            R1276 -1          A01X+154679Y+028458X0198Y0197     S1      
317m0157            VIA   -    MD0100PA00X+154679Y+028712X0200Y         S0      
327m0157            R1345 -2          A01X+118000Y+042742X0198Y0197R270 S1      
317m0157            VIA   -    M      A01X+118100Y+040250X0200Y         S2      
017m0157            VIA   -    M      A18X+118100Y+040250X0260Y         S2      
017m0157                  -    MD0100PA00X+118100Y+040250                       
327m0158            R1273 -2          A01X+155369Y+028458X0198Y0197R180 S1      
317m0158            VIA   -    M      A01X+155190Y+028729X0200Y         S2      
017m0158            VIA   -    M      A18X+155190Y+028729X0260Y         S2      
017m0158                  -    MD0100PA00X+155190Y+028729                       
327m0158            U55   -5          A01X+155326Y+029490X0090Y0240     S1      
327m0159            R1344 -2          A01X+117600Y+042742X0198Y0197R270 S1      
317m0159            VIA   -    M      A01X+117403Y+040352X0200Y         S2      
017m0159            VIA   -    M      A18X+117403Y+040352X0260Y         S2      
017m0159                  -    MD0100PA00X+117403Y+040352                       
317m0159            VIA   -    M      A01X+155696Y+028748X0200Y         S2      
017m0159            VIA   -    M      A18X+155696Y+028748X0260Y         S2      
017m0159                  -    MD0100PA00X+155696Y+028748                       
327m0159            R1273 -1          A01X+155684Y+028458X0198Y0197R180 S1      
327m0160            R1217 -2          A18X+165101Y+167647X0120Y0150     S2      
327m0160            VIA   -    M      A18X+165396Y+167645X0260Y         S2      
327m0160            U47   -6          A18X+165852Y+167723X0120Y0210R270 S2      
327m0161            VIA   -    M      A01X+146323Y+167677X0300Y         S1      
327m0161            U46   -6          A01X+147001Y+167688X0120Y0210     S1      
327m0161            R1216 -2          A01X+146550Y+167055X0120Y0150R270 S1      
327m0162            VIA   -    M      A01X+115255Y+156231X0300Y         S1      
327m0162            U48   -6          A01X+114819Y+155855X0120Y0210R180 S1      
327m0162            R1218 -2          A01X+115219Y+156542X0120Y0150R090 S1      
327m0163            VIA   -    M      A18X+116723Y+167112X0260Y         S2      
327m0163            R1219 -2          A18X+116411Y+166976X0120Y0150     S2      
327m0163            U49   -6          A18X+117293Y+167141X0120Y0210R270 S2      
327m0164            VIA   -    M      A18X+063196Y+165195X0260Y         S2      
327m0164            R1214 -2          A18X+063651Y+165064X0120Y0150R180 S2      
327m0164            U43   -6          A18X+063285Y+164667X0120Y0210R090 S2      
327m0165            VIA   -    M      A18X+065780Y+167690X0260Y         S2      
327m0165            U41   -6          A18X+066022Y+167227X0120Y0210R180 S2      
327m0165            R1212 -2          A18X+065541Y+167358X0120Y0150R090 S2      
327m0166            VIA   -    M      A01X+044681Y+158518X0300Y         S1      
327m0166            U42   -6          A01X+045177Y+158309X0120Y0210R270 S1      
327m0166            R1213 -2          A01X+044622Y+158842X0120Y0150R090 S1      
327m0167            VIA   -    M      A01X+038913Y+157697X0300Y         S1      
327m0167            U45   -6          A01X+038532Y+158127X0120Y0210R090 S1      
327m0167            R1215 -2          A01X+038577Y+157645X0120Y0150R180 S1      
327m0168            VIA   -    M      A01X+029274Y+024269X0300Y         S1      
327m0168            R1174 -2          A01X+029295Y+024634X0198Y0197R270 S1      
327m0168            U35   -1          A01X+029274Y+023722X0220Y0320R180 S1      
327m0169            VIA   -    M      A01X+028655Y+022212X0300Y         S1      
327m0169            R1177 -1          A01X+028860Y+021859X0198Y0197R270 S1      
327m0169            U35   -4          A01X+028526Y+022778X0220Y0320R180 S1      
327m0170            R1177 -2          A01X+028860Y+021544X0198Y0197R270 S1      
317m0170            VIA   -    MD0100PA00X+028916Y+021250X0200Y         S0      
317m0170            VIA   -    M      A01X+033178Y+018290X0200Y    R270 S2      
017m0170            VIA   -    M      A18X+033178Y+018290X0260Y    R270 S2      
017m0170                  -    MD0100PA00X+033178Y+018290                       
327m0170            U207  -2          A01X+033178Y+017861X0140Y0490     S1      
327m0171            R9023 -2          A01X+083508Y+047100X0198Y0197     S1      
327m0171            U9001 -1          A01X+084476Y+046728X0220Y0320     S1      
327m0171            VIA   -    M      A01X+083850Y+047100X0300Y         S1      
327m0172            R9033 -1          A01X+085200Y+048592X0198Y0197R090 S1      
327m0172            U9001 -4          A01X+085224Y+047672X0220Y0320     S1      
327m0172            VIA   -    M      A01X+085224Y+048250X0300Y         S1      
327m0173            R9033 -2          A01X+085200Y+048908X0198Y0197R090 S1      
317m0173            VIA   -    M      A01X+082700Y+048906X0200Y         S2      
017m0173            VIA   -    M      A18X+082700Y+048906X0260Y         S2      
017m0173                  -    MD0100PA00X+082700Y+048906                       
327m0173            U75   -2          A01X+082159Y+048906X0140Y0490R090 S1      
327m0174            R1255 -2          A18X+090808Y+128824X0180Y0200R180 S2      
327m0174            VIA   -    M      A18X+089388Y+129132X0260Y         S2      
327m0174            U51   -11         A18X+088665Y+128941X0140Y0630R270 S2      
327m0174            C1089 -1   M      A18X+089795Y+128963X0198Y0197R180 S2      
327m0175            R1248 -2          A18X+091438Y+128824X0180Y0200     S2      
317m0175            VIA   -    M      A01X+096467Y+127100X0200Y         S2      
017m0175            VIA   -    M      A18X+096467Y+127100X0260Y         S2      
017m0175                  -    MD0100PA00X+096467Y+127100                       
317m0175            VIA   -    MD0100PA00X+091703Y+128824X0200Y         S0      
327m0175            U50   -10         A18X+097342Y+127569X0150Y0630R270 S2      
327m0175            C1082 -1          A18X+096108Y+127100X0198Y0197     S2      
327PVDD_33_S5_ADC   R1248 -1          A18X+091122Y+128824X0180Y0200     S2      
327PVDD_33_S5_ADC   R1255 -1   M      A18X+091122Y+128824X0180Y0200R180 S2      
327PVDD_33_S5_ADC   VIA   -    M      A18X+093151Y+128508X0260Y         S2      
327PVDD_33_S5_ADC   R1235 -2          A18X+093508Y+128616X0198Y0197     S2      
327PVDD_33_S5_ADC   R1224 -1   M      A18X+092296Y+128719X0198Y0197R180 S2      
327m0176            R1256 -2          A18X+090799Y+129671X0180Y0200R180 S2      
327m0176            VIA   -    M      A18X+088665Y+129918X0260Y         S2      
327m0176            U51   -9          A18X+088665Y+129452X0140Y0630R270 S2      
327m0176            C1090 -1   M      A18X+089772Y+129803X0198Y0197R180 S2      
327m0177            R1249 -2          A18X+091429Y+129671X0180Y0200     S2      
327m0177            VIA   -    M      A01X+094426Y+128573X0300Y         S1      
317m0177            VIA   -    MD0100PA00X+096644Y+127814X0200Y         S0      
327m0177            C1081 -1          A18X+096108Y+127900X0198Y0197     S2      
327m0177            U50   -12         A18X+097342Y+128069X0150Y0630R270 S2      
317m0177            VIA   -    MD0100PA00X+091694Y+129671X0200Y         S0      
327m0178            R1249 -1          A18X+091114Y+129671X0180Y0200     S2      
327m0178            R1256 -1   M      A18X+091114Y+129671X0180Y0200R180 S2      
327m0178            R1236 -2          A18X+093496Y+129419X0198Y0197     S2      
327m0178            VIA   -    M      A18X+093171Y+129399X0260Y         S2      
327m0178            R1225 -1   M      A18X+092301Y+129596X0198Y0197R180 S2      
327m0178            VIA   -    M      A18X+091978Y+129698X0260Y         S2      
327m0179            R1254 -2          A18X+090801Y+129233X0180Y0200R180 S2      
327m0179            VIA   -    M      A18X+089351Y+129660X0260Y         S2      
327m0179            U51   -10         A18X+088665Y+129197X0140Y0630R270 S2      
327m0179            C1088 -1   M      A18X+089768Y+129385X0198Y0197R180 S2      
327m0180            R1247 -2          A18X+091431Y+129233X0180Y0200     S2      
327m0180            VIA   -           A18X+097813Y+126853X0260Y         S2      
317m0180            VIA   -    M      A01X+096350Y+127500X0300Y         S1      
017m0180            VIA   -    M      A18X+096350Y+127500X0200Y         S1      
017m0180                  -    MD0100PA00X+096350Y+127500                       
317m0180            VIA   -    MD0100PA00X+091690Y+129233X0200Y         S0      
327m0180            C1080 -1          A18X+096108Y+127500X0198Y0197     S2      
327m0180            U50   -11  M      A18X+097342Y+127819X0150Y0630R270 S2      
327m0181            R1247 -1          A18X+091116Y+129233X0180Y0200     S2      
327m0181            R1254 -1   M      A18X+091116Y+129233X0180Y0200R180 S2      
327m0181            VIA   -    M      A18X+091972Y+129168X0260Y         S2      
327m0181            R1233 -2          A18X+093504Y+129015X0198Y0197     S2      
327m0181            R1222 -1   M      A18X+092293Y+129168X0198Y0197R180 S2      
327m0182            R1263 -2          A18X+090832Y+126683X0180Y0200R180 S2      
327m0182            VIA   -    M      A18X+088614Y+127084X0260Y         S2      
327m0182            C1093 -1   M      A18X+089801Y+126842X0198Y0197R180 S2      
327m0182            U51   -16         A18X+088665Y+127661X0140Y0630R270 S2      
327m0183            R1260 -2          A18X+091462Y+126683X0180Y0200     S2      
327m0183            VIA   -           A18X+100615Y+128349X0260Y         S2      
317m0183            VIA   -    MD0100PA00X+091711Y+126630X0200Y         S0      
317m0183            VIA   -    MD0100PA00X+097832Y+126313X0200Y         S0      
327m0183            U50   -5   M      A18X+099433Y+128069X0150Y0630R270 S2      
327m0183            C1085 -1   M      A18X+100534Y+127975X0198Y0197R180 S2      
327P5V_AUX_ADC      R1263 -1          A18X+091147Y+126683X0180Y0200R180 S2      
327P5V_AUX_ADC      R1260 -1   M      A18X+091147Y+126683X0180Y0200     S2      
327P5V_AUX_ADC      VIA   -    M      A18X+091969Y+126844X0260Y         S2      
327P5V_AUX_ADC      R1238 -2          A18X+093506Y+126564X0198Y0197     S2      
327P5V_AUX_ADC      R1226 -1   M      A18X+092278Y+126635X0198Y0197R180 S2      
327m0184            VIA   -           A18X+097439Y+129510X0260Y         S2      
327m0184            C1077 -1          A18X+096200Y+129200X0400Y0500R090 S2      
327m0184            C1075 -1          A18X+096750Y+129442X0198Y0197R270 S2      
327m0184            U50   -16         A18X+097342Y+129069X0150Y0630R270 S2      
327m0184            L24   -1          A18X+095590Y+129200X0280Y0320R090 S2      
327m0185            R1257 -2          A18X+090816Y+128378X0180Y0200R180 S2      
327m0185            VIA   -    M      A18X+089388Y+128632X0260Y         S2      
327m0185            U51   -12         A18X+088665Y+128685X0140Y0630R270 S2      
327m0185            C1091 -1   M      A18X+089797Y+128542X0198Y0197R180 S2      
327m0186            R1250 -2          A18X+091446Y+128378X0180Y0200     S2      
317m0186            VIA   -    MD0100PA00X+091734Y+128378X0200Y         S0      
317m0186            VIA   -    MD0100PA00X+096400Y+126700X0200Y         S0      
327m0186            VIA   -    M      A18X+096882Y+126700X0260Y         S2      
327m0186            U50   -9          A18X+097342Y+127319X0150Y0630R270 S2      
327m0186            C1083 -1          A18X+096108Y+126700X0198Y0197     S2      
327m0187            R1250 -1          A18X+091131Y+128378X0180Y0200     S2      
327m0187            R1257 -1   M      A18X+091131Y+128378X0180Y0200R180 S2      
327m0187            VIA   -    M      A18X+091913Y+128595X0260Y         S2      
327m0187            R1234 -2          A18X+093506Y+128212X0198Y0197     S2      
327m0187            R1223 -1   M      A18X+092286Y+128305X0198Y0197R180 S2      
327m0188            R1252 -2          A18X+090820Y+127945X0180Y0200R180 S2      
327m0188            C1087 -1   M      A18X+089793Y+128120X0198Y0197R180 S2      
327m0188            VIA   -    M      A18X+089388Y+128122X0260Y         S2      
327m0188            U51   -13         A18X+088665Y+128429X0140Y0630R270 S2      
327m0189            R1246 -2          A18X+091450Y+127945X0180Y0200     S2      
317m0189            VIA   -    M      A01X+098824Y+127319X0300Y         S1      
017m0189            VIA   -    M      A18X+098824Y+127319X0200Y         S1      
017m0189                  -    MD0100PA00X+098824Y+127319                       
317m0189            VIA   -    MD0100PA00X+091716Y+127945X0200Y         S0      
327m0189            U50   -8   M      A18X+099433Y+127319X0150Y0630R270 S2      
327m0189            C1079 -1          A18X+099429Y+126713X0198Y0197R180 S2      
327m0190            R1246 -1          A18X+091135Y+127945X0180Y0200     S2      
327m0190            R1252 -1   M      A18X+091135Y+127945X0180Y0200R180 S2      
327m0190            VIA   -    M      A18X+093128Y+127684X0260Y         S2      
327m0190            R1231 -2          A18X+093511Y+127806X0198Y0197     S2      
327m0190            R1220 -1   M      A18X+092301Y+127871X0198Y0197R180 S2      
327m0191            R1259 -2          A18X+090844Y+127102X0180Y0200R180 S2      
327m0191            VIA   -    M      A18X+089272Y+127052X0260Y         S2      
327m0191            U51   -15         A18X+088665Y+127917X0140Y0630R270 S2      
327m0191            C1092 -1   M      A18X+089805Y+127269X0198Y0197R180 S2      
327m0192            R1258 -2          A18X+091474Y+127102X0180Y0200     S2      
317m0192            VIA   -    M      A01X+098266Y+126547X0200Y         S2      
017m0192            VIA   -    M      A18X+098266Y+126547X0260Y         S2      
017m0192                  -    MD0100PA00X+098266Y+126547                       
317m0192            VIA   -    MD0100PA00X+091740Y+127102X0200Y         S0      
327m0192            U50   -6   M      A18X+099433Y+127819X0150Y0630R270 S2      
327m0192            C1084 -1          A18X+100526Y+127577X0198Y0197R180 S2      
327P1V8_AUX_ADC     R1259 -1          A18X+091159Y+127102X0180Y0200R180 S2      
327P1V8_AUX_ADC     R1258 -1   M      A18X+091159Y+127102X0180Y0200     S2      
327P1V8_AUX_ADC     VIA   -    M      A18X+093108Y+126850X0260Y         S2      
327P1V8_AUX_ADC     R1237 -2          A18X+093503Y+126973X0198Y0197     S2      
327P1V8_AUX_ADC     R1229 -1   M      A18X+092293Y+127041X0198Y0197R180 S2      
327m0193            R1251 -2          A18X+090817Y+127525X0180Y0200R180 S2      
327m0193            C1086 -1   M      A18X+089798Y+127697X0198Y0197R180 S2      
327m0193            VIA   -    M      A18X+089388Y+127612X0260Y         S2      
327m0193            U51   -14         A18X+088665Y+128173X0140Y0630R270 S2      
327m0194            R1245 -2          A18X+091447Y+127525X0180Y0200     S2      
327m0194            VIA   -    M      A18X+100206Y+127269X0260Y         S2      
317m0194            VIA   -    MD0100PA00X+091713Y+127525X0200Y         S0      
317m0194            VIA   -    MD0100PA00X+098540Y+126815X0200Y         S0      
327m0194            U50   -7   M      A18X+099433Y+127569X0150Y0630R270 S2      
327m0194            C1078 -1          A18X+100529Y+127174X0198Y0197R180 S2      
327P1V2_AUX_ADC     R1245 -1          A18X+091132Y+127525X0180Y0200     S2      
327P1V2_AUX_ADC     R1251 -1   M      A18X+091132Y+127525X0180Y0200R180 S2      
327P1V2_AUX_ADC     VIA   -    M      A18X+091972Y+127636X0260Y         S2      
327P1V2_AUX_ADC     R1232 -2          A18X+093513Y+127396X0198Y0197     S2      
327P1V2_AUX_ADC     R1221 -1   M      A18X+092288Y+127459X0198Y0197R180 S2      
327m0195            VIA   -           A18X+026793Y+005925X0260Y         S2      
327m0195            VIA   -           A18X+026800Y+006834X0260Y         S2      
317m0195            VIA   -    M      A01X+026536Y+004917X0200Y         S2      
017m0195            VIA   -    M      A18X+026536Y+004917X0260Y         S2      
017m0195                  -    MD0100PA00X+026536Y+004917                       
317m0195            VIA   -    M      A01X+025752Y+005156X0200Y         S2      
017m0195            VIA   -    M      A18X+025752Y+005156X0260Y         S2      
017m0195                  -    MD0100PA00X+025752Y+005156                       
317m0195            VIA   -    M      A01X+024882Y+004896X0200Y         S2      
017m0195            VIA   -    M      A18X+024882Y+004896X0260Y         S2      
017m0195                  -    MD0100PA00X+024882Y+004896                       
327m0195            C1829 -1          A01X+026017Y+006783X0400Y0500     S1      
327m0195            C1831 -1          A01X+025898Y+006240X0198Y0197R180 S1      
327m0195            R1325 -1          A01X+027041Y+006424X1150Y1380     S1      
327m0195            C1833 -1          A01X+025898Y+005840X0198Y0197R180 S1      
327m0195            C1832 -1          A01X+025898Y+005440X0198Y0197R180 S1      
327m0195            J35   -B1         A01X+025932Y+004437X0150Y0570R180 S1      
327m0195            J35   -B2         A01X+025696Y+004437X0150Y0570R180 S1      
327m0195            J35   -B3         A01X+025459Y+004437X0150Y0570R180 S1      
327m0195            J35   -B4         A01X+025223Y+004437X0150Y0570R180 S1      
327m0195            J35   -B5         A01X+024987Y+004437X0150Y0570R180 S1      
327m0195            J35   -B6         A01X+024751Y+004437X0150Y0570R180 S1      
327m0195            R1302 -1          A01X+027188Y+007454X0198Y0197     S1      
317m0195            VIA   -    MD0100PA00X+026986Y+007274X0200Y         S0      
327m0195            C1830 -1          A18X+026017Y+006783X0400Y0500R180 S2      
327m0195            C1834 -1          A18X+025898Y+006240X0198Y0197     S2      
317m0195            VIA   -    MD0100PA00X+026182Y+004896X0200Y         S0      
317m0195            VIA   -    MD0100PA00X+026352Y+005156X0200Y         S0      
327m0195            C1839 -1          A18X+025898Y+005840X0198Y0197     S2      
317m0195            VIA   -    MD0100PA00X+025052Y+005156X0200Y         S0      
317m0195            VIA   -    MD0100PA00X+025402Y+005156X0200Y         S0      
317m0195            VIA   -    MD0100PA00X+025582Y+004896X0200Y         S0      
317m0195            VIA   -    MD0100PA00X+025232Y+004896X0200Y         S0      
317m0195            VIA   -    MD0100PA00X+026102Y+005156X0200Y         S0      
317m0195            VIA   -    MD0100PA00X+025932Y+004896X0200Y         S0      
327m0196            R1166 -1          A01X+039392Y+030400X0198Y0197     S1      
327m0196            U33   -4          A01X+038232Y+030376X0220Y0530R270 S1      
327m0196            VIA   -    M      A01X+038900Y+030376X0300Y         S1      
317m0197            VIA   -    MD0100PA00X+041962Y+030800X0200Y         S0      
327m0197            R1166 -2          A01X+039708Y+030400X0198Y0197     S1      
327m0197            R1167 -2   M      A01X+040142Y+030400X0198Y0197R180 S1      
317m0197            VIA   -    M      A01X+062788Y+045531X0200Y         S2      
017m0197            VIA   -    M      A18X+062788Y+045531X0260Y         S2      
017m0197                  -    MD0100PA00X+062788Y+045531                       
327m0197            R407  -1          A18X+064310Y+046193X0198Y0197R180 S2      
327m0198            VIA   -    M      A01X+019758Y+016043X0300Y         S1      
327m0198            R1164 -2          A01X+019556Y+016532X0198Y0197R180 S1      
327m0198            R1165 -2   M      A01X+019758Y+015650X0198Y0197     S1      
327m0198            U31   -1          A01X+020278Y+015624X0220Y0320R270 S1      
317m0199            VIA   -    MD0100PA00X+030824Y+014810X0200Y         S0      
327m0199            R1521 -1   M      A01X+022543Y+014471X0198Y0197R180 S1      
327m0199            R1520 -1          A01X+022509Y+015340X0198Y0197R090 S1      
327m0199            R1168 -2   M      A01X+022543Y+014875X0198Y0197     S1      
317m0199            VIA   -    M      A01X+023328Y+013720X0200Y         S2      
017m0199            VIA   -    M      A18X+023328Y+013720X0260Y         S2      
017m0199                  -    MD0100PA00X+023328Y+013720                       
327m0199            R1181 -1   M      A01X+027018Y+013730X0198Y0197R180 S1      
327m0199            R1193 -1   M      A01X+027978Y+012714X0198Y0197R270 S1      
317m0199            VIA   -    MD0100PA00X+027018Y+014032X0200Y         S0      
317m0199            VIA   -    MD0100PA00X+049788Y+005132X0200Y         S0      
317m0199            VIA   -    MD0100PA00X+061742Y+011964X0200Y         S0      
327m0199            R1522 -2          A01X+060334Y+013227X0198Y0197     S1      
327m0200            VIA   -    M      A01X+021840Y+014876X0300Y         S1      
327m0200            R1168 -1          A01X+022228Y+014875X0198Y0197     S1      
327m0200            U31   -4          A01X+021222Y+014876X0220Y0320R270 S1      
327m0201            U56   -3          A01X+008594Y+015581X0090Y0240R270 S1      
327m0201            R1271 -1          A01X+007733Y+014919X0198Y0197R180 S1      
327m0201            VIA   -    M      A01X+008099Y+015119X0300Y         S1      
327m0202            VIA   -           A01X+080549Y+037316X0300Y         S1      
327m0202            U28   -4          A01X+079755Y+037745X0220Y0530R270 S1      
327m0202            R1132 -1   M      A01X+080549Y+037675X0198Y0197     S1      
317m0203            VIA   -    MD0100PA00X+082734Y+041534X0200Y    R180 S0      
327m0203            R6051 -2          A01X+082399Y+041534X0198Y0197     S1      
317m0203            VIA   -    M      A01X+081816Y+038102X0300Y         S1      
017m0203            VIA   -    M      A18X+081816Y+038102X0200Y         S1      
017m0203                  -    MD0100PA00X+081816Y+038102                       
327m0203            R1133 -2   M      A01X+080864Y+038102X0198Y0197     S1      
327m0203            R1132 -2          A01X+080864Y+037675X0198Y0197     S1      
327P12V_OCP_SFF_R   VIA   -           A18X+173988Y+004074X0260Y         S2      
327P12V_OCP_SFF_R   VIA   -           A18X+173174Y+004500X0260Y         S2      
327P12V_OCP_SFF_R   VIA   -           A18X+172460Y+004097X0260Y         S2      
327P12V_OCP_SFF_R   VIA   -           A18X+173949Y+004897X0260Y         S2      
317P12V_OCP_SFF_R   VIA   -    M      A01X+172324Y+004882X0200Y         S2      
017P12V_OCP_SFF_R   VIA   -    M      A18X+172324Y+004882X0260Y         S2      
017P12V_OCP_SFF_R         -    MD0100PA00X+172324Y+004882                       
327P12V_OCP_SFF_R   R1301 -1          A01X+173673Y+008534X0198Y0197     S1      
317P12V_OCP_SFF_R   VIA   -    MD0100PA00X+173762Y+008164X0200Y         S0      
317P12V_OCP_SFF_R   VIA   -    MD0100PA00X+173762Y+007914X0200Y         S0      
327P12V_OCP_SFF_R   R1324 -1          A01X+173037Y+007504X1150Y1380     S1      
327P12V_OCP_SFF_R   C27   -1          A01X+173544Y+005365X0198Y0197R180 S1      
327P12V_OCP_SFF_R   C1236 -1          A01X+173544Y+005765X0198Y0197R180 S1      
327P12V_OCP_SFF_R   C1213 -1          A01X+173710Y+006305X0400Y0500     S1      
327P12V_OCP_SFF_R   J38   -B1         A01X+173373Y+004437X0150Y0570R180 S1      
327P12V_OCP_SFF_R   J38   -B2         A01X+173137Y+004437X0150Y0570R180 S1      
327P12V_OCP_SFF_R   J38   -B3         A01X+172900Y+004437X0150Y0570R180 S1      
327P12V_OCP_SFF_R   J38   -B4         A01X+172664Y+004437X0150Y0570R180 S1      
327P12V_OCP_SFF_R   J38   -B5         A01X+172428Y+004437X0150Y0570R180 S1      
327P12V_OCP_SFF_R   J38   -B6         A01X+172192Y+004437X0150Y0570R180 S1      
317P12V_OCP_SFF_R   VIA   -    MD0100PA00X+173762Y+007314X0200Y         S0      
317P12V_OCP_SFF_R   VIA   -    MD0100PA00X+173762Y+007564X0200Y         S0      
317P12V_OCP_SFF_R   VIA   -    MD0100PA00X+173809Y+005560X0200Y         S0      
317P12V_OCP_SFF_R   VIA   -    MD0100PA00X+173809Y+005310X0200Y         S0      
327P12V_OCP_SFF_R   C1235 -1          A18X+173544Y+005365X0198Y0197     S2      
327P12V_OCP_SFF_R   C21   -1          A18X+173544Y+005765X0198Y0197     S2      
327P12V_OCP_SFF_R   C34   -1          A18X+173710Y+006305X0400Y0500R180 S2      
317P12V_OCP_SFF_R   VIA   -    MD0100PA00X+173024Y+004882X0200Y         S0      
317P12V_OCP_SFF_R   VIA   -    MD0100PA00X+172674Y+004882X0200Y         S0      
317P12V_OCP_SFF_R   VIA   -    MD0100PA00X+172990Y+005135X0200Y         S0      
317P12V_OCP_SFF_R   VIA   -    MD0100PA00X+172722Y+005142X0200Y         S0      
317P12V_OCP_SFF_R   VIA   -    MD0100PA00X+172468Y+005145X0200Y         S0      
317P12V_OCP_SFF_R   VIA   -    MD0100PA00X+173601Y+004434X0200Y         S0      
317P12V_OCP_SFF_R   VIA   -    MD0100PA00X+173601Y+004184X0200Y         S0      
327m0204            VIA   -    M      A01X+061542Y+042246X0300Y         S1      
327m0204            U23   -1          A01X+060922Y+041776X0220Y0320R090 S1      
327m0204            R1130 -2          A01X+061532Y+042690X0198Y0197R180 S1      
327m0204            R1131 -2   M      A01X+061542Y+041800X0198Y0197R180 S1      
317m0205            VIA   -    MD0100PA00X+162168Y+036692X0200Y         S0      
317m0205            VIA   -    MD0100PA00X+161502Y+018305X0200Y         S0      
317m0205            VIA   -    MD0100PA00X+178895Y+014275X0200Y         S0      
327m0205            R1486 -1          A01X+178413Y+015574X0198Y0197R090 S1      
327m0205            R1134 -2          A01X+059376Y+041863X0198Y0197R270 S1      
317m0205            VIA   -    M      A01X+059376Y+041585X0200Y         S2      
017m0205            VIA   -    M      A18X+059376Y+041585X0260Y         S2      
017m0205                  -    MD0100PA00X+059376Y+041585                       
327m0205            R561  -1          A01X+184784Y+017029X0198Y0197R180 S1      
327m0205            R591  -1          A01X+175732Y+012825X0198Y0197R270 S1      
317m0205            VIA   -    MD0100PA00X+185079Y+017029X0200Y         S0      
317m0205            VIA   -    MD0100PA00X+176012Y+012825X0200Y         S0      
327m0205            R1500 -2   M      A01X+162552Y+027852X0198Y0197     S1      
317m0205            VIA   -    MD0100PA00X+165004Y+043475X0200Y         S0      
327m0205            R1487 -1          A01X+165004Y+043162X0198Y0197R270 S1      
327m0206            R1134 -1          A01X+059376Y+042178X0198Y0197R270 S1      
327m0206            U23   -4          A01X+059978Y+042524X0220Y0320R090 S1      
327m0206            VIA   -    M      A01X+059425Y+042524X0300Y         S1      
327m0207            U55   -3          A01X+155070Y+029943X0090Y0240R270 S1      
327m0207            VIA   -    M      A01X+154556Y+029282X0300Y         S1      
327m0207            R1270 -1          A01X+154209Y+029282X0198Y0197R180 S1      
327P12V_E1S_0_R     VIA   -           A18X+096042Y+016229X0260Y         S2      
327P12V_E1S_0_R     VIA   -           A18X+096477Y+017305X0260Y         S2      
327P12V_E1S_0_R     VIA   -           A18X+095280Y+016594X0260Y         S2      
327P12V_E1S_0_R     VIA   -           A18X+095216Y+017459X0260Y         S2      
327P12V_E1S_0_R     R1292 -1          A01X+095805Y+019817X0198Y0197     S1      
327P12V_E1S_0_R     R1323 -1          A01X+095369Y+018787X1150Y1380     S1      
327P12V_E1S_0_R     C1279 -1          A01X+096544Y+016796X0198Y0197R270 S1      
327P12V_E1S_0_R     C1278 -1          A01X+096544Y+017181X0198Y0197R090 S1      
317P12V_E1S_0_R     VIA   -    MD0100PA00X+096267Y+016776X0200Y         S0      
317P12V_E1S_0_R     VIA   -    MD0100PA00X+096267Y+017026X0200Y         S0      
327P12V_E1S_0_R     C1276 -1          A01X+095845Y+016910X0400Y0500R090 S1      
327P12V_E1S_0_R     C1277 -1          A01X+095344Y+017592X0400Y0500R180 S1      
317P12V_E1S_0_R     VIA   -    MD0100PA00X+094840Y+017650X0200Y         S0      
317P12V_E1S_0_R     VIA   -    MD0100PA00X+094072Y+017639X0200Y         S0      
317P12V_E1S_0_R     VIA   -    MD0100PA00X+094072Y+017339X0200Y         S0      
317P12V_E1S_0_R     VIA   -    MD0100PA00X+093559Y+017605X0200Y         S0      
317P12V_E1S_0_R     VIA   -    MD0100PA00X+093816Y+017639X0200Y         S0      
317P12V_E1S_0_R     VIA   -    MD0100PA00X+093816Y+017339X0200Y         S0      
317P12V_E1S_0_R     VIA   -    MD0100PA00X+093555Y+017333X0200Y         S0      
317P12V_E1S_0_R     VIA   -    MD0100PA00X+094572Y+017639X0200Y         S0      
317P12V_E1S_0_R     VIA   -    MD0100PA00X+094322Y+017639X0200Y         S0      
317P12V_E1S_0_R     VIA   -    MD0100PA00X+094322Y+017339X0200Y         S0      
317P12V_E1S_0_R     VIA   -    MD0100PA00X+094572Y+017339X0200Y         S0      
327P12V_E1S_0_R     J90   -B1         A01X+093150Y+016758X0150Y0500R090 S1      
327P12V_E1S_0_R     J90   -B2         A01X+093150Y+016994X0150Y0500R090 S1      
327P12V_E1S_0_R     J90   -B3         A01X+093150Y+017230X0150Y0500R090 S1      
327P12V_E1S_0_R     J90   -B4         A01X+093150Y+017466X0150Y0500R090 S1      
327P12V_E1S_0_R     J90   -B5         A01X+093150Y+017703X0150Y0500R090 S1      
327P12V_E1S_0_R     J90   -B6         A01X+093150Y+017939X0150Y0500R090 S1      
327m0208            R1269 -1          A01X+126578Y+039912X0198Y0197R180 S1      
327m0208            VIA   -    M      A01X+126926Y+039912X0300Y         S1      
327m0208            U52   -3          A01X+127439Y+040574X0090Y0240R270 S1      
327m0209            VIA   -    M      A01X+031964Y+027400X0300Y         S1      
327m0209            R1169 -2          A01X+031460Y+027417X0198Y0197R090 S1      
327m0209            U34   -2          A01X+032618Y+027400X0220Y0530R270 S1      
317m0210            VIA   -    MD0100PA00X+042695Y+032075X0200Y         S0      
327m0210            R1170 -2          A01X+034615Y+027346X0198Y0197R090 S1      
327m0210            R1171 -2   M      A01X+034200Y+027742X0198Y0197R270 S1      
317m0210            VIA   -    M      A01X+068049Y+050478X0200Y         S2      
017m0210            VIA   -    M      A18X+068049Y+050478X0260Y         S2      
017m0210                  -    MD0100PA00X+068049Y+050478                       
317m0210            VIA   -    MD0100PA00X+071154Y+046552X0180Y    R090 S0      
327m0210            U18   -F15        A01X+071308Y+046399X0160Y    R090 S1      
327m0211            VIA   -    M      A01X+034219Y+027026X0300Y         S1      
327m0211            R1170 -1          A01X+034615Y+027031X0198Y0197R090 S1      
327m0211            U34   -4          A01X+033582Y+027026X0220Y0530R270 S1      
327m0212            VIA   -    M      A01X+028381Y+021587X0300Y         S1      
327m0212            R1147 -1          A01X+027308Y+021100X0198Y0197R180 S1      
327m0212            R1146 -1   M      A01X+028008Y+021500X0198Y0197R180 S1      
327m0212            R1175 -1   M      A01X+027692Y+021100X0198Y0197     S1      
327m0212            U37   -4          A01X+027850Y+022044X0400Y0150     S1      
327m0213            VIA   -    M      A01X+065933Y+036357X0300Y         S1      
327m0213            U30   -2          A01X+065900Y+037068X0220Y0530     S1      
327m0213            R1142 -2          A01X+066465Y+036326X0198Y0197R180 S1      
317m0214            VIA   -    M      A01X+065295Y+039428X0200Y         S2      
017m0214            VIA   -    M      A18X+065295Y+039428X0260Y         S2      
017m0214                  -    MD0100PA00X+065295Y+039428                       
317m0214            VIA   -    MD0100PA00X+067000Y+044636X0200Y    R270 S0      
327m0214            U18   -A9         A01X+069733Y+044509X0160Y    R090 S1      
327m0214            R1143 -2          A01X+065942Y+039000X0198Y0197R180 S1      
327m0214            R1144 -2   M      A01X+065558Y+039000X0198Y0197     S1      
327m0215            VIA   -           A01X+064989Y+039572X0300Y         S1      
327m0215            U30   -4          A01X+066274Y+038032X0220Y0530     S1      
327m0215            R1143 -1   M      A01X+066258Y+039000X0198Y0197R180 S1      
327m0216            VIA   -    M      A01X+084342Y+038489X0300Y         S1      
327m0216            R9030 -1          A01X+083900Y+038592X0198Y0197R090 S1      
327m0216            R9031 -1   M      A01X+085158Y+038500X0198Y0197R180 S1      
327m0216            U9002 -4          A01X+085250Y+039044X0400Y0150     S1      
327m0216            R9029 -1   M      A01X+085615Y+038403X0198Y0197     S1      
327m0217            VIA   -           A01X+127282Y+041630X0300Y         S1      
327m0217            U52   -16         A01X+127695Y+041224X0090Y0240     S1      
327m0218            VIA   -           A01X+127774Y+041724X0300Y         S1      
327m0218            U52   -15         A01X+127892Y+041224X0090Y0240     S1      
327m0219            VIA   -           A01X+128089Y+042114X0300Y         S1      
327m0219            U52   -14         A01X+128089Y+041224X0090Y0240     S1      
327m0220            VIA   -           A01X+128734Y+039728X0300Y         S1      
327m0220            U52   -8          A01X+128286Y+040121X0090Y0240     S1      
327m0221            VIA   -           A01X+128246Y+039618X0300Y         S1      
327m0221            U52   -7          A01X+128089Y+040121X0090Y0240     S1      
327m0222            VIA   -           A01X+127746Y+039616X0300Y         S1      
327m0222            U52   -6          A01X+127892Y+040121X0090Y0240     S1      
327m0223            VIA   -           A01X+008438Y+016636X0300Y         S1      
327m0223            U56   -16         A01X+008850Y+016230X0090Y0240     S1      
327m0224            U56   -15         A01X+009047Y+016230X0090Y0240     S1      
327m0224            VIA   -           A01X+008929Y+016731X0300Y         S1      
327m0225            U56   -14         A01X+009244Y+016230X0090Y0240     S1      
327m0225            VIA   -           A01X+009429Y+016728X0300Y         S1      
327m0226            VIA   -           A01X+009889Y+014734X0300Y         S1      
327m0226            U56   -8          A01X+009441Y+015128X0090Y0240     S1      
327m0227            VIA   -           A01X+009401Y+014625X0300Y         S1      
327m0227            U56   -7          A01X+009244Y+015128X0090Y0240     S1      
327m0228            U56   -6          A01X+009047Y+015128X0090Y0240     S1      
327m0228            VIA   -           A01X+008901Y+014623X0300Y         S1      
327m0229            VIA   -           A01X+154820Y+031121X0300Y         S1      
327m0229            U55   -16         A01X+155326Y+030593X0090Y0240     S1      
327m0230            VIA   -           A01X+155365Y+031098X0300Y         S1      
327m0230            U55   -15         A01X+155523Y+030593X0090Y0240     S1      
327m0231            VIA   -           A01X+155905Y+031090X0300Y         S1      
327m0231            U55   -14         A01X+155720Y+030593X0090Y0240     S1      
327m0232            VIA   -           A01X+156366Y+029097X0300Y         S1      
327m0232            U55   -8          A01X+155917Y+029490X0090Y0240     S1      
327m0233            VIA   -           A01X+155877Y+028988X0300Y         S1      
327m0233            U55   -7          A01X+155720Y+029490X0090Y0240     S1      
327m0234            VIA   -           A01X+155377Y+028986X0300Y         S1      
327m0234            U55   -6          A01X+155523Y+029490X0090Y0240     S1      
327m0235            VIA   -    M      A18X+100448Y+129427X0260Y         S2      
327m0235            U50   -1          A18X+099433Y+129069X0150Y0630R270 S2      
327m0235            R1230 -2          A18X+100800Y+129427X0198Y0197     S2      
327m0236            VIA   -           A18X+101467Y+129427X0260Y         S2      
327m0236            C1076 -1          A18X+101114Y+128479X0400Y0500     S2      
327m0236            R1230 -1   M      A18X+101115Y+129427X0198Y0197     S2      
327m0236            C1074 -1   M      A18X+101115Y+129010X0198Y0197R180 S2      
327INA230_8_A1      R1350 -1          A01X+126242Y+039050X0198Y0197     S1      
317INA230_8_A1      VIA   -    MD0100PA00X+125966Y+038946X0200Y         S0      
317INA230_8_A1      VIA   -    M      A01X+126984Y+041113X0200Y         S2      
017INA230_8_A1      VIA   -    M      A18X+126984Y+041113X0260Y         S2      
017INA230_8_A1            -    MD0100PA00X+126984Y+041113                       
327INA230_8_A1      R1317 -2          A01X+126578Y+041512X0198Y0197     S1      
327INA230_8_A1      R1305 -2   M      A01X+126578Y+041112X0198Y0197     S1      
327INA230_8_A1      U52   -1          A01X+127439Y+040968X0090Y0240R270 S1      
327INA230_8_A0      R1308 -2          A01X+126578Y+040712X0198Y0197     S1      
327INA230_8_A0      VIA   -    M      A01X+126923Y+040786X0300Y         S1      
327INA230_8_A0      U52   -2          A01X+127439Y+040771X0090Y0240R270 S1      
327INA230_7_A1      R1322 -2          A01X+007733Y+016519X0198Y0197     S1      
327INA230_7_A1      R1307 -2   M      A01X+007733Y+016119X0198Y0197     S1      
327INA230_7_A1      U56   -1          A01X+008594Y+015974X0090Y0240R270 S1      
327INA230_7_A1      VIA   -    M      A01X+008096Y+016119X0300Y         S1      
327INA230_7_A0      R1360 -1          A01X+007733Y+015319X0198Y0197R180 S1      
327INA230_7_A0      R1310 -2   M      A01X+007733Y+015719X0198Y0197     S1      
327INA230_7_A0      U56   -2          A01X+008594Y+015778X0090Y0240R270 S1      
327INA230_7_A0      VIA   -    M      A01X+008098Y+015619X0300Y         S1      
327INA230_6_A1      U55   -1          A01X+155070Y+030337X0090Y0240R270 S1      
327INA230_6_A1      R1320 -2          A01X+154209Y+030882X0198Y0197     S1      
327INA230_6_A1      VIA   -    M      A01X+154519Y+030685X0300Y         S1      
327INA230_6_A1      R1306 -2   M      A01X+154209Y+030482X0198Y0197     S1      
327INA230_6_A0      R1355 -1          A01X+154209Y+029682X0198Y0197R180 S1      
327INA230_6_A0      U55   -2          A01X+155070Y+030140X0090Y0240R270 S1      
327INA230_6_A0      VIA   -    M      A01X+154575Y+030140X0300Y         S1      
327INA230_6_A0      R1309 -2   M      A01X+154209Y+030082X0198Y0197     S1      
327m0237            VIA   -           A01X+026482Y+022795X0300Y         S1      
327m0237            R1178 -2   M      A01X+027308Y+021500X0198Y0197     S1      
327m0237            R1146 -2          A01X+027692Y+021500X0198Y0197R180 S1      
327m0237            U37   -1   M      A01X+027150Y+022556X0400Y0150     S1      
327m0238            VIA   -    M      A01X+028700Y+024307X0300Y         S1      
327m0238            R1173 -2          A01X+028895Y+024634X0198Y0197R270 S1      
327m0238            U35   -2          A01X+028900Y+023722X0220Y0320R180 S1      
327m0239            U32   -G          A01X+017817Y+015474X0400Y0560R270 S1      
317m0239            VIA   -    MD0100PA00X+018102Y+015912X0200Y         S0      
327m0239            R1191 -2          A01X+006280Y+026822X0198Y0197     S1      
327m0239            R1192 -2   M      A01X+006665Y+026822X0198Y0197R180 S1      
317m0239            VIA   -    M      A01X+006665Y+026532X0200Y         S2      
017m0239            VIA   -    M      A18X+006665Y+026532X0260Y         S2      
017m0239                  -    MD0100PA00X+006665Y+026532                       
327m0240            VIA   -    M      A01X+019738Y+015250X0300Y         S1      
327m0240            R1149 -2   M      A01X+019708Y+014900X0198Y0197     S1      
327m0240            U32   -D          A01X+018683Y+015100X0400Y0560R270 S1      
327m0240            U31   -2          A01X+020278Y+015250X0220Y0320R270 S1      
327m0241            R1163 -2          A01X+036108Y+030750X0198Y0197     S1      
327m0241            U33   -2          A01X+037268Y+030750X0220Y0530R270 S1      
327m0241            VIA   -    M      A01X+036600Y+030750X0300Y         S1      
327m0242            VIA   -    M      A01X+085908Y+038774X0300Y         S1      
327m0242            U9002 -1          A01X+084550Y+039556X0400Y0150     S1      
327m0242            R9034 -2   M      A01X+085892Y+039150X0198Y0197R180 S1      
327m0242            R9029 -2          A01X+085930Y+038403X0198Y0197     S1      
327m0243            R9022 -2          A01X+084850Y+045808X0198Y0197R090 S1      
327m0243            U9001 -2          A01X+084850Y+046728X0220Y0320     S1      
327m0243            VIA   -    M      A01X+084850Y+046150X0300Y         S1      
327m0244            VIA   -           A01X+077251Y+037449X0300Y         S1      
327m0244            R1129 -2   M      A01X+078146Y+038119X0198Y0197R090 S1      
327m0244            U28   -2          A01X+078790Y+038119X0220Y0530R270 S1      
327m0245            U24   -G          A01X+060817Y+045474X0400Y0560R270 S1      
317m0245            VIA   -    MD0100PA00X+060577Y+044259X0200Y         S0      
317m0245            VIA   -    MD0100PA00X+065992Y+032650X0200Y         S0      
327m0245            R576  -2          A01X+181887Y+043168X0198Y0197     S1      
327m0245            R577  -2   M      A01X+182272Y+043168X0198Y0197R180 S1      
317m0245            VIA   -    M      A01X+182239Y+043622X0200Y         S2      
017m0245            VIA   -    M      A18X+182239Y+043622X0260Y         S2      
017m0245                  -    MD0100PA00X+182239Y+043622                       
327m0246            VIA   -    M      A01X+061700Y+043563X0300Y         S1      
327m0246            U23   -2          A01X+060922Y+042150X0220Y0320R090 S1      
327m0246            R1128 -2   M      A01X+061950Y+044208X0198Y0197R090 S1      
327m0246            U24   -D          A01X+061683Y+045100X0400Y0560R270 S1      
327m0247            VIA   -    M      A18X+165398Y+168705X0260Y         S2      
327m0247            U47   -9          A18X+165852Y+168313X0120Y0210R270 S2      
327m0247            R1209 -2          A18X+165065Y+168773X0120Y0150     S2      
327m0248            VIA   -    M      A01X+148161Y+167511X0300Y         S1      
327m0248            R1206 -2          A01X+148245Y+167850X0120Y0150     S1      
327m0248            U46   -9          A01X+147591Y+167688X0120Y0210     S1      
327m0249            VIA   -    M      A01X+113760Y+156163X0300Y         S1      
327m0249            U48   -9          A01X+114228Y+155855X0120Y0210R180 S1      
327m0249            R1210 -2          A01X+113833Y+156530X0120Y0150R090 S1      
327m0250            VIA   -    M      A18X+116725Y+168084X0260Y         S2      
327m0250            R1211 -2          A18X+116405Y+168200X0120Y0150     S2      
327m0250            U49   -9          A18X+117293Y+167732X0120Y0210R270 S2      
327m0251            VIA   -    M      A18X+063752Y+164201X0260Y         S2      
327m0251            U43   -9          A18X+063285Y+164077X0120Y0210R090 S2      
327m0251            R1200 -2          A18X+064235Y+164290X0120Y0150R180 S2      
327m0252            R1198 -2          A18X+067083Y+167449X0120Y0150R090 S2      
327m0252            VIA   -    M      A18X+066788Y+167696X0260Y         S2      
327m0252            U41   -9          A18X+066613Y+167227X0120Y0210R180 S2      
327m0253            VIA   -    M      A01X+044696Y+157653X0300Y         S1      
327m0253            U42   -9          A01X+045177Y+157718X0120Y0210R270 S1      
327m0253            R1199 -2          A01X+044767Y+157984X0120Y0150R180 S1      
327m0254            R1201 -2          A01X+039501Y+158524X0120Y0150R090 S1      
327m0254            VIA   -    M      A01X+039160Y+158717X0300Y         S1      
327m0254            U45   -9          A01X+038532Y+158717X0120Y0210R090 S1      
317m0255            VIA   -    M      A01X+079230Y+035754X0200Y         S2      
017m0255            VIA   -    M      A18X+079230Y+035754X0260Y         S2      
017m0255                  -    MD0100PA00X+079230Y+035754                       
327m0255            R958  -1          A18X+073150Y+039329X0198Y0197R270 S2      
327m0255            R9030 -2   M      A01X+083900Y+038908X0198Y0197R090 S1      
327m0255            U9002 -2          A01X+084550Y+039300X0400Y0150     S1      
327m0255            R9032 -2   M      A01X+083908Y+039300X0198Y0197     S1      
327m0256            VIA   -    M      A01X+026508Y+021308X0300Y         S1      
327m0256            R1179 -1   M      A01X+026508Y+021750X0198Y0197R180 S1      
327m0256            R1176 -2   M      A01X+026508Y+022150X0198Y0197     S1      
327m0256            R1147 -2          A01X+026992Y+021100X0198Y0197R180 S1      
327m0256            U37   -2          A01X+027150Y+022300X0400Y0150     S1      
317m0257            VIA   -    MD0100PA00X+070210Y+047497X0180Y    R090 S0      
317m0257            VIA   -    M      A01X+055573Y+047997X0200Y         S2      
017m0257            VIA   -    M      A18X+055573Y+047997X0260Y         S2      
017m0257                  -    MD0100PA00X+055573Y+047997                       
317m0257            VIA   -    MD0100PA00X+053705Y+021196X0200Y         S0      
327m0257            U18   -C18        A01X+070363Y+047344X0160Y    R090 S1      
317m0257            VIA   -    MD0100PA00X+033824Y+019226X0200Y         S0      
327m0257            R1179 -2          A01X+026192Y+021750X0198Y0197R180 S1      
317m0257            VIA   -    MD0100PA00X+029281Y+021324X0200Y         S0      
327ADC128_2_VREF    R1267 -2          A18X+084932Y+128744X0198Y0197     S2      
317ADC128_2_VREF    VIA   -    MD0100PA00X+084580Y+128778X0200Y         S0      
317ADC128_2_VREF    VIA   -    M      A01X+084425Y+126676X0200Y         S2      
017ADC128_2_VREF    VIA   -    M      A18X+084425Y+126676X0260Y         S2      
017ADC128_2_VREF          -    MD0100PA00X+084425Y+126676                       
327ADC128_2_VREF    U51   -1          A18X+086460Y+127661X0140Y0630R270 S2      
327ADC128_2_VREF    R1268 -1   M      A18X+085232Y+126978X0198Y0197     S2      
327ADC128_2_A1      R1240 -1          A18X+084258Y+129607X0198Y0197     S2      
327ADC128_2_A1      VIA   -    M      A18X+085668Y+129723X0260Y         S2      
327ADC128_2_A1      U51   -8          A18X+086460Y+129452X0140Y0630R270 S2      
327ADC128_2_A1      R1239 -2   M      A18X+085250Y+129598X0198Y0197R180 S2      
327ADC128_2_A0      R1242 -1          A18X+084259Y+129177X0198Y0197     S2      
327ADC128_2_A0      VIA   -    M      A18X+085698Y+129173X0260Y         S2      
327ADC128_2_A0      R1241 -2   M      A18X+085253Y+129147X0198Y0197R180 S2      
327ADC128_2_A0      U51   -7          A18X+086460Y+129197X0140Y0630R270 S2      
327m0258            R9027 -2   M      A01X+064692Y+042250X0198Y0197R180 S1      
327m0258            R9028 -2   M      A01X+064250Y+042208X0198Y0197R090 S1      
327m0258            C9005 -1   M      A01X+063800Y+042242X0198Y0197R090 S1      
317m0258            VIA   -    M      A01X+065276Y+042787X0200Y         S2      
017m0258            VIA   -    M      A18X+065276Y+042787X0260Y         S2      
017m0258                  -    MD0100PA00X+065276Y+042787                       
327m0258            R6095 -2          A01X+067242Y+043386X0198Y0197R180 S1      
327m0258            Q9003 -3          A01X+063224Y+042156X0170Y0200R270 S1      
327IRQ_HSC_FAULT    R9026 -2          A01X+062792Y+042700X0198Y0197R180 S1      
317IRQ_HSC_FAULT    VIA   -    M      A01X+062792Y+042197X0200Y         S2      
017IRQ_HSC_FAULT    VIA   -    M      A18X+062792Y+042197X0260Y         S2      
017IRQ_HSC_FAULT          -    MD0100PA00X+062792Y+042197                       
327IRQ_HSC_FAULT    Q9003 -5          A01X+062476Y+041900X0170Y0200R270 S1      
327IRQ_HSC_FAULT    Q9003 -6          A01X+062476Y+041644X0170Y0200R270 S1      
327m0259            R9044 -2          A01X+172463Y+170826X0198Y0197R090 S1      
317m0259            VIA   -    M      A01X+173225Y+170826X0200Y         S2      
017m0259            VIA   -    M      A18X+173225Y+170826X0260Y         S2      
017m0259                  -    MD0100PA00X+173225Y+170826                       
317m0259            J105  -A3   D0142PA00X+158563Y+173421X0302Y    R180 S3      
327m0259            Q106  -3          A01X+173714Y+170826X0170Y0200R090 S1      
327m0259            R3472 -2   M      A01X+172863Y+170826X0198Y0197R090 S1      
327m0260            R6073 -1          A01X+074750Y+037679X0198Y0197R090 S1      
317m0260            VIA   -    MD0100PA00X+082506Y+076488X0200Y         S0      
317m0260            VIA   -    MD0100PA00X+065258Y+049796X0200Y         S0      
317m0260            VIA   -    MD0100PA00X+075017Y+067583X0200Y         S0      
317m0260            VIA   -    MD0100PA00X+074750Y+037436X0200Y         S0      
317m0260            VIA   -    M      A01X+075219Y+169106X0200Y         S2      
017m0260            VIA   -    M      A18X+075219Y+169106X0260Y         S2      
017m0260                  -    MD0100PA00X+075219Y+169106                       
327m0260            R2793 -1          A01X+075709Y+169337X0198Y0197     S1      
327m0261            R2950 -2          A01X+075219Y+168857X0198Y0197R090 S1      
327m0261            U190  -G          A01X+076504Y+168777X0320Y0360R180 S1      
327m0261            R2793 -2   M      A01X+076024Y+169337X0198Y0197     S1      
317m0261            VIA   -    M      A01X+076846Y+168777X0200Y         S2      
017m0261            VIA   -    M      A18X+076846Y+168777X0260Y         S2      
017m0261                  -    MD0100PA00X+076846Y+168777                       
327m0262            R6863 -2          A01X+040758Y+163122X0198Y0197     S1      
327m0262            U10   -6          A01X+041534Y+162208X0100Y0220R180 S1      
327m0262            VIA   -    M      A01X+041234Y+162847X0300Y         S1      
327m0263            R6862 -2          A01X+040297Y+162590X0198Y0197R090 S1      
327m0263            U10   -7          A01X+041337Y+162208X0100Y0220R180 S1      
327m0263            VIA   -    M      A01X+040768Y+162648X0300Y         S1      
327m0264            VIA   -    M      A01X+111117Y+164333X0300Y         S1      
327m0264            R6865 -2          A01X+110260Y+163440X0198Y0197     S1      
327m0264            U314  -6          A01X+111617Y+164399X0100Y0220R270 S1      
327m0265            VIA   -    M      A01X+110777Y+163595X0300Y         S1      
327m0265            U314  -7          A01X+111617Y+164202X0100Y0220R270 S1      
327m0265            R6864 -2          A01X+110279Y+163012X0198Y0197     S1      
317m0266            VIA   -    M      A01X+069702Y+053758X0200Y         S2      
017m0266            VIA   -    M      A18X+069702Y+053758X0260Y         S2      
017m0266                  -    MD0100PA00X+069702Y+053758                       
327m0266            R6853 -2          A01X+069628Y+054071X0198Y0197R270 S1      
327m0266            U18   -E20        A01X+070993Y+047974X0160Y    R090 S1      
317m0266            VIA   -    MD0100PA00X+070840Y+048127X0180Y    R090 S0      
327m0267            R6852 -2          A18X+069108Y+049700X0198Y0197R180 S2      
327m0267            U18   -D19        A01X+070678Y+047659X0160Y    R090 S1      
317m0267            VIA   -    MD0100PA00X+070524Y+047812X0180Y    R090 S0      
327m0267            VIA   -    M      A18X+069390Y+049210X0260Y         S2      
327m0268            R6851 -2          A01X+066986Y+050490X0198Y0197     S1      
327m0268            U18   -A20        A01X+069733Y+047974X0160Y    R090 S1      
327m0268            VIA   -    M      A01X+068123Y+048842X0300Y         S1      
327m0269            R6850 -2          A01X+067786Y+050490X0198Y0197     S1      
327m0269            U18   -B15        A01X+070048Y+046399X0160Y    R090 S1      
317m0269            VIA   -    MD0100PA00X+069895Y+046552X0180Y    R090 S0      
317m0269            VIA   -    MD0100PA00X+068292Y+050057X0200Y    R270 S0      
327m0269            VIA   -    M      A18X+070164Y+048440X0260Y    R090 S2      
327m0270            R6855 -1          A01X+076870Y+054042X0198Y0197R090 S1      
327m0270            U18   -AA21       A01X+076032Y+048288X0160Y    R090 S1      
327m0270            VIA   -    M      A01X+077080Y+053564X0300Y         S1      
327m0271            R6854 -2          A18X+077392Y+044250X0198Y0197     S2      
327m0271            U18   -AA10       A01X+076032Y+044824X0160Y    R090 S1      
327m0271            VIA   -    M      A18X+076539Y+044399X0260Y         S2      
317m0271            VIA   -    MD0100PA00X+076186Y+044670X0180Y         S0      
317U17_E2           VIA   -    M      A01X+148888Y+167738X0200Y         S2      
017U17_E2           VIA   -    M      A18X+148888Y+167738X0260Y         S2      
017U17_E2                 -    MD0100PA00X+148888Y+167738                       
327U17_E2           R1127 -1          A01X+148268Y+166892X0120Y0150R180 S1      
327U17_E2           U17   -3          A18X+148258Y+166885X0350Y0500R090 S2      
317U16_E2           VIA   -    M      A01X+165610Y+170109X0200Y         S2      
017U16_E2           VIA   -    M      A18X+165610Y+170109X0260Y         S2      
017U16_E2                 -    MD0100PA00X+165610Y+170109                       
327U16_E2           R1085 -1          A01X+165609Y+170424X0120Y0150     S1      
327U16_E2           U16   -3          A01X+165610Y+169640X0350Y0500R180 S1      
327U15_E2           U15   -3          A01X+113307Y+158445X0350Y0500R270 S1      
317U15_E2           VIA   -    M      A01X+113848Y+157636X0200Y         S2      
017U15_E2           VIA   -    M      A18X+113848Y+157636X0260Y         S2      
017U15_E2                 -    MD0100PA00X+113848Y+157636                       
327U15_E2           R1044 -1          A01X+113848Y+157410X0120Y0150R270 S1      
327U11_E2           VIA   -    M      A01X+118166Y+169083X0300Y         S1      
327U11_E2           U11   -3          A01X+117419Y+168263X0350Y0500R180 S1      
327U11_E2           R6822 -1          A01X+118568Y+169298X0120Y0150R090 S1      
327m0272            VIA   -           A01X+143321Y+154731X0300Y         S1      
327m0272            R1119 -2   M      A01X+143744Y+154380X0120Y0150R180 S1      
327m0272            R1120 -1   M      A01X+144134Y+154380X0120Y0150     S1      
327m0272            U6013 -FF30       A01X+145355Y+154926X0120Y         S1      
327m0273            VIA   -           A01X+156127Y+154731X0300Y         S1      
327m0273            R1077 -2   M      A01X+156550Y+154380X0120Y0150R180 S1      
327m0273            R1078 -1   M      A01X+156940Y+154380X0120Y0150     S1      
327m0273            U6012 -FF30       A01X+158161Y+154926X0120Y         S1      
327m0274            VIA   -           A01X+129710Y+154731X0300Y         S1      
327m0274            R1034 -2   M      A01X+130132Y+154380X0120Y0150R180 S1      
327m0274            R1035 -1   M      A01X+130522Y+154380X0120Y0150     S1      
327m0274            U6011 -FF30       A01X+131744Y+154926X0120Y         S1      
327m0275            VIA   -           A01X+116904Y+154731X0300Y         S1      
327m0275            U6010 -FF30       A01X+118938Y+154926X0120Y         S1      
327m0275            R995  -1   M      A01X+117716Y+154380X0120Y0150     S1      
327m0275            R985  -2   M      A01X+117326Y+154380X0120Y0150R180 S1      
317m0276            VIA   -    MD0080PA00X+144913Y+155112X0160Y         S0      
327m0276            R1116 -2          A18X+143844Y+154742X0120Y0150     S2      
327m0276            R1118 -1   M      A18X+144134Y+154742X0120Y0150R180 S2      
327m0276            VIA   -    M      A18X+144913Y+154830X0260Y         S2      
327m0276            U6013 -FF27       A01X+145355Y+155163X0120Y         S1      
317m0277            VIA   -    MD0080PA00X+157720Y+155112X0160Y         S0      
327m0277            VIA   -    M      A18X+157720Y+154830X0260Y         S2      
327m0277            R1075 -2          A18X+156650Y+154742X0120Y0150     S2      
327m0277            R1076 -1   M      A18X+156940Y+154742X0120Y0150R180 S2      
327m0277            U6012 -FF27       A01X+158161Y+155163X0120Y         S1      
317m0278            VIA   -    MD0080PA00X+131302Y+155112X0160Y         S0      
327m0278            R1032 -2          A18X+130232Y+154742X0120Y0150     S2      
327m0278            R1033 -1   M      A18X+130522Y+154742X0120Y0150R180 S2      
327m0278            VIA   -    M      A18X+131302Y+154830X0260Y         S2      
327m0278            U6011 -FF27       A01X+131744Y+155163X0120Y         S1      
317m0279            VIA   -    MD0080PA00X+118496Y+155112X0160Y         S0      
327m0279            VIA   -    M      A18X+118414Y+154852X0260Y         S2      
327m0279            R983  -2   M      A18X+117926Y+154914X0120Y0150     S2      
327m0279            R984  -1          A18X+117716Y+154594X0120Y0150R180 S2      
327m0279            U6010 -FF27       A01X+118938Y+155163X0120Y         S1      
317m0280            VIA   -    MD0080PA00X+144953Y+155461X0160Y         S0      
327m0280            VIA   -    M      A18X+144735Y+155319X0260Y         S2      
327m0280            R1114 -2          A18X+143844Y+155104X0120Y0150     S2      
327m0280            R1115 -1   M      A18X+144134Y+155104X0120Y0150R180 S2      
327m0280            U6013 -FF24       A01X+145355Y+155399X0120Y         S1      
317m0281            VIA   -    MD0080PA00X+157760Y+155461X0160Y         S0      
327m0281            VIA   -    M      A18X+157542Y+155319X0260Y         S2      
327m0281            R1073 -2          A18X+156650Y+155104X0120Y0150     S2      
327m0281            R1074 -1   M      A18X+156940Y+155104X0120Y0150R180 S2      
327m0281            U6012 -FF24       A01X+158161Y+155399X0120Y         S1      
317m0282            VIA   -    MD0080PA00X+131342Y+155461X0160Y         S0      
327m0282            VIA   -    M      A18X+131124Y+155319X0260Y         S2      
327m0282            R1030 -2          A18X+130232Y+155104X0120Y0150     S2      
327m0282            R1031 -1   M      A18X+130522Y+155104X0120Y0150R180 S2      
327m0282            U6011 -FF24       A01X+131744Y+155399X0120Y         S1      
317m0283            VIA   -    MD0080PA00X+118536Y+155461X0160Y         S0      
327m0283            VIA   -    M      A18X+118250Y+155554X0260Y         S2      
327m0283            R981  -2   M      A18X+117926Y+155554X0120Y0150     S2      
327m0283            R982  -1          A18X+117716Y+155234X0120Y0150R180 S2      
327m0283            U6010 -FF24       A01X+118938Y+155399X0120Y         S1      
317m0284            VIA   -    MD0080PA00X+153882Y+154934X0160Y         S0      
327m0284            R1110 -2          A18X+091905Y+132800X0120Y0150     S2      
327m0284            U6013 -B28        A01X+153722Y+155044X0100Y0130R090 S1      
317m0284            VIA   -    MD0100PA00X+092200Y+132800X0200Y         S0      
317m0284            VIA   -    M      A01X+096157Y+144834X0200Y         S2      
017m0284            VIA   -    M      A18X+096157Y+144834X0260Y         S2      
017m0284                  -    MD0100PA00X+096157Y+144834                       
317m0285            VIA   -    MD0080PA00X+153888Y+154707X0160Y         S0      
327m0285            R1109 -2          A18X+091905Y+132400X0120Y0150     S2      
327m0285            U6013 -B31        A01X+153722Y+154808X0100Y0130R090 S1      
317m0285            VIA   -    M      A01X+092200Y+132400X0200Y         S2      
017m0285            VIA   -    M      A18X+092200Y+132400X0260Y         S2      
017m0285                  -    MD0100PA00X+092200Y+132400                       
317m0285            VIA   -    MD0100PA00X+096450Y+144810X0200Y         S0      
317m0286            VIA   -    MD0080PA00X+166688Y+154934X0160Y         S0      
317m0286            VIA   -    M      A01X+171842Y+146824X0200Y         S2      
017m0286            VIA   -    M      A18X+171842Y+146824X0260Y         S2      
017m0286                  -    MD0100PA00X+171842Y+146824                       
327m0286            R1068 -2          A18X+092155Y+131900X0120Y0150     S2      
317m0286            VIA   -    MD0100PA00X+092550Y+131900X0200Y         S0      
327m0286            U6012 -B28        A01X+166528Y+155044X0100Y0130R090 S1      
317m0286            VIA   -    MD0100PA00X+096700Y+144801X0200Y         S0      
317m0287            VIA   -    MD0080PA00X+166694Y+154707X0160Y         S0      
327m0287            VIA   -    M      A18X+170685Y+146815X0260Y         S2      
317m0287            VIA   -    MD0100PA00X+096978Y+144799X0200Y         S0      
327m0287            U6012 -B31        A01X+166528Y+154808X0100Y0130R090 S1      
317m0287            VIA   -    MD0100PA00X+172233Y+146815X0200Y         S0      
327m0287            R1067 -2          A18X+092155Y+131500X0120Y0150     S2      
317m0287            VIA   -    MD0100PA00X+092546Y+131535X0200Y         S0      
317m0288            VIA   -    MD0080PA00X+140271Y+154934X0160Y         S0      
327m0288            R1026 -2          A18X+092155Y+133700X0120Y0150     S2      
317m0288            VIA   -    MD0100PA00X+092550Y+133700X0200Y         S0      
317m0288            VIA   -    M      A01X+095454Y+144831X0200Y         S2      
017m0288            VIA   -    M      A18X+095454Y+144831X0260Y         S2      
017m0288                  -    MD0100PA00X+095454Y+144831                       
327m0288            U6011 -B28        A01X+140111Y+155044X0100Y0130R090 S1      
317m0289            VIA   -    MD0080PA00X+140276Y+154707X0160Y         S0      
327m0289            U6011 -B31        A01X+140111Y+154808X0100Y0130R090 S1      
327m0289            R1025 -2          A18X+092155Y+133300X0120Y0150     S2      
317m0289            VIA   -    M      A01X+092550Y+133300X0200Y         S2      
017m0289            VIA   -    M      A18X+092550Y+133300X0260Y         S2      
017m0289                  -    MD0100PA00X+092550Y+133300                       
317m0289            VIA   -    MD0100PA00X+095831Y+144806X0200Y         S0      
317m0290            VIA   -    MD0080PA00X+127464Y+154934X0160Y         S0      
317m0290            VIA   -    MD0100PA00X+092200Y+134600X0200Y         S0      
327m0290            R977  -2          A18X+091905Y+134600X0120Y0150     S2      
327m0290            U6010 -B28        A01X+127305Y+155044X0100Y0130R090 S1      
317m0290            VIA   -    M      A01X+094410Y+144832X0200Y         S2      
017m0290            VIA   -    M      A18X+094410Y+144832X0260Y         S2      
017m0290                  -    MD0100PA00X+094410Y+144832                       
317m0291            VIA   -    MD0080PA00X+127470Y+154707X0160Y         S0      
327m0291            R976  -2          A18X+091905Y+134200X0120Y0150     S2      
317m0291            VIA   -    MD0100PA00X+092200Y+134200X0200Y         S0      
327m0291            U6010 -B31        A01X+127305Y+154808X0100Y0130R090 S1      
317m0291            VIA   -    M      A01X+094922Y+144834X0200Y         S2      
017m0291            VIA   -    M      A18X+094922Y+144834X0260Y         S2      
017m0291                  -    MD0100PA00X+094922Y+144834                       
327m0292            VIA   -           A01X+153081Y+158955X0300Y         S1      
327m0292            R1123 -2   M      A01X+153407Y+158955X0120Y0150R090 S1      
327m0292            U6013 -G1         A01X+153314Y+157348X0100Y0130     S1      
327m0292            R1124 -1   M      A01X+153407Y+158665X0120Y0150R270 S1      
317m0293            VIA   -    MD0080PA00X+145079Y+154622X0160Y         S0      
327m0293            R1105 -2          A18X+143844Y+154380X0120Y0150     S2      
327m0293            R1106 -1   M      A18X+144134Y+154380X0120Y0150R180 S2      
327m0293            VIA   -    M      A18X+144810Y+154199X0260Y         S2      
327m0293            U6013 -FF33       A01X+145355Y+154690X0120Y         S1      
327m0294            U6013 -B25        A01X+153722Y+155281X0100Y0130R090 S1      
327m0294            R1098 -1   M      A01X+155505Y+155475X0120Y0150R090 S1      
327m0294            VIA   -    M      A01X+154875Y+155995X0300Y         S1      
327m0294            R1097 -2          A01X+155505Y+155185X0120Y0150R270 S1      
327m0295            U6013 -B23        A01X+153722Y+155517X0100Y0130R090 S1      
327m0295            R1100 -1   M      A01X+155825Y+155475X0120Y0150R090 S1      
327m0295            VIA   -    M      A01X+155375Y+155995X0300Y         S1      
327m0295            R1099 -2          A01X+155825Y+155185X0120Y0150R270 S1      
327m0296            R1102 -1   M      A01X+155560Y+153800X0120Y0150     S1      
327m0296            R1101 -2   M      A01X+155040Y+153960X0120Y0150     S1      
327m0296            VIA   -           A01X+155892Y+154198X0300Y         S1      
327m0296            U6013 -F34        A01X+153432Y+154450X0120Y         S1      
327m0297            VIA   -           A01X+165887Y+158955X0300Y         S1      
327m0297            R1081 -2   M      A01X+166213Y+158955X0120Y0150R090 S1      
327m0297            U6012 -G1         A01X+166120Y+157348X0100Y0130     S1      
327m0297            R1082 -1   M      A01X+166213Y+158665X0120Y0150R270 S1      
317m0298            VIA   -    MD0080PA00X+157885Y+154622X0160Y         S0      
327m0298            VIA   -    M      A18X+157573Y+154199X0260Y         S2      
327m0298            R1063 -2          A18X+156650Y+154380X0120Y0150     S2      
327m0298            R1064 -1   M      A18X+156940Y+154380X0120Y0150R180 S2      
327m0298            U6012 -FF33       A01X+158161Y+154690X0120Y         S1      
327m0299            VIA   -    M      A01X+169408Y+156716X0300Y         S1      
327m0299            R1055 -2          A01X+169385Y+157764X0120Y0150R090 S1      
327m0299            R1056 -1   M      A01X+169408Y+157052X0120Y0150R180 S1      
327m0299            U6012 -B25        A01X+166528Y+155281X0100Y0130R090 S1      
327m0300            R1058 -1          A01X+169408Y+157372X0120Y0150R180 S1      
327m0300            U6012 -B23        A01X+166528Y+155517X0100Y0130R090 S1      
327m0300            VIA   -    M      A01X+168754Y+156779X0300Y         S1      
327m0300            R1057 -2   M      A01X+169065Y+157764X0120Y0150R090 S1      
327m0301            R1060 -1          A01X+167997Y+153814X0120Y0150     S1      
327m0301            VIA   -    M      A01X+167682Y+154198X0300Y         S1      
327m0301            R1059 -2   M      A01X+167997Y+154134X0120Y0150     S1      
327m0301            U6012 -F34        A01X+166238Y+154450X0120Y         S1      
327m0302            VIA   -           A01X+139470Y+158955X0300Y         S1      
327m0302            R1040 -2   M      A01X+139796Y+158955X0120Y0150R090 S1      
327m0302            U6011 -G1         A01X+139703Y+157348X0100Y0130     S1      
327m0302            R1041 -1   M      A01X+139796Y+158665X0120Y0150R270 S1      
317m0303            VIA   -    MD0080PA00X+131468Y+154622X0160Y         S0      
327m0303            R1021 -2          A18X+130232Y+154380X0120Y0150     S2      
327m0303            R1022 -1   M      A18X+130522Y+154380X0120Y0150R180 S2      
327m0303            VIA   -    M      A18X+131177Y+154199X0260Y         S2      
327m0303            U6011 -FF33       A01X+131744Y+154690X0120Y         S1      
327m0304            U6011 -B25        A01X+140111Y+155281X0100Y0130R090 S1      
327m0304            R1014 -1   M      A01X+141894Y+155475X0120Y0150R090 S1      
327m0304            R1013 -2          A01X+141894Y+155185X0120Y0150R270 S1      
327m0304            VIA   -    M      A01X+141264Y+155995X0300Y         S1      
327m0305            U6011 -B23        A01X+140111Y+155517X0100Y0130R090 S1      
327m0305            VIA   -    M      A01X+141764Y+155995X0300Y         S1      
327m0305            R1015 -2          A01X+142214Y+155185X0120Y0150R270 S1      
327m0305            R1016 -1   M      A01X+142214Y+155475X0120Y0150R090 S1      
327m0306            R1017 -2   M      A01X+141428Y+153960X0120Y0150     S1      
327m0306            R1018 -1   M      A01X+141948Y+153800X0120Y0150     S1      
327m0306            U6011 -F34        A01X+139821Y+154450X0120Y         S1      
327m0306            VIA   -           A01X+142281Y+154198X0300Y         S1      
327m0307            R6808 -2   M      A01X+126915Y+158851X0120Y0150R270 S1      
327m0307            R6809 -1          A01X+126225Y+158830X0120Y0150R270 S1      
327m0307            VIA   -    M      A01X+126578Y+159034X0300Y         S1      
327m0307            U6010 -G1         A01X+126897Y+157348X0100Y0130     S1      
317m0308            VIA   -    MD0080PA00X+118662Y+154622X0160Y         S0      
327m0308            VIA   -    M      A18X+118230Y+153964X0260Y         S2      
327m0308            R972  -2   M      A18X+117926Y+153964X0120Y0150     S2      
327m0308            R973  -1          A18X+117716Y+154284X0120Y0150R180 S2      
327m0308            U6010 -FF33       A01X+118938Y+154690X0120Y         S1      
327m0309            U6010 -B25        A01X+127305Y+155281X0100Y0130R090 S1      
327m0309            R965  -1   M      A01X+129087Y+155475X0120Y0150R090 S1      
327m0309            VIA   -    M      A01X+128458Y+155995X0300Y         S1      
327m0309            R964  -2          A01X+129087Y+155185X0120Y0150R270 S1      
327m0310            U6010 -B23        A01X+127305Y+155517X0100Y0130R090 S1      
327m0310            R967  -1   M      A01X+129407Y+155475X0120Y0150R090 S1      
327m0310            VIA   -    M      A01X+128958Y+155995X0300Y         S1      
327m0310            R966  -2          A01X+129407Y+155185X0120Y0150R270 S1      
327m0311            R969  -1   M      A01X+129142Y+153800X0120Y0150     S1      
327m0311            R968  -2   M      A01X+128622Y+153960X0120Y0150     S1      
327m0311            U6010 -F34        A01X+127015Y+154450X0120Y         S1      
327m0311            VIA   -           A01X+129474Y+154198X0300Y         S1      
317m0312            VIA   -    MD0100PA00X+143985Y+154147X0200Y         S0      
317m0312            VIA   -    M      A01X+144703Y+157730X0200Y         S2      
017m0312            VIA   -    M      A18X+144703Y+157730X0260Y         S2      
017m0312                  -    MD0100PA00X+144703Y+157730                       
327m0312            R1104 -1   M      A01X+144798Y+158589X0120Y0150R270 S1      
327m0312            R1096 -2          A01X+144418Y+158879X0120Y0150R270 S1      
327m0312            R1107 -2   M      A01X+144798Y+158879X0120Y0150R090 S1      
327m0312            R6826 -2          A01X+085609Y+049458X0198Y0197     S1      
317m0312            VIA   -    MD0100PA00X+147395Y+049217X0200Y         S0      
317m0312            VIA   -    MD0100PA00X+084769Y+047592X0200Y         S0      
317m0312            VIA   -    MD0100PA00X+154358Y+152456X0200Y         S0      
317m0313            VIA   -    M      A01X+084977Y+049458X0200Y         S2      
017m0313            VIA   -    M      A18X+084977Y+049458X0260Y         S2      
017m0313                  -    MD0100PA00X+084977Y+049458                       
327m0313            U18   -T17        A01X+074458Y+047029X0160Y    R090 S1      
317m0313            VIA   -    MD0100PA00X+074611Y+047182X0180Y    R090 S0      
327m0313            R6826 -1          A01X+085294Y+049458X0198Y0197     S1      
327m0314            VIA   -           A01X+145427Y+160012X0300Y         S1      
327m0314            R1096 -1   M      A01X+144418Y+158669X0120Y0150R090 S1      
327m0314            U6013 -FF11       A01X+145355Y+156344X0120Y         S1      
317m0315            VIA   -    MD0100PA00X+167492Y+158297X0200Y         S0      
317m0315            VIA   -    MD0100PA00X+175938Y+050793X0200Y         S0      
327m0315            R6825 -2          A01X+085590Y+050315X0198Y0197     S1      
317m0315            VIA   -    MD0100PA00X+086034Y+050315X0200Y         S0      
327m0315            R1103 -1   M      A01X+154043Y+158665X0120Y0150R270 S1      
327m0315            R1088 -2          A01X+154043Y+158955X0120Y0150R090 S1      
317m0315            VIA   -    M      A01X+153934Y+157952X0200Y         S2      
017m0315            VIA   -    M      A18X+153934Y+157952X0260Y         S2      
017m0315                  -    MD0100PA00X+153934Y+157952                       
327m0316            U18   -T19        A01X+074458Y+047659X0160Y    R090 S1      
317m0316            VIA   -    MD0100PA00X+074611Y+047812X0180Y    R090 S0      
327m0316            R6825 -1          A01X+085275Y+050315X0198Y0197     S1      
317m0316            VIA   -    M      A01X+084810Y+050332X0200Y         S2      
017m0316            VIA   -    M      A18X+084810Y+050332X0260Y         S2      
017m0316                  -    MD0100PA00X+084810Y+050332                       
327m0317            VIA   -           A01X+153666Y+159452X0300Y         S1      
327m0317            R1088 -1   M      A01X+154043Y+159165X0120Y0150R270 S1      
327m0317            U6013 -F2         A01X+153432Y+157143X0120Y         S1      
317m0318            VIA   -    M      A01X+157497Y+157704X0200Y         S2      
017m0318            VIA   -    M      A18X+157497Y+157704X0260Y         S2      
017m0318                  -    MD0100PA00X+157497Y+157704                       
327m0318            R1062 -1   M      A01X+157605Y+158589X0120Y0150R270 S1      
327m0318            R1054 -2          A01X+157225Y+158879X0120Y0150R270 S1      
327m0318            R1065 -2   M      A01X+157605Y+158879X0120Y0150R090 S1      
317m0318            VIA   -    MD0100PA00X+167618Y+158065X0200Y         S0      
317m0318            VIA   -    MD0100PA00X+074808Y+052179X0200Y         S0      
327m0318            R6824 -2          A18X+074801Y+050132X0198Y0197R270 S2      
317m0318            VIA   -    MD0100PA00X+175357Y+051297X0200Y         S0      
327m0319            U18   -R20        A01X+074143Y+047974X0160Y    R090 S1      
327m0319            VIA   -    M      A18X+074685Y+048766X0260Y    R090 S2      
317m0319            VIA   -    MD0100PA00X+074296Y+048127X0180Y    R090 S0      
327m0319            R6824 -1          A18X+074801Y+049816X0198Y0197R270 S2      
327m0320            VIA   -           A01X+158012Y+160032X0300Y         S1      
327m0320            R1054 -1   M      A01X+157225Y+158669X0120Y0150R090 S1      
327m0320            U6012 -FF11       A01X+158161Y+156344X0120Y         S1      
317m0321            VIA   -    MD0100PA00X+169035Y+159149X0200Y         S0      
317m0321            VIA   -    M      A01X+086436Y+049300X0200Y         S2      
017m0321            VIA   -    M      A18X+086436Y+049300X0260Y         S2      
017m0321                  -    MD0100PA00X+086436Y+049300                       
327m0321            R6823 -2          A18X+080925Y+050426X0198Y0197R180 S2      
317m0321            VIA   -    MD0100PA00X+085218Y+034188X0200Y         S0      
327m0321            R1047 -2          A01X+166849Y+158955X0120Y0150R090 S1      
327m0321            R1061 -1   M      A01X+166849Y+158665X0120Y0150R270 S1      
317m0322            VIA   -    MD0100PA00X+073666Y+047497X0180Y    R090 S0      
317m0322            VIA   -    M      A01X+080067Y+050413X0200Y         S2      
017m0322            VIA   -    M      A18X+080067Y+050413X0260Y         S2      
017m0322                  -    MD0100PA00X+080067Y+050413                       
327m0322            R6823 -1          A18X+080610Y+050426X0198Y0197R180 S2      
327m0322            U18   -N18        A01X+073513Y+047344X0160Y    R090 S1      
327m0323            VIA   -    M      A01X+166573Y+159436X0300Y         S1      
327m0323            R1047 -1          A01X+166849Y+159165X0120Y0150R270 S1      
327m0323            U6012 -F2         A01X+166238Y+157143X0120Y         S1      
317m0324            VIA   -    MD0100PA00X+131091Y+157730X0200Y         S0      
327m0324            R6807 -1          A18X+080924Y+050817X0198Y0197     S2      
317m0324            VIA   -    M      A01X+099500Y+136200X0200Y         S2      
017m0324            VIA   -    M      A18X+099500Y+136200X0260Y         S2      
017m0324                  -    MD0100PA00X+099500Y+136200                       
327m0324            R1020 -1   M      A01X+131187Y+158589X0120Y0150R270 S1      
327m0324            R1012 -2          A01X+130807Y+158879X0120Y0150R270 S1      
327m0324            R1023 -2   M      A01X+131187Y+158879X0120Y0150R090 S1      
317m0324            VIA   -    MD0100PA00X+114032Y+159870X0200Y         S0      
317m0324            VIA   -    MD0100PA00X+095426Y+065737X0200Y         S0      
327m0325            R6807 -2          A18X+080609Y+050817X0198Y0197     S2      
327m0325            U18   -M17        A01X+073198Y+047029X0160Y    R090 S1      
317m0325            VIA   -    MD0100PA00X+073351Y+047182X0180Y    R090 S2      
317m0325            VIA   -    MD0100PA00X+080186Y+050803X0200Y         S0      
327m0326            VIA   -           A01X+131594Y+160032X0300Y         S1      
327m0326            R1012 -1   M      A01X+130807Y+158669X0120Y0150R090 S1      
327m0326            U6011 -FF11       A01X+131744Y+156344X0120Y         S1      
317m0327            VIA   -    M      A01X+140323Y+157952X0200Y         S2      
017m0327            VIA   -    M      A18X+140323Y+157952X0260Y         S2      
017m0327                  -    MD0100PA00X+140323Y+157952                       
327m0327            R1004 -2          A01X+140432Y+158955X0120Y0150R090 S1      
327m0327            R1019 -1   M      A01X+140432Y+158665X0120Y0150R270 S1      
317m0327            VIA   -    MD0100PA00X+097803Y+146000X0200Y         S0      
317m0327            VIA   -    MD0100PA00X+096159Y+082174X0200Y         S0      
317m0327            VIA   -    MD0100PA00X+093758Y+065595X0200Y         S0      
327m0327            R6806 -1          A01X+072679Y+052742X0198Y0197R270 S1      
317m0327            VIA   -    MD0100PA00X+077875Y+057227X0200Y         S0      
327m0328            R6806 -2          A01X+072679Y+052427X0198Y0197R270 S1      
327m0328            U18   -L22        A01X+072883Y+048604X0160Y    R090 S1      
317m0328            VIA   -    MD0100PA00X+072729Y+048757X0180Y    R090 S2      
327m0329            VIA   -           A01X+140155Y+159436X0300Y         S1      
327m0329            R1004 -1   M      A01X+140432Y+159165X0120Y0150R270 S1      
327m0329            U6011 -F2         A01X+139821Y+157143X0120Y         S1      
317m0330            VIA   -    MD0100PA00X+116687Y+156143X0200Y         S0      
327m0330            R963  -2          A01X+117042Y+156780X0120Y0150     S1      
327m0330            R971  -1   M      A01X+117042Y+156460X0120Y0150     S1      
327m0330            R974  -2   M      A01X+116687Y+156355X0120Y0150R090 S1      
317m0330            VIA   -    MD0100PA00X+072949Y+066655X0200Y         S0      
317m0330            VIA   -    M      A01X+101600Y+136100X0200Y         S2      
017m0330            VIA   -    M      A18X+101600Y+136100X0260Y         S2      
017m0330                  -    MD0100PA00X+101600Y+136100                       
317m0330            VIA   -    MD0100PA00X+095746Y+066870X0200Y         S0      
317m0330            VIA   -    MD0100PA00X+072470Y+053505X0200Y         S0      
327m0330            R6805 -1          A18X+072542Y+052831X0198Y0197R090 S2      
327m0331            R6805 -2          A18X+072542Y+052516X0198Y0197R090 S2      
327m0331            U18   -L21        A01X+072883Y+048288X0160Y    R090 S1      
327m0331            VIA   -    M      A18X+072730Y+050540X0260Y         S2      
317m0331            VIA   -    MD0100PA00X+072729Y+048442X0180Y    R090 S0      
327m0332            VIA   -    M      A01X+117577Y+156300X0300Y         S1      
327m0332            U6010 -FF11       A01X+118938Y+156344X0120Y         S1      
327m0332            R963  -1          A01X+117252Y+156780X0120Y0150R180 S1      
317m0333            VIA   -    MD0100PA00X+127517Y+157952X0200Y         S0      
317m0333            VIA   -    MD0100PA00X+099800Y+136550X0200Y         S0      
327m0333            R953  -2          A01X+127625Y+158955X0120Y0150R090 S1      
327m0333            R970  -1   M      A01X+127625Y+158665X0120Y0150R270 S1      
317m0333            VIA   -    MD0100PA00X+114042Y+159546X0200Y         S0      
327m0333            R6804 -1          A01X+067234Y+047427X0198Y0197     S1      
317m0333            VIA   -    M      A01X+066022Y+048311X0200Y         S2      
017m0333            VIA   -    M      A18X+066022Y+048311X0260Y         S2      
017m0333                  -    MD0100PA00X+066022Y+048311                       
317m0333            VIA   -    MD0100PA00X+070496Y+063877X0200Y         S0      
317m0333            VIA   -    MD0100PA00X+095436Y+066022X0200Y         S0      
327m0334            R6804 -2          A01X+067549Y+047427X0198Y0197     S1      
327m0334            U18   -K22        A01X+072568Y+048604X0160Y    R090 S1      
317m0334            VIA   -    MD0100PA00X+069045Y+048698X0200Y    R090 S2      
317m0334            VIA   -    MD0100PA00X+072414Y+048757X0180Y    R090 S0      
327m0335            VIA   -           A01X+127249Y+159452X0300Y         S1      
327m0335            R953  -1   M      A01X+127625Y+159165X0120Y0150R270 S1      
327m0335            U6010 -F2         A01X+127015Y+157143X0120Y         S1      
327m0336            R1087 -1   M      A01X+154867Y+154912X0180Y0200     S1      
327m0336            R1086 -1   M      A01X+154867Y+154522X0180Y0200     S1      
327m0336            R1093 -2   M      A01X+154867Y+154522X0180Y0200     S1      
327m0336            L30   -2   M      A01X+154867Y+154912X0180Y0200     S1      
327m0336            U6013 -BV17       A01X+149910Y+155914X0120Y         S1      
317m0336            VIA   -    MD0100PA00X+154867Y+154522X0200Y         S0      
327m0336            C1002 -1          A18X+150165Y+155955X0120Y0150R270 S2      
317m0336            VIA   -    MD0080PA00X+150165Y+155935X0160Y    R180 S0      
327m0336            C999  -1          A18X+150110Y+155675X0120Y0150R090 S2      
317m0336            VIA   -    MD0080PA00X+150110Y+155695X0160Y         S0      
317m0336            VIA   -    MD0100PA00X+154867Y+154912X0200Y         S0      
327m0337            R1087 -2          A01X+154552Y+154912X0180Y0200     S1      
327m0337            R1086 -2          A01X+154552Y+154522X0180Y0200     S1      
327m0337            C993  -1          A01X+154564Y+155284X0198Y0197R090 S1      
327m0337            C995  -1          A18X+149642Y+157221X0198Y0197R090 S2      
327m0337            C996  -1          A18X+149170Y+157221X0198Y0197R090 S2      
327m0337            U6013 -BV20       A01X+149910Y+155717X0120Y         S1      
327m0337            U6013 -CE17       A01X+149437Y+155914X0120Y         S1      
327m0337            U6013 -CE20       A01X+149437Y+155717X0120Y         S1      
327m0337            U6013 -CM17       A01X+148965Y+155914X0120Y         S1      
327m0337            U6013 -CM20       A01X+148965Y+155717X0120Y         S1      
327m0337            VIA   -           A18X+153727Y+154502X0260Y         S2      
327m0337            VIA   -           A18X+153677Y+155099X0260Y         S2      
327m0337            L22   -2   M      A18X+154489Y+154708X0440Y0540R180 S2      
327m0337            C991  -1   M      A18X+154337Y+155345X0400Y0500R090 S2      
317m0337            VIA   -    MD0100PA00X+154188Y+155444X0200Y    R180 S0      
317m0337            VIA   -    MD0100PA00X+154552Y+154522X0200Y    R180 S0      
317m0337            VIA   -    MD0100PA00X+154552Y+154912X0200Y    R180 S0      
317m0337            VIA   -    MD0100PA00X+154564Y+155284X0200Y    R180 S0      
317m0337            VIA   -    MD0100PA00X+153937Y+155225X0200Y    R270 S0      
317m0337            VIA   -    MD0100PA00X+154119Y+154995X0200Y    R270 S0      
317m0337            VIA   -    MD0100PA00X+154119Y+154745X0200Y    R270 S0      
317m0337            VIA   -    MD0100PA00X+154119Y+154495X0200Y    R270 S0      
317m0337            VIA   -    MD0080PA00X+148747Y+155935X0160Y         S0      
317m0337            VIA   -    MD0080PA00X+148692Y+155695X0160Y         S0      
317m0337            VIA   -    MD0080PA00X+149220Y+155935X0160Y         S0      
317m0337            VIA   -    MD0080PA00X+149692Y+155935X0160Y         S0      
317m0337            VIA   -    MD0080PA00X+149165Y+155695X0160Y         S0      
327m0337            C1005 -1   M      A18X+149692Y+155955X0120Y0150R270 S2      
327m0337            C1001 -1   M      A18X+148692Y+155675X0120Y0150R090 S2      
327m0337            C1000 -1   M      A18X+148747Y+155955X0120Y0150R270 S2      
327m0337            C1004 -1   M      A18X+149165Y+155675X0120Y0150R090 S2      
327m0337            C998  -1   M      A18X+149220Y+155955X0120Y0150R270 S2      
327m0337            C1003 -1   M      A18X+149637Y+155675X0120Y0150R090 S2      
317m0337            VIA   -    MD0080PA00X+149637Y+155695X0160Y         S0      
327m0338            R1050 -2   M      A01X+168059Y+155963X0180Y0200     S1      
327m0338            R1046 -1   M      A01X+168059Y+156353X0180Y0200     S1      
327m0338            R1045 -1   M      A01X+168059Y+155963X0180Y0200     S1      
327m0338            L29   -2   M      A01X+168059Y+156353X0180Y0200     S1      
327m0338            U6012 -BV17       A01X+162716Y+155914X0120Y         S1      
327m0338            VIA   -           A18X+167799Y+156165X0260Y         S2      
317m0338            VIA   -    MD0100PA00X+168059Y+156353X0200Y         S0      
317m0338            VIA   -    MD0100PA00X+168059Y+155963X0200Y         S0      
327m0338            C676  -1          A18X+162916Y+155675X0120Y0150R090 S2      
317m0338            VIA   -    MD0080PA00X+162916Y+155695X0160Y         S0      
327m0338            C775  -1          A18X+162971Y+155955X0120Y0150R270 S2      
317m0338            VIA   -    MD0080PA00X+162971Y+155935X0160Y         S0      
327m0339            R1046 -2          A01X+167744Y+156353X0180Y0200     S1      
327m0339            R1045 -2          A01X+167744Y+155963X0180Y0200     S1      
327m0339            C668  -1   M      A01X+167371Y+156042X0198Y0197R090 S1      
327m0339            C670  -1          A18X+161976Y+157221X0198Y0197R090 S2      
327m0339            C671  -1          A18X+162448Y+157221X0198Y0197R090 S2      
327m0339            U6012 -BV20       A01X+162716Y+155717X0120Y         S1      
327m0339            U6012 -CE17       A01X+162243Y+155914X0120Y         S1      
327m0339            U6012 -CE20       A01X+162243Y+155717X0120Y         S1      
327m0339            U6012 -CM17       A01X+161771Y+155914X0120Y         S1      
327m0339            U6012 -CM20       A01X+161771Y+155717X0120Y         S1      
317m0339            VIA   -    M      A01X+167103Y+154693X0200Y         S2      
017m0339            VIA   -    M      A18X+167103Y+154693X0260Y         S2      
017m0339                  -    MD0100PA00X+167103Y+154693                       
317m0339            VIA   -    MD0100PA00X+167371Y+156042X0200Y         S0      
317m0339            VIA   -    MD0100PA00X+166870Y+155090X0200Y         S0      
317m0339            VIA   -    MD0100PA00X+167103Y+155223X0200Y         S0      
317m0339            VIA   -    MD0100PA00X+167103Y+155473X0200Y         S0      
317m0339            VIA   -    MD0100PA00X+167103Y+155723X0200Y         S0      
317m0339            VIA   -    MD0100PA00X+167103Y+154973X0200Y         S0      
317m0339            VIA   -    MD0100PA00X+166883Y+155355X0200Y    R090 S0      
327m0339            L18   -2          A01X+167473Y+154720X0440Y0540     S1      
327m0339            C666  -1          A01X+167457Y+155420X0400Y0500R180 S1      
317m0339            VIA   -    MD0080PA00X+161971Y+155695X0160Y         S0      
317m0339            VIA   -    MD0080PA00X+162026Y+155935X0160Y         S0      
317m0339            VIA   -    MD0080PA00X+161554Y+155935X0160Y         S0      
317m0339            VIA   -    MD0080PA00X+161498Y+155695X0160Y         S0      
317m0339            VIA   -    MD0080PA00X+162498Y+155935X0160Y         S0      
327m0339            C778  -1   M      A18X+161498Y+155675X0120Y0150R090 S2      
327m0339            C774  -1   M      A18X+161971Y+155675X0120Y0150R090 S2      
327m0339            C673  -1   M      A18X+162026Y+155955X0120Y0150R270 S2      
327m0339            C677  -1   M      A18X+161554Y+155955X0120Y0150R270 S2      
327m0339            C776  -1   M      A18X+162498Y+155955X0120Y0150R270 S2      
327m0339            C777  -1   M      A18X+162443Y+155675X0120Y0150R090 S2      
317m0339            VIA   -    MD0080PA00X+162443Y+155695X0160Y         S0      
327m0340            R1008 -2   M      A01X+141256Y+154522X0180Y0200     S1      
327m0340            R1003 -1   M      A01X+141256Y+154522X0180Y0200     S1      
327m0340            R1002 -1   M      A01X+141256Y+154912X0180Y0200     S1      
327m0340            L28   -2   M      A01X+141256Y+154912X0180Y0200     S1      
327m0340            U6011 -BV17       A01X+136298Y+155914X0120Y         S1      
317m0340            VIA   -    MD0100PA00X+141256Y+154522X0200Y         S0      
327m0340            C598  -1          A18X+136498Y+155675X0120Y0150R090 S2      
317m0340            VIA   -    MD0080PA00X+136498Y+155695X0160Y         S0      
327m0340            C601  -1          A18X+136554Y+155955X0120Y0150R270 S2      
317m0340            VIA   -    MD0080PA00X+136554Y+155935X0160Y         S0      
317m0340            VIA   -    MD0100PA00X+141256Y+154912X0200Y         S0      
327m0341            R1003 -2          A01X+140941Y+154522X0180Y0200     S1      
327m0341            R1002 -2          A01X+140941Y+154912X0180Y0200     S1      
327m0341            C590  -1          A01X+140953Y+155284X0198Y0197R090 S1      
327m0341            C594  -1          A18X+135559Y+157221X0198Y0197R090 S2      
327m0341            C595  -1          A18X+136031Y+157221X0198Y0197R090 S2      
327m0341            U6011 -BV20       A01X+136298Y+155717X0120Y         S1      
327m0341            U6011 -CE17       A01X+135826Y+155914X0120Y         S1      
327m0341            U6011 -CE20       A01X+135826Y+155717X0120Y         S1      
327m0341            U6011 -CM17       A01X+135354Y+155914X0120Y         S1      
327m0341            U6011 -CM20       A01X+135354Y+155717X0120Y         S1      
327m0341            VIA   -           A18X+140120Y+154492X0260Y         S2      
327m0341            VIA   -           A18X+140065Y+155094X0260Y         S2      
317m0341            VIA   -    MD0100PA00X+140508Y+154745X0200Y         S0      
317m0341            VIA   -    MD0100PA00X+140508Y+154495X0200Y         S0      
317m0341            VIA   -    MD0100PA00X+140508Y+154995X0200Y         S0      
317m0341            VIA   -    MD0100PA00X+140326Y+155225X0200Y         S0      
327m0341            L13   -2   M      A18X+140878Y+154708X0440Y0540R180 S2      
317m0341            VIA   -    MD0100PA00X+140941Y+154522X0200Y         S0      
317m0341            VIA   -    MD0100PA00X+140941Y+154912X0200Y         S0      
327m0341            C588  -1   M      A18X+140726Y+155345X0400Y0500R090 S2      
317m0341            VIA   -    MD0100PA00X+140953Y+155284X0200Y    R180 S0      
317m0341            VIA   -    MD0100PA00X+140576Y+155444X0200Y    R180 S0      
317m0341            VIA   -    MD0080PA00X+135554Y+155695X0160Y         S0      
317m0341            VIA   -    MD0080PA00X+135609Y+155935X0160Y         S0      
317m0341            VIA   -    MD0080PA00X+135136Y+155935X0160Y         S0      
317m0341            VIA   -    MD0080PA00X+135081Y+155695X0160Y         S0      
317m0341            VIA   -    MD0080PA00X+136081Y+155935X0160Y         S0      
327m0341            C600  -1   M      A18X+135081Y+155675X0120Y0150R090 S2      
327m0341            C603  -1   M      A18X+135554Y+155675X0120Y0150R090 S2      
327m0341            C599  -1   M      A18X+135609Y+155955X0120Y0150R270 S2      
327m0341            C597  -1   M      A18X+135136Y+155955X0120Y0150R270 S2      
327m0341            C606  -1   M      A18X+136081Y+155955X0120Y0150R270 S2      
327m0341            C602  -1   M      A18X+136026Y+155675X0120Y0150R090 S2      
317m0341            VIA   -    MD0080PA00X+136026Y+155695X0160Y         S0      
327m0342            U6010 -BV17       A01X+123492Y+155914X0120Y         S1      
327m0342            C516  -1          A18X+123747Y+155955X0120Y0150R270 S2      
317m0342            VIA   -    MD0080PA00X+123747Y+155935X0160Y    R180 S0      
327m0342            C513  -1          A18X+123692Y+155675X0120Y0150R090 S2      
317m0342            VIA   -    MD0080PA00X+123692Y+155695X0160Y         S0      
317m0342            VIA   -    MD0100PA00X+128450Y+154522X0200Y         S0      
327m0342            R952  -1   M      A01X+128450Y+154522X0180Y0200     S1      
327m0342            R960  -2   M      A01X+128450Y+154522X0180Y0200     S1      
317m0342            VIA   -    MD0100PA00X+128450Y+154912X0200Y         S0      
327m0342            L26   -2   M      A01X+128450Y+154912X0180Y0200     S1      
327m0342            R951  -1   M      A01X+128450Y+154912X0180Y0200     S1      
327m0343            VIA   -           A18X+127302Y+154505X0260Y         S2      
327m0343            R952  -2          A01X+128135Y+154522X0180Y0200     S1      
327m0343            R951  -2          A01X+128135Y+154912X0180Y0200     S1      
327m0343            C505  -1          A01X+128147Y+155284X0198Y0197R090 S1      
327m0343            C507  -1          A18X+123225Y+157221X0198Y0197R090 S2      
327m0343            C510  -1          A18X+122752Y+157221X0198Y0197R090 S2      
327m0343            U6010 -BV20       A01X+123492Y+155717X0120Y         S1      
327m0343            U6010 -CE17       A01X+123020Y+155914X0120Y         S1      
327m0343            U6010 -CE20       A01X+123020Y+155717X0120Y         S1      
327m0343            U6010 -CM17       A01X+122547Y+155914X0120Y         S1      
327m0343            U6010 -CM20       A01X+122547Y+155717X0120Y         S1      
327m0343            VIA   -           A18X+127257Y+155091X0260Y         S2      
327m0343            L11   -2   M      A18X+128072Y+154708X0440Y0540R180 S2      
327m0343            C503  -1   M      A18X+127920Y+155345X0400Y0500R090 S2      
317m0343            VIA   -    MD0100PA00X+127770Y+155444X0200Y    R180 S0      
317m0343            VIA   -    MD0100PA00X+128135Y+154522X0200Y    R180 S0      
317m0343            VIA   -    MD0100PA00X+128135Y+154912X0200Y    R180 S0      
317m0343            VIA   -    MD0100PA00X+128147Y+155284X0200Y    R180 S0      
317m0343            VIA   -    MD0100PA00X+127520Y+155225X0200Y    R270 S0      
317m0343            VIA   -    MD0100PA00X+127702Y+154995X0200Y    R270 S0      
317m0343            VIA   -    MD0100PA00X+127702Y+154745X0200Y    R270 S0      
317m0343            VIA   -    MD0100PA00X+127702Y+154495X0200Y    R270 S0      
317m0343            VIA   -    MD0080PA00X+122330Y+155935X0160Y         S0      
317m0343            VIA   -    MD0080PA00X+122275Y+155695X0160Y         S0      
317m0343            VIA   -    MD0080PA00X+122802Y+155935X0160Y         S0      
317m0343            VIA   -    MD0080PA00X+123275Y+155935X0160Y         S0      
317m0343            VIA   -    MD0080PA00X+122747Y+155695X0160Y         S0      
327m0343            C519  -1   M      A18X+123275Y+155955X0120Y0150R270 S2      
327m0343            C520  -1   M      A18X+122275Y+155675X0120Y0150R090 S2      
327m0343            C512  -1   M      A18X+122330Y+155955X0120Y0150R270 S2      
327m0343            C517  -1   M      A18X+122747Y+155675X0120Y0150R090 S2      
327m0343            C514  -1   M      A18X+122802Y+155955X0120Y0150R270 S2      
327m0343            C515  -1   M      A18X+123220Y+155675X0120Y0150R090 S2      
317m0343            VIA   -    MD0080PA00X+123220Y+155695X0160Y         S0      
327m0344            U6013 -BD17       A01X+150854Y+155914X0120Y         S1      
327m0344            U6013 -BD20       A01X+150854Y+155717X0120Y         S1      
327m0344            U6013 -DF17       A01X+148020Y+155914X0120Y         S1      
327m0344            U6013 -DF20       A01X+148020Y+155717X0120Y         S1      
327m0344            VIA   -           A18X+143198Y+158693X0260Y         S2      
327m0344            C1021 -1          A18X+147802Y+155955X0120Y0150R270 S2      
317m0344            VIA   -    MD0080PA00X+147802Y+155935X0160Y         S0      
327m0344            C1020 -1          A18X+147747Y+155675X0120Y0150R090 S2      
317m0344            VIA   -    MD0080PA00X+147747Y+155695X0160Y         S0      
327m0344            C1018 -1          A18X+151054Y+155675X0120Y0150R090 S2      
317m0344            VIA   -    MD0080PA00X+151054Y+155695X0160Y         S0      
317m0344            VIA   -    MD0100PA00X+142957Y+158484X0200Y         S0      
317m0344            VIA   -    MD0100PA00X+143199Y+158410X0200Y         S0      
317m0344            VIA   -    MD0100PA00X+143449Y+158484X0200Y         S0      
327m0344            R1095 -1   M      A18X+143199Y+158120X0280Y0320R270 S2      
327m0344            R1094 -2   M      A18X+143199Y+158120X0280Y0320R270 S2      
317m0344            VIA   -    MD0100PA00X+143199Y+158120X0200Y         S0      
317m0344            VIA   -    MD0080PA00X+151110Y+155935X0160Y         S0      
327m0344            C1014 -1          A18X+151110Y+155955X0120Y0150R270 S2      
327m0345            C1047 -1          A18X+153642Y+155965X0120Y0150R180 S2      
327m0345            C1050 -1          A18X+145191Y+155682X0120Y0150     S2      
327m0345            C1054 -1          A18X+145507Y+157214X0198Y0197R270 S2      
327m0345            C1053 -1          A18X+144961Y+156401X0120Y0150R090 S2      
327m0345            C1006 -1          A18X+145777Y+154967X0120Y0150R270 S2      
327m0345            C7017 -1          A18X+146613Y+153344X0950Y1110R180 S2      
327m0345            C7019 -1          A18X+145508Y+153574X0400Y0500R180 S2      
327m0345            C7018 -1          A18X+152861Y+153344X0950Y1110     S2      
327m0345            C1030 -1          A18X+146335Y+157221X0198Y0197R090 S2      
327m0345            C1049 -1          A18X+147280Y+157221X0198Y0197R090 S2      
327m0345            C1041 -1          A18X+147752Y+157221X0198Y0197R090 S2      
327m0345            C1026 -1          A18X+152004Y+157221X0198Y0197R090 S2      
327m0345            C1036 -1          A18X+152949Y+157221X0198Y0197R090 S2      
327m0345            C1045 -1          A18X+152477Y+157221X0198Y0197R090 S2      
327m0345            C1040 -1          A18X+153482Y+157221X0198Y0197R090 S2      
327m0345            U6013 -AC17       A01X+152272Y+155914X0120Y         S1      
327m0345            U6013 -AC20       A01X+152272Y+155717X0120Y         S1      
327m0345            U6013 -AK17       A01X+151799Y+155914X0120Y         S1      
327m0345            U6013 -AK20       A01X+151799Y+155717X0120Y         S1      
327m0345            U6013 -AU17       A01X+151327Y+155914X0120Y         S1      
327m0345            U6013 -AU20       A01X+151327Y+155717X0120Y         S1      
327m0345            U6013 -T17        A01X+152744Y+155914X0120Y         S1      
327m0345            U6013 -T20        A01X+152744Y+155717X0120Y         S1      
327m0345            U6013 -DN17       A01X+147548Y+155914X0120Y         S1      
327m0345            U6013 -DN20       A01X+147548Y+155717X0120Y         S1      
327m0345            U6013 -DY17       A01X+147075Y+155914X0120Y         S1      
327m0345            U6013 -DY20       A01X+147075Y+155717X0120Y         S1      
327m0345            U6013 -EG17       A01X+146603Y+155914X0120Y         S1      
327m0345            U6013 -EG20       A01X+146603Y+155717X0120Y         S1      
327m0345            U6013 -EP17       A01X+146130Y+155914X0120Y         S1      
327m0345            U6013 -EP20       A01X+146130Y+155717X0120Y         S1      
327m0345            VIA   -           A18X+147205Y+159290X0260Y         S2      
327m0345            VIA   -           A18X+149171Y+159345X0260Y         S2      
327m0345            VIA   -           A18X+151611Y+159317X0260Y         S2      
327m0345            VIA   -           A18X+153689Y+159359X0260Y         S2      
327m0345            VIA   -           A18X+145531Y+159304X0260Y         S2      
327m0345            C1025 -1          A18X+154359Y+157558X0400Y0500     S2      
327m0345            C1023 -1          A18X+151532Y+157221X0198Y0197R090 S2      
327m0345            C1034 -1          A18X+151060Y+157221X0198Y0197R090 S2      
327m0345            C1037 -1          A18X+145863Y+157221X0198Y0197R090 S2      
327m0345            C1056 -1          A18X+146808Y+157221X0198Y0197R090 S2      
317m0345            VIA   -    MD0100PA00X+144290Y+157480X0200Y         S0      
317m0345            VIA   -    MD0100PA00X+144290Y+157730X0200Y         S0      
317m0345            VIA   -    MD0100PA00X+144290Y+157980X0200Y         S0      
317m0345            VIA   -    MD0100PA00X+144290Y+158230X0200Y         S0      
327m0345            C1029 -1          A18X+144255Y+157075X0400Y0500R180 S2      
317m0345            VIA   -    MD0100PA00X+143540Y+157480X0200Y         S0      
317m0345            VIA   -    MD0100PA00X+143540Y+157730X0200Y         S0      
317m0345            VIA   -    MD0100PA00X+143540Y+157980X0200Y         S0      
317m0345            VIA   -    MD0100PA00X+143540Y+158230X0200Y         S0      
327m0345            R1095 -2   M      A18X+143779Y+158120X0280Y0320R270 S2      
317m0345            VIA   -    MD0100PA00X+143790Y+158230X0200Y         S0      
327m0345            L23   -2   M      A01X+143916Y+157836X0420Y0990     S1      
317m0345            VIA   -    MD0100PA00X+143790Y+157480X0200Y         S0      
317m0345            VIA   -    MD0100PA00X+144040Y+157730X0200Y         S0      
317m0345            VIA   -    MD0100PA00X+144040Y+157980X0200Y         S0      
317m0345            VIA   -    MD0100PA00X+144040Y+158230X0200Y         S0      
317m0345            VIA   -    MD0100PA00X+144040Y+157480X0200Y         S0      
317m0345            VIA   -    MD0100PA00X+143790Y+157730X0200Y         S0      
317m0345            VIA   -    MD0100PA00X+143790Y+157980X0200Y         S0      
327m0345            C1046 -1          A18X+153419Y+155675X0120Y0150R090 S2      
327m0345            C1022 -1          A18X+154359Y+156872X0400Y0500     S2      
327m0345            C1051 -1   M      A18X+152054Y+155955X0120Y0150R270 S2      
327m0345            C1039 -1   M      A18X+151999Y+155675X0120Y0150R090 S2      
327m0345            C1055 -1   M      A18X+151582Y+155955X0120Y0150R270 S2      
327m0345            C1015 -1   M      A18X+151527Y+155675X0120Y0150R090 S2      
327m0345            C1043 -1   M      A18X+152999Y+155955X0120Y0150R270 S2      
327m0345            C1010 -1   M      A18X+152527Y+155955X0120Y0150R270 S2      
327m0345            C1019 -1   M      A18X+152944Y+155675X0120Y0150R090 S2      
327m0345            C1027 -1   M      A18X+152472Y+155675X0120Y0150R090 S2      
317m0345            VIA   -    MD0080PA00X+152472Y+155695X0160Y         S0      
317m0345            VIA   -    MD0080PA00X+152527Y+155935X0160Y         S0      
317m0345            VIA   -    MD0080PA00X+152999Y+155935X0160Y         S0      
317m0345            VIA   -    MD0080PA00X+152054Y+155935X0160Y         S0      
317m0345            VIA   -    MD0080PA00X+151999Y+155695X0160Y         S0      
317m0345            VIA   -    MD0080PA00X+152944Y+155695X0160Y         S0      
317m0345            VIA   -    MD0080PA00X+151527Y+155695X0160Y         S0      
317m0345            VIA   -    MD0080PA00X+151582Y+155935X0160Y         S0      
327m0345            C1033 -1          A18X+144253Y+156389X0400Y0500R180 S2      
317m0345            VIA   -    MD0080PA00X+146803Y+155695X0160Y         S0      
317m0345            VIA   -    MD0080PA00X+146330Y+155695X0160Y         S0      
317m0345            VIA   -    MD0080PA00X+147330Y+155935X0160Y         S0      
317m0345            VIA   -    MD0080PA00X+145913Y+155935X0160Y         S0      
317m0345            VIA   -    MD0080PA00X+146385Y+155935X0160Y         S0      
317m0345            VIA   -    MD0080PA00X+146858Y+155935X0160Y         S0      
317m0345            VIA   -    MD0080PA00X+145858Y+155695X0160Y         S0      
317m0345            VIA   -    MD0080PA00X+147275Y+155695X0160Y         S0      
327m0345            C1024 -1   M      A18X+147275Y+155675X0120Y0150R090 S2      
327m0345            C1013 -1   M      A18X+146803Y+155675X0120Y0150R090 S2      
327m0345            C1035 -1   M      A18X+147330Y+155955X0120Y0150R270 S2      
327m0345            C1008 -1   M      A18X+146385Y+155955X0120Y0150R270 S2      
327m0345            C1011 -1   M      A18X+146858Y+155955X0120Y0150R270 S2      
327m0345            C1017 -1   M      A18X+145858Y+155675X0120Y0150R090 S2      
327m0345            C1031 -1   M      A18X+146330Y+155675X0120Y0150R090 S2      
327m0345            C1052 -1   M      A18X+145913Y+155955X0120Y0150R270 S2      
327m0346            U6012 -BD17       A01X+163661Y+155914X0120Y         S1      
327m0346            U6012 -BD20       A01X+163661Y+155717X0120Y         S1      
327m0346            U6012 -DF17       A01X+160826Y+155914X0120Y         S1      
327m0346            U6012 -DF20       A01X+160826Y+155717X0120Y         S1      
327m0346            VIA   -           A18X+156004Y+158693X0260Y         S2      
327m0346            C787  -1          A18X+160554Y+155675X0120Y0150R090 S2      
317m0346            VIA   -    MD0080PA00X+160554Y+155695X0160Y         S0      
327m0346            C791  -1          A18X+160609Y+155955X0120Y0150R270 S2      
317m0346            VIA   -    MD0080PA00X+160609Y+155935X0160Y         S0      
327m0346            C793  -1          A18X+163861Y+155675X0120Y0150R090 S2      
317m0346            VIA   -    MD0080PA00X+163861Y+155695X0160Y         S0      
317m0346            VIA   -    MD0100PA00X+155763Y+158484X0200Y         S0      
317m0346            VIA   -    MD0100PA00X+156005Y+158410X0200Y         S0      
317m0346            VIA   -    MD0100PA00X+156256Y+158484X0200Y         S0      
327m0346            R1053 -1   M      A18X+156005Y+158120X0280Y0320R270 S2      
327m0346            R1051 -2   M      A18X+156005Y+158120X0280Y0320R270 S2      
317m0346            VIA   -    MD0100PA00X+156005Y+158120X0200Y         S0      
317m0346            VIA   -    MD0080PA00X+163916Y+155935X0160Y         S0      
327m0346            C794  -1          A18X+163916Y+155955X0120Y0150R270 S2      
327m0347            C781  -1          A18X+157997Y+155682X0120Y0150     S2      
327m0347            C970  -1          A18X+158313Y+157214X0198Y0197R270 S2      
327m0347            C784  -1          A18X+157767Y+156401X0120Y0150R090 S2      
327m0347            C779  -1          A18X+158583Y+154967X0120Y0150R270 S2      
327m0347            C7015 -1          A18X+159419Y+153344X0950Y1110R180 S2      
327m0347            C7016 -1          A18X+158299Y+153557X0400Y0500R180 S2      
327m0347            C7014 -1          A18X+165668Y+153344X0950Y1110     S2      
327m0347            C974  -1          A18X+159141Y+157221X0198Y0197R090 S2      
327m0347            C799  -1          A18X+160559Y+157221X0198Y0197R090 S2      
327m0347            C981  -1          A18X+163866Y+157221X0198Y0197R090 S2      
327m0347            C973  -1          A18X+164338Y+157221X0198Y0197R090 S2      
327m0347            C977  -1          A18X+165283Y+157221X0198Y0197R090 S2      
327m0347            C988  -1          A18X+166289Y+157221X0198Y0197R090 S2      
327m0347            C969  -1          A18X+164811Y+157221X0198Y0197R090 S2      
327m0347            U6012 -AC17       A01X+165078Y+155914X0120Y         S1      
327m0347            U6012 -AC20       A01X+165078Y+155717X0120Y         S1      
327m0347            U6012 -T17        A01X+165550Y+155914X0120Y         S1      
327m0347            U6012 -T20        A01X+165550Y+155717X0120Y         S1      
327m0347            U6012 -AK17       A01X+164606Y+155914X0120Y         S1      
327m0347            U6012 -AK20       A01X+164606Y+155717X0120Y         S1      
327m0347            U6012 -AU17       A01X+164133Y+155914X0120Y         S1      
327m0347            U6012 -AU20       A01X+164133Y+155717X0120Y         S1      
327m0347            U6012 -DN17       A01X+160354Y+155914X0120Y         S1      
327m0347            U6012 -DN20       A01X+160354Y+155717X0120Y         S1      
327m0347            U6012 -DY17       A01X+159881Y+155914X0120Y         S1      
327m0347            U6012 -DY20       A01X+159881Y+155717X0120Y         S1      
327m0347            U6012 -EG17       A01X+159409Y+155914X0120Y         S1      
327m0347            U6012 -EG20       A01X+159409Y+155717X0120Y         S1      
327m0347            U6012 -EP17       A01X+158936Y+155914X0120Y         S1      
327m0347            U6012 -EP20       A01X+158936Y+155717X0120Y         S1      
327m0347            VIA   -           A18X+159505Y+159282X0260Y         S2      
327m0347            VIA   -           A18X+162363Y+159387X0260Y         S2      
327m0347            VIA   -           A18X+164316Y+159331X0260Y         S2      
327m0347            VIA   -           A18X+166575Y+158788X0260Y         S2      
327m0347            VIA   -           A18X+157657Y+159087X0260Y         S2      
317m0347            VIA   -    MD0100PA00X+166883Y+157300X0200Y         S0      
317m0347            VIA   -    MD0100PA00X+166883Y+157550X0200Y         S0      
317m0347            VIA   -    MD0100PA00X+167101Y+157174X0200Y         S0      
317m0347            VIA   -    MD0100PA00X+167101Y+157424X0200Y         S0      
317m0347            VIA   -    MD0100PA00X+167101Y+157674X0200Y         S0      
327m0347            C795  -1          A01X+167451Y+157660X0400Y0500R180 S1      
327m0347            C798  -1          A01X+167451Y+156974X0400Y0500R180 S1      
327m0347            C986  -1          A18X+165756Y+157221X0198Y0197R090 S2      
327m0347            C796  -1          A18X+160086Y+157221X0198Y0197R090 S2      
327m0347            C967  -1          A18X+159614Y+157221X0198Y0197R090 S2      
327m0347            C803  -1          A18X+158669Y+157221X0198Y0197R090 S2      
317m0347            VIA   -    MD0100PA00X+156346Y+157730X0200Y         S0      
317m0347            VIA   -    MD0100PA00X+156346Y+157980X0200Y         S0      
317m0347            VIA   -    MD0100PA00X+156346Y+158230X0200Y         S0      
317m0347            VIA   -    MD0100PA00X+156346Y+157480X0200Y         S0      
317m0347            VIA   -    MD0100PA00X+157096Y+157730X0200Y         S0      
317m0347            VIA   -    MD0100PA00X+157096Y+157980X0200Y         S0      
317m0347            VIA   -    MD0100PA00X+157096Y+158230X0200Y         S0      
317m0347            VIA   -    MD0100PA00X+157096Y+157480X0200Y         S0      
327m0347            C966  -1          A18X+157062Y+157075X0400Y0500R180 S2      
327m0347            R1053 -2   M      A18X+156585Y+158120X0280Y0320R270 S2      
317m0347            VIA   -    MD0100PA00X+156596Y+158230X0200Y         S0      
327m0347            L21   -2   M      A01X+156723Y+157836X0420Y0990     S1      
317m0347            VIA   -    MD0100PA00X+156846Y+158230X0200Y         S0      
317m0347            VIA   -    MD0100PA00X+156596Y+157980X0200Y         S0      
317m0347            VIA   -    MD0100PA00X+156846Y+157980X0200Y         S0      
317m0347            VIA   -    MD0100PA00X+156846Y+157730X0200Y         S0      
317m0347            VIA   -    MD0100PA00X+156596Y+157730X0200Y         S0      
317m0347            VIA   -    MD0100PA00X+156846Y+157480X0200Y         S0      
317m0347            VIA   -    MD0100PA00X+156596Y+157480X0200Y         S0      
327m0347            C987  -1          A18X+165784Y+154495X0120Y0150R270 S2      
327m0347            C979  -1          A18X+166225Y+155675X0120Y0150R090 S2      
327m0347            C984  -1   M      A18X+165333Y+155955X0120Y0150R270 S2      
327m0347            C975  -1   M      A18X+165278Y+155675X0120Y0150R090 S2      
327m0347            C982  -1   M      A18X+164388Y+155955X0120Y0150R270 S2      
327m0347            C804  -1   M      A18X+164861Y+155955X0120Y0150R270 S2      
327m0347            C792  -1   M      A18X+164333Y+155675X0120Y0150R090 S2      
327m0347            C788  -1   M      A18X+164806Y+155675X0120Y0150R090 S2      
327m0347            C790  -1   M      A18X+165806Y+155955X0120Y0150R270 S2      
327m0347            C786  -1   M      A18X+165750Y+155675X0120Y0150R090 S2      
317m0347            VIA   -    MD0080PA00X+165750Y+155695X0160Y         S0      
317m0347            VIA   -    MD0080PA00X+165333Y+155935X0160Y         S0      
317m0347            VIA   -    MD0080PA00X+165806Y+155935X0160Y         S0      
317m0347            VIA   -    MD0080PA00X+164388Y+155935X0160Y         S0      
317m0347            VIA   -    MD0080PA00X+164333Y+155695X0160Y         S0      
317m0347            VIA   -    MD0080PA00X+164806Y+155695X0160Y         S0      
317m0347            VIA   -    MD0080PA00X+164861Y+155935X0160Y         S0      
317m0347            VIA   -    MD0080PA00X+165278Y+155695X0160Y         S0      
327m0347            C802  -1          A18X+157059Y+156389X0400Y0500R180 S2      
317m0347            VIA   -    MD0080PA00X+159191Y+155935X0160Y         S0      
317m0347            VIA   -    MD0080PA00X+158719Y+155935X0160Y         S0      
317m0347            VIA   -    MD0080PA00X+159136Y+155695X0160Y         S0      
317m0347            VIA   -    MD0080PA00X+158664Y+155695X0160Y         S0      
317m0347            VIA   -    MD0080PA00X+160136Y+155935X0160Y         S0      
317m0347            VIA   -    MD0080PA00X+159609Y+155695X0160Y         S0      
317m0347            VIA   -    MD0080PA00X+159664Y+155935X0160Y         S0      
317m0347            VIA   -    MD0080PA00X+160081Y+155695X0160Y         S0      
327m0347            C783  -1   M      A18X+160081Y+155675X0120Y0150R090 S2      
327m0347            C985  -1   M      A18X+160136Y+155955X0120Y0150R270 S2      
327m0347            C983  -1   M      A18X+158664Y+155675X0120Y0150R090 S2      
327m0347            C797  -1   M      A18X+159136Y+155675X0120Y0150R090 S2      
327m0347            C800  -1   M      A18X+159191Y+155955X0120Y0150R270 S2      
327m0347            C968  -1   M      A18X+158719Y+155955X0120Y0150R270 S2      
327m0347            C978  -1   M      A18X+159609Y+155675X0120Y0150R090 S2      
327m0347            C972  -1   M      A18X+159664Y+155955X0120Y0150R270 S2      
327m0348            U6011 -BD17       A01X+137243Y+155914X0120Y         S1      
327m0348            U6011 -BD20       A01X+137243Y+155717X0120Y         S1      
327m0348            U6011 -DF17       A01X+134409Y+155914X0120Y         S1      
327m0348            U6011 -DF20       A01X+134409Y+155717X0120Y         S1      
327m0348            VIA   -           A18X+129587Y+158693X0260Y         S2      
327m0348            C621  -1          A18X+134136Y+155675X0120Y0150R090 S2      
317m0348            VIA   -    MD0080PA00X+134136Y+155695X0160Y         S0      
327m0348            C617  -1          A18X+134191Y+155955X0120Y0150R270 S2      
317m0348            VIA   -    MD0080PA00X+134191Y+155935X0160Y         S0      
327m0348            C624  -1          A18X+137443Y+155675X0120Y0150R090 S2      
317m0348            VIA   -    MD0080PA00X+137443Y+155695X0160Y         S0      
317m0348            VIA   -    MD0100PA00X+129346Y+158484X0200Y         S0      
317m0348            VIA   -    MD0100PA00X+129588Y+158410X0200Y         S0      
317m0348            VIA   -    MD0100PA00X+129838Y+158484X0200Y         S0      
327m0348            R1011 -1   M      A18X+129588Y+158120X0280Y0320R270 S2      
327m0348            R1010 -2   M      A18X+129588Y+158120X0280Y0320R270 S2      
317m0348            VIA   -    MD0100PA00X+129588Y+158120X0200Y         S0      
317m0348            VIA   -    MD0080PA00X+137498Y+155935X0160Y         S0      
327m0348            C623  -1          A18X+137498Y+155955X0120Y0150R270 S2      
327m0349            C649  -1          A18X+131896Y+157214X0198Y0197R270 S2      
327m0349            C620  -1          A18X+131580Y+155682X0120Y0150     S2      
327m0349            C622  -1          A18X+132166Y+154967X0120Y0150R270 S2      
327m0349            C616  -1          A18X+131349Y+156401X0120Y0150R090 S2      
327m0349            C658  -1          A18X+140031Y+155965X0120Y0150R180 S2      
327m0349            C7011 -1          A18X+133002Y+153344X0950Y1110R180 S2      
327m0349            C7013 -1          A18X+131885Y+153534X0400Y0500R180 S2      
327m0349            C7012 -1          A18X+139250Y+153344X0950Y1110     S2      
327m0349            C634  -1          A18X+132724Y+157221X0198Y0197R090 S2      
327m0349            C630  -1          A18X+134141Y+157221X0198Y0197R090 S2      
327m0349            C648  -1          A18X+137921Y+157221X0198Y0197R090 S2      
327m0349            C644  -1          A18X+137448Y+157221X0198Y0197R090 S2      
327m0349            C652  -1          A18X+138866Y+157221X0198Y0197R090 S2      
327m0349            C663  -1          A18X+139871Y+157221X0198Y0197R090 S2      
327m0349            C656  -1          A18X+138393Y+157221X0198Y0197R090 S2      
327m0349            U6011 -AC17       A01X+138661Y+155914X0120Y         S1      
327m0349            U6011 -AC20       A01X+138661Y+155717X0120Y         S1      
327m0349            U6011 -AK17       A01X+138188Y+155914X0120Y         S1      
327m0349            U6011 -AK20       A01X+138188Y+155717X0120Y         S1      
327m0349            U6011 -T17        A01X+139133Y+155914X0120Y         S1      
327m0349            U6011 -T20        A01X+139133Y+155717X0120Y         S1      
327m0349            U6011 -AU17       A01X+137716Y+155914X0120Y         S1      
327m0349            U6011 -AU20       A01X+137716Y+155717X0120Y         S1      
327m0349            U6011 -DN17       A01X+133936Y+155914X0120Y         S1      
327m0349            U6011 -DN20       A01X+133936Y+155717X0120Y         S1      
327m0349            U6011 -DY17       A01X+133464Y+155914X0120Y         S1      
327m0349            U6011 -DY20       A01X+133464Y+155717X0120Y         S1      
327m0349            U6011 -EG17       A01X+132991Y+155914X0120Y         S1      
327m0349            U6011 -EG20       A01X+132991Y+155717X0120Y         S1      
327m0349            U6011 -EP17       A01X+132519Y+155914X0120Y         S1      
327m0349            U6011 -EP20       A01X+132519Y+155717X0120Y         S1      
327m0349            VIA   -           A18X+132429Y+159150X0260Y         S2      
327m0349            VIA   -           A18X+134416Y+159317X0260Y         S2      
327m0349            VIA   -           A18X+140413Y+158885X0260Y         S2      
327m0349            VIA   -           A18X+138684Y+159513X0260Y         S2      
327m0349            VIA   -           A18X+130951Y+158885X0260Y         S2      
327m0349            C625  -1          A18X+140748Y+157558X0400Y0500     S2      
327m0349            C661  -1          A18X+139338Y+157221X0198Y0197R090 S2      
327m0349            C626  -1          A18X+133669Y+157221X0198Y0197R090 S2      
327m0349            C638  -1          A18X+133196Y+157221X0198Y0197R090 S2      
327m0349            C645  -1          A18X+132251Y+157221X0198Y0197R090 S2      
317m0349            VIA   -    MD0100PA00X+130679Y+157730X0200Y         S0      
317m0349            VIA   -    MD0100PA00X+130679Y+157980X0200Y         S0      
317m0349            VIA   -    MD0100PA00X+130679Y+158230X0200Y         S0      
317m0349            VIA   -    MD0100PA00X+130679Y+157480X0200Y         S0      
327m0349            C633  -1          A18X+130644Y+157075X0400Y0500R180 S2      
317m0349            VIA   -    MD0100PA00X+129929Y+157730X0200Y         S0      
317m0349            VIA   -    MD0100PA00X+129929Y+157980X0200Y         S0      
317m0349            VIA   -    MD0100PA00X+129929Y+158230X0200Y         S0      
317m0349            VIA   -    MD0100PA00X+129929Y+157480X0200Y         S0      
327m0349            R1011 -2   M      A18X+130168Y+158120X0280Y0320R270 S2      
317m0349            VIA   -    MD0100PA00X+130179Y+158230X0200Y         S0      
327m0349            L14   -2   M      A01X+130305Y+157836X0420Y0990     S1      
317m0349            VIA   -    MD0100PA00X+130429Y+158230X0200Y         S0      
317m0349            VIA   -    MD0100PA00X+130179Y+157980X0200Y         S0      
317m0349            VIA   -    MD0100PA00X+130429Y+157980X0200Y         S0      
317m0349            VIA   -    MD0100PA00X+130429Y+157730X0200Y         S0      
317m0349            VIA   -    MD0100PA00X+130179Y+157730X0200Y         S0      
317m0349            VIA   -    MD0100PA00X+130429Y+157480X0200Y         S0      
317m0349            VIA   -    MD0100PA00X+130179Y+157480X0200Y         S0      
327m0349            C653  -1          A18X+139808Y+155675X0120Y0150R090 S2      
327m0349            C628  -1          A18X+140748Y+156872X0400Y0500     S2      
327m0349            C631  -1   M      A18X+138916Y+155955X0120Y0150R270 S2      
327m0349            C643  -1   M      A18X+138861Y+155675X0120Y0150R090 S2      
327m0349            C627  -1   M      A18X+137971Y+155955X0120Y0150R270 S2      
327m0349            C659  -1   M      A18X+138443Y+155955X0120Y0150R270 S2      
327m0349            C618  -1   M      A18X+137916Y+155675X0120Y0150R090 S2      
327m0349            C613  -1   M      A18X+138388Y+155675X0120Y0150R090 S2      
327m0349            C614  -1   M      A18X+139388Y+155955X0120Y0150R270 S2      
327m0349            C609  -1   M      A18X+139333Y+155675X0120Y0150R090 S2      
317m0349            VIA   -    MD0080PA00X+139333Y+155695X0160Y         S0      
317m0349            VIA   -    MD0080PA00X+138916Y+155935X0160Y         S0      
317m0349            VIA   -    MD0080PA00X+139388Y+155935X0160Y         S0      
317m0349            VIA   -    MD0080PA00X+137971Y+155935X0160Y         S0      
317m0349            VIA   -    MD0080PA00X+137916Y+155695X0160Y         S0      
317m0349            VIA   -    MD0080PA00X+138388Y+155695X0160Y         S0      
317m0349            VIA   -    MD0080PA00X+138443Y+155935X0160Y         S0      
317m0349            VIA   -    MD0080PA00X+138861Y+155695X0160Y         S0      
327m0349            C637  -1          A18X+130642Y+156389X0400Y0500R180 S2      
317m0349            VIA   -    MD0080PA00X+132774Y+155935X0160Y         S0      
317m0349            VIA   -    MD0080PA00X+132302Y+155935X0160Y         S0      
317m0349            VIA   -    MD0080PA00X+132719Y+155695X0160Y         S0      
317m0349            VIA   -    MD0080PA00X+132246Y+155695X0160Y         S0      
317m0349            VIA   -    MD0080PA00X+133719Y+155935X0160Y         S0      
317m0349            VIA   -    MD0080PA00X+133191Y+155695X0160Y         S0      
317m0349            VIA   -    MD0080PA00X+133246Y+155935X0160Y         S0      
317m0349            VIA   -    MD0080PA00X+133664Y+155695X0160Y         S0      
327m0349            C607  -1   M      A18X+133664Y+155675X0120Y0150R090 S2      
327m0349            C662  -1   M      A18X+133719Y+155955X0120Y0150R270 S2      
327m0349            C660  -1   M      A18X+132246Y+155675X0120Y0150R090 S2      
327m0349            C647  -1   M      A18X+132719Y+155675X0120Y0150R090 S2      
327m0349            C650  -1   M      A18X+132774Y+155955X0120Y0150R270 S2      
327m0349            C657  -1   M      A18X+132302Y+155955X0120Y0150R270 S2      
327m0349            C654  -1   M      A18X+133191Y+155675X0120Y0150R090 S2      
327m0349            C635  -1   M      A18X+133246Y+155955X0120Y0150R270 S2      
327m0350            U6010 -BD17       A01X+124437Y+155914X0120Y         S1      
327m0350            U6010 -BD20       A01X+124437Y+155717X0120Y         S1      
327m0350            U6010 -DF17       A01X+121602Y+155914X0120Y         S1      
327m0350            U6010 -DF20       A01X+121602Y+155717X0120Y         S1      
327m0350            VIA   -           A18X+118999Y+160526X0260Y         S2      
317m0350            VIA   -    MD0100PA00X+118646Y+160549X0200Y    R090 S0      
327m0350            R962  -1   M      A01X+118646Y+160549X0280Y0320R270 S1      
327m0350            R961  -2   M      A01X+118646Y+160549X0280Y0320R270 S1      
317m0350            VIA   -    MD0100PA00X+118646Y+160259X0200Y    R090 S0      
317m0350            VIA   -    MD0100PA00X+118646Y+160839X0200Y         S0      
317m0350            VIA   -    MD0100PA00X+118896Y+160914X0200Y         S0      
327m0350            C544  -1          A18X+124692Y+155955X0120Y0150R270 S2      
317m0350            VIA   -    MD0080PA00X+124692Y+155935X0160Y         S0      
317m0350            VIA   -    MD0080PA00X+124637Y+155695X0160Y         S0      
327m0350            C545  -1          A18X+124637Y+155675X0120Y0150R090 S2      
327m0350            C538  -1          A18X+121385Y+155955X0120Y0150R270 S2      
317m0350            VIA   -    MD0080PA00X+121385Y+155935X0160Y         S0      
327m0350            C542  -1          A18X+121330Y+155675X0120Y0150R090 S2      
317m0350            VIA   -    MD0080PA00X+121330Y+155695X0160Y         S0      
327m0351            C555  -1          A18X+118774Y+155682X0120Y0150     S2      
327m0351            C554  -1          A18X+119089Y+157214X0198Y0197R270 S2      
327m0351            C576  -1          A18X+118543Y+156401X0120Y0150R090 S2      
327m0351            C539  -1          A18X+119359Y+154967X0120Y0150R270 S2      
327m0351            C566  -1          A18X+127225Y+155965X0120Y0150R180 S2      
327m0351            C7008 -1          A18X+120196Y+153344X0950Y1110R180 S2      
327m0351            C7010 -1          A18X+119075Y+153325X0400Y0500R180 S2      
327m0351            C7009 -1          A18X+126444Y+153344X0950Y1110     S2      
327m0351            C565  -1          A18X+119918Y+157221X0198Y0197R090 S2      
327m0351            C568  -1          A18X+121335Y+157221X0198Y0197R090 S2      
327m0351            C579  -1          A18X+120863Y+157221X0198Y0197R090 S2      
327m0351            C586  -1          A18X+125587Y+157221X0198Y0197R090 S2      
327m0351            C567  -1          A18X+126532Y+157221X0198Y0197R090 S2      
327m0351            C571  -1          A18X+126060Y+157221X0198Y0197R090 S2      
327m0351            C575  -1          A18X+127065Y+157221X0198Y0197R090 S2      
327m0351            U6010 -T17        A01X+126327Y+155914X0120Y         S1      
327m0351            U6010 -T20        A01X+126327Y+155717X0120Y         S1      
327m0351            U6010 -AC17       A01X+125854Y+155914X0120Y         S1      
327m0351            U6010 -AC20       A01X+125854Y+155717X0120Y         S1      
327m0351            U6010 -AK17       A01X+125382Y+155914X0120Y         S1      
327m0351            U6010 -AK20       A01X+125382Y+155717X0120Y         S1      
327m0351            U6010 -AU17       A01X+124910Y+155914X0120Y         S1      
327m0351            U6010 -AU20       A01X+124910Y+155717X0120Y         S1      
327m0351            U6010 -DN17       A01X+121130Y+155914X0120Y         S1      
327m0351            U6010 -DN20       A01X+121130Y+155717X0120Y         S1      
327m0351            U6010 -DY17       A01X+120658Y+155914X0120Y         S1      
327m0351            U6010 -DY20       A01X+120658Y+155717X0120Y         S1      
327m0351            U6010 -EG17       A01X+120185Y+155914X0120Y         S1      
327m0351            U6010 -EG20       A01X+120185Y+155717X0120Y         S1      
327m0351            U6010 -EP17       A01X+119713Y+155914X0120Y         S1      
327m0351            U6010 -EP20       A01X+119713Y+155717X0120Y         S1      
327m0351            VIA   -           A18X+119076Y+158898X0260Y         S2      
327m0351            VIA   -           A18X+120972Y+159114X0260Y         S2      
327m0351            VIA   -           A18X+123943Y+159177X0260Y         S2      
327m0351            VIA   -           A18X+127164Y+159100X0260Y         S2      
327m0351            VIA   -           A18X+118009Y+157587X0260Y         S2      
327m0351            L12   -2   M      A01X+117447Y+158502X0420Y0990R270 S1      
317m0351            VIA   -    MD0100PA00X+117054Y+158375X0200Y    R090 S0      
317m0351            VIA   -    MD0100PA00X+117304Y+158375X0200Y    R090 S0      
317m0351            VIA   -    MD0100PA00X+117554Y+158375X0200Y    R090 S0      
317m0351            VIA   -    MD0100PA00X+117804Y+158375X0200Y    R090 S0      
317m0351            VIA   -    MD0100PA00X+117054Y+158625X0200Y    R090 S0      
317m0351            VIA   -    MD0100PA00X+117304Y+158625X0200Y    R090 S0      
317m0351            VIA   -    MD0100PA00X+117554Y+158625X0200Y    R090 S0      
317m0351            VIA   -    MD0100PA00X+117804Y+158625X0200Y    R090 S0      
317m0351            VIA   -    MD0100PA00X+117804Y+158875X0200Y    R090 S0      
317m0351            VIA   -    MD0100PA00X+117554Y+158875X0200Y    R090 S0      
317m0351            VIA   -    MD0100PA00X+117304Y+158875X0200Y    R090 S0      
317m0351            VIA   -    MD0100PA00X+118092Y+158625X0200Y    R090 S0      
317m0351            VIA   -    MD0100PA00X+118092Y+158875X0200Y    R090 S0      
317m0351            VIA   -    MD0100PA00X+116802Y+158875X0200Y    R090 S0      
317m0351            VIA   -    MD0100PA00X+117054Y+158875X0200Y    R090 S0      
317m0351            VIA   -    MD0100PA00X+116802Y+158625X0200Y    R090 S0      
327m0351            C564  -1          A01X+119283Y+159210X0400Y0500R180 S1      
327m0351            C556  -1          A01X+119281Y+159895X0400Y0500R180 S1      
327m0351            R962  -2          A01X+119226Y+160549X0280Y0320R270 S1      
327m0351            C550  -1          A18X+127942Y+157558X0400Y0500     S2      
327m0351            C572  -1          A18X+124642Y+157221X0198Y0197R090 S2      
327m0351            C584  -1          A18X+125115Y+157221X0198Y0197R090 S2      
327m0351            C557  -1          A18X+120390Y+157221X0198Y0197R090 S2      
327m0351            C561  -1          A18X+119445Y+157221X0198Y0197R090 S2      
327m0351            C560  -1          A18X+127942Y+156872X0400Y0500     S2      
327m0351            C577  -1          A18X+127001Y+155675X0120Y0150R090 S2      
327m0351            C582  -1   M      A18X+125637Y+155955X0120Y0150R270 S2      
327m0351            C570  -1   M      A18X+125582Y+155675X0120Y0150R090 S2      
327m0351            C583  -1   M      A18X+125165Y+155955X0120Y0150R270 S2      
327m0351            C529  -1   M      A18X+125110Y+155675X0120Y0150R090 S2      
327m0351            C585  -1   M      A18X+126582Y+155955X0120Y0150R270 S2      
327m0351            C541  -1   M      A18X+126110Y+155955X0120Y0150R270 S2      
327m0351            C525  -1   M      A18X+126527Y+155675X0120Y0150R090 S2      
327m0351            C573  -1   M      A18X+126054Y+155675X0120Y0150R090 S2      
317m0351            VIA   -    MD0080PA00X+126054Y+155695X0160Y         S0      
317m0351            VIA   -    MD0080PA00X+126110Y+155935X0160Y         S0      
317m0351            VIA   -    MD0080PA00X+126582Y+155935X0160Y         S0      
317m0351            VIA   -    MD0080PA00X+125637Y+155935X0160Y         S0      
317m0351            VIA   -    MD0080PA00X+125582Y+155695X0160Y         S0      
317m0351            VIA   -    MD0080PA00X+126527Y+155695X0160Y         S0      
317m0351            VIA   -    MD0080PA00X+125110Y+155695X0160Y         S0      
317m0351            VIA   -    MD0080PA00X+125165Y+155935X0160Y         S0      
317m0351            VIA   -    MD0080PA00X+120385Y+155695X0160Y         S0      
317m0351            VIA   -    MD0080PA00X+119913Y+155695X0160Y         S0      
317m0351            VIA   -    MD0080PA00X+120913Y+155935X0160Y         S0      
317m0351            VIA   -    MD0080PA00X+119495Y+155935X0160Y         S0      
317m0351            VIA   -    MD0080PA00X+119968Y+155935X0160Y         S0      
317m0351            VIA   -    MD0080PA00X+120440Y+155935X0160Y         S0      
317m0351            VIA   -    MD0080PA00X+119440Y+155695X0160Y         S0      
317m0351            VIA   -    MD0080PA00X+120858Y+155695X0160Y         S0      
327m0351            C581  -1   M      A18X+120858Y+155675X0120Y0150R090 S2      
327m0351            C526  -1   M      A18X+120385Y+155675X0120Y0150R090 S2      
327m0351            C558  -1   M      A18X+120913Y+155955X0120Y0150R270 S2      
327m0351            C523  -1   M      A18X+119968Y+155955X0120Y0150R270 S2      
327m0351            C543  -1   M      A18X+120440Y+155955X0120Y0150R270 S2      
327m0351            C521  -1   M      A18X+119440Y+155675X0120Y0150R090 S2      
327m0351            C562  -1   M      A18X+119913Y+155675X0120Y0150R090 S2      
327m0351            C580  -1   M      A18X+119495Y+155955X0120Y0150R270 S2      
317m0352            VIA   -    MD0080PA00X+153747Y+154036X0160Y         S0      
317m0352            VIA   -    MD0080PA00X+153537Y+154036X0160Y         S0      
327m0352            VIA   -           A18X+154270Y+154060X0260Y         S2      
327m0352            U6013 -A35        A01X+153787Y+154246X0100Y0130     S1      
327m0352            R1125 -1          A18X+154680Y+154040X0120Y0150R180 S2      
327m0352            U6013 -D35 M      A01X+153550Y+154246X0100Y0130     S1      
327m0352            U6013 -C34        A01X+153668Y+154450X0120Y         S1      
317m0352            VIA   -    MD0080PA00X+153858Y+157166X0160Y         S0      
327m0352            U6013 -D1         A01X+153550Y+157348X0100Y0130     S1      
327m0352            U6013 -C2  M      A01X+153668Y+157143X0120Y         S1      
327m0352            U6013 -FG1 M      A01X+145283Y+157348X0100Y0130     S1      
327m0352            U6013 -FE2        A01X+145401Y+157143X0120Y         S1      
317m0352            VIA   -    MD0080PA00X+145510Y+157762X0160Y         S0      
327m0352            U6013 -FH2        A01X+145164Y+157143X0120Y         S1      
317m0352            VIA   -    MD0080PA00X+145103Y+157332X0160Y         S0      
327m0352            U6013 -FG35       A01X+145283Y+154246X0100Y0130     S1      
317m0352            VIA   -    MD0080PA00X+145283Y+154051X0160Y         S0      
327m0352            U6013 -FE34       A01X+145401Y+154450X0120Y         S1      
327m0352            U6013 -FH34M      A01X+145164Y+154450X0120Y         S1      
317m0352            VIA   -    MD0080PA00X+145063Y+154051X0160Y         S0      
317m0353            VIA   -    MD0080PA00X+157869Y+154051X0160Y         S0      
317m0353            VIA   -    MD0080PA00X+157909Y+157332X0160Y         S0      
317m0353            VIA   -    MD0080PA00X+166553Y+154036X0160Y         S0      
317m0353            VIA   -    MD0080PA00X+166343Y+154036X0160Y         S0      
317m0353            VIA   -    MD0080PA00X+158094Y+154046X0160Y         S0      
317m0353            VIA   -    MD0080PA00X+158316Y+157762X0160Y         S0      
317m0353            VIA   -    MD0080PA00X+166665Y+157166X0160Y         S0      
327m0353            U6012 -D1         A01X+166357Y+157348X0100Y0130     S1      
327m0353            U6012 -C2  M      A01X+166475Y+157143X0120Y         S1      
327m0353            VIA   -           A18X+166803Y+154122X0260Y         S2      
327m0353            R1083 -1          A18X+167133Y+154207X0120Y0150R180 S2      
327m0353            U6012 -FE2        A01X+158207Y+157143X0120Y         S1      
327m0353            U6012 -FG1 M      A01X+158089Y+157348X0100Y0130     S1      
327m0353            U6012 -FH2        A01X+157971Y+157143X0120Y         S1      
327m0353            U6012 -A35        A01X+166593Y+154246X0100Y0130     S1      
327m0353            U6012 -D35 M      A01X+166357Y+154246X0100Y0130     S1      
327m0353            U6012 -C34        A01X+166475Y+154450X0120Y         S1      
327m0353            U6012 -FG35       A01X+158089Y+154246X0100Y0130     S1      
327m0353            U6012 -FH34M      A01X+157971Y+154450X0120Y         S1      
327m0353            U6012 -FE34       A01X+158207Y+154450X0120Y         S1      
317m0354            VIA   -    MD0080PA00X+131452Y+154051X0160Y         S0      
317m0354            VIA   -    MD0080PA00X+140247Y+157166X0160Y         S0      
317m0354            VIA   -    MD0080PA00X+131492Y+157332X0160Y         S0      
317m0354            VIA   -    MD0080PA00X+140136Y+154036X0160Y         S0      
317m0354            VIA   -    MD0080PA00X+139926Y+154036X0160Y         S0      
317m0354            VIA   -    MD0080PA00X+131677Y+154046X0160Y         S0      
317m0354            VIA   -    MD0080PA00X+131899Y+157762X0160Y         S0      
327m0354            U6011 -D1         A01X+139939Y+157348X0100Y0130     S1      
327m0354            U6011 -C2  M      A01X+140057Y+157143X0120Y         S1      
327m0354            R1042 -1          A18X+141068Y+154040X0120Y0150R180 S2      
327m0354            VIA   -           A18X+140557Y+154051X0260Y         S2      
327m0354            U6011 -FE2        A01X+131790Y+157143X0120Y         S1      
327m0354            U6011 -FG1 M      A01X+131672Y+157348X0100Y0130     S1      
327m0354            U6011 -FH2        A01X+131553Y+157143X0120Y         S1      
327m0354            U6011 -FG35       A01X+131672Y+154246X0100Y0130     S1      
327m0354            U6011 -A35        A01X+140175Y+154246X0100Y0130     S1      
327m0354            U6011 -D35 M      A01X+139939Y+154246X0100Y0130     S1      
327m0354            U6011 -C34        A01X+140057Y+154450X0120Y         S1      
327m0354            U6011 -FH34M      A01X+131553Y+154450X0120Y         S1      
327m0354            U6011 -FE34       A01X+131790Y+154450X0120Y         S1      
317m0355            VIA   -    MD0080PA00X+118645Y+154051X0160Y         S0      
317m0355            VIA   -    MD0080PA00X+127441Y+157166X0160Y         S0      
317m0355            VIA   -    MD0080PA00X+127119Y+154036X0160Y         S0      
317m0355            VIA   -    MD0080PA00X+118865Y+154051X0160Y         S0      
317m0355            VIA   -    MD0080PA00X+119092Y+157762X0160Y         S0      
317m0355            VIA   -    MD0080PA00X+118685Y+157332X0160Y         S0      
317m0355            VIA   -    MD0080PA00X+127329Y+154036X0160Y         S0      
327m0355            U6010 -D1         A01X+127133Y+157348X0100Y0130     S1      
327m0355            U6010 -C2  M      A01X+127251Y+157143X0120Y         S1      
327m0355            U6010 -FE2        A01X+118983Y+157143X0120Y         S1      
327m0355            U6010 -FG1 M      A01X+118865Y+157348X0100Y0130     S1      
327m0355            U6010 -FH2        A01X+118747Y+157143X0120Y         S1      
327m0355            U6010 -FG35       A01X+118865Y+154246X0100Y0130     S1      
327m0355            VIA   -           A18X+127698Y+154054X0260Y         S2      
327m0355            U6010 -A35        A01X+127369Y+154246X0100Y0130     S1      
327m0355            R6821 -1          A18X+128262Y+154040X0120Y0150R180 S2      
327m0355            U6010 -D35 M      A01X+127133Y+154246X0100Y0130     S1      
327m0355            U6010 -C34        A01X+127251Y+154450X0120Y         S1      
327m0355            U6010 -FH34M      A01X+118747Y+154450X0120Y         S1      
327m0355            U6010 -FE34       A01X+118983Y+154450X0120Y         S1      
327m0356            VIA   -           A01X+153175Y+159819X0300Y         S1      
327m0356            U6013 -A1         A01X+153787Y+157348X0100Y0130     S1      
327m0356            R1126 -1   M      A01X+154363Y+158735X0120Y0150R270 S1      
327m0357            VIA   -           A01X+168606Y+157389X0300Y         S1      
327m0357            U6012 -A1         A01X+166593Y+157348X0100Y0130     S1      
327m0357            R1084 -1   M      A01X+167169Y+158665X0120Y0150R270 S1      
327m0358            VIA   -           A01X+139901Y+159888X0300Y         S1      
327m0358            U6011 -A1         A01X+140175Y+157348X0100Y0130     S1      
327m0358            R1043 -1   M      A01X+140752Y+158665X0120Y0150R270 S1      
327m0359            VIA   -           A01X+126753Y+159862X0300Y         S1      
327m0359            U6010 -A1         A01X+127369Y+157348X0100Y0130     S1      
327m0359            R6820 -1   M      A01X+127945Y+158735X0120Y0150R270 S1      
327m0360            VIA   -           A01X+145221Y+159408X0300Y         S1      
327m0360            R1122 -2   M      A01X+145118Y+158879X0120Y0150R090 S1      
327m0360            R1091 -1   M      A01X+145118Y+158589X0120Y0150R270 S1      
327m0360            U6013 -FJ9        A01X+145150Y+156462X0100Y0130R090 S1      
327m0361            VIA   -           A01X+158027Y+159408X0300Y         S1      
327m0361            R1080 -2   M      A01X+157925Y+158879X0120Y0150R090 S1      
327m0361            R1048 -1   M      A01X+157925Y+158589X0120Y0150R270 S1      
327m0361            U6012 -FJ9        A01X+157957Y+156462X0100Y0130R090 S1      
327m0362            VIA   -           A01X+131610Y+159408X0300Y         S1      
327m0362            R1039 -2   M      A01X+131507Y+158879X0120Y0150R090 S1      
327m0362            R1006 -1   M      A01X+131507Y+158589X0120Y0150R270 S1      
327m0362            U6011 -FJ9        A01X+131539Y+156462X0100Y0130R090 S1      
327m0363            VIA   -    M      A01X+117577Y+156800X0300Y         S1      
327m0363            R998  -2          A01X+116687Y+157105X0120Y0150R270 S1      
327m0363            U6010 -FJ9        A01X+118733Y+156462X0100Y0130R090 S1      
327m0363            R1001 -1   M      A01X+117042Y+157100X0120Y0150     S1      
327m0364            U6013 -FF8        A01X+145355Y+156580X0120Y         S1      
327m0364            VIA   -    M      A01X+145876Y+158883X0300Y         S1      
327m0364            R1108 -2          A01X+145546Y+159294X0120Y0150R090 S1      
327m0364            R1121 -1   M      A01X+145546Y+159004X0120Y0150R270 S1      
327m0365            U6012 -FF8        A01X+158161Y+156580X0120Y         S1      
327m0365            VIA   -    M      A01X+158682Y+158883X0300Y         S1      
327m0365            R1066 -2          A01X+158352Y+159294X0120Y0150R090 S1      
327m0365            R1079 -1   M      A01X+158352Y+159004X0120Y0150R270 S1      
327m0366            U6011 -FF8        A01X+131744Y+156580X0120Y         S1      
327m0366            VIA   -    M      A01X+132264Y+158883X0300Y         S1      
327m0366            R1024 -2          A01X+131935Y+159294X0120Y0150R090 S1      
327m0366            R1037 -1   M      A01X+131935Y+159004X0120Y0150R270 S1      
327m0367            VIA   -    M      A01X+117577Y+157300X0300Y         S1      
327m0367            R975  -2          A01X+116687Y+157435X0120Y0150R090 S1      
327m0367            U6010 -FF8        A01X+118938Y+156580X0120Y         S1      
327m0367            R997  -1   M      A01X+117042Y+157550X0120Y0150     S1      
327m0368            VIA   -           A01X+143821Y+154731X0300Y         S1      
327m0368            U6013 -FJ28       A01X+145150Y+155044X0100Y0130R090 S1      
327m0368            R1113 -1   M      A01X+144134Y+154742X0120Y0150     S1      
327m0369            VIA   -           A01X+156627Y+154731X0300Y         S1      
327m0369            U6012 -FJ28       A01X+157957Y+155044X0100Y0130R090 S1      
327m0369            R1072 -1   M      A01X+156940Y+154742X0120Y0150     S1      
327m0370            VIA   -           A01X+130210Y+154731X0300Y         S1      
327m0370            U6011 -FJ28       A01X+131539Y+155044X0100Y0130R090 S1      
327m0370            R1029 -1   M      A01X+130522Y+154742X0120Y0150     S1      
327m0371            VIA   -           A01X+117405Y+154742X0300Y         S1      
327m0371            R980  -1   M      A01X+117716Y+154742X0120Y0150     S1      
327m0371            U6010 -FJ28       A01X+118733Y+155044X0100Y0130R090 S1      
327m0372            VIA   -           A01X+142980Y+155776X0300Y         S1      
327m0372            R1111 -2   M      A01X+143844Y+155064X0120Y0150R180 S1      
327m0372            U6013 -FJ25       A01X+145150Y+155281X0100Y0130R090 S1      
327m0372            R1112 -1   M      A01X+144134Y+155104X0120Y0150     S1      
327m0373            VIA   -           A01X+156151Y+155320X0300Y         S1      
327m0373            R1069 -2   M      A01X+156650Y+155064X0120Y0150R180 S1      
327m0373            U6012 -FJ25       A01X+157957Y+155281X0100Y0130R090 S1      
327m0373            R1070 -1   M      A01X+156940Y+155104X0120Y0150     S1      
327m0374            VIA   -           A01X+129733Y+155320X0300Y         S1      
327m0374            R1027 -2   M      A01X+130232Y+155064X0120Y0150R180 S1      
327m0374            U6011 -FJ25       A01X+131539Y+155281X0100Y0130R090 S1      
327m0374            R1028 -1   M      A01X+130522Y+155104X0120Y0150     S1      
327m0375            VIA   -           A01X+116669Y+155537X0300Y         S1      
327m0375            R978  -2   M      A01X+117426Y+155104X0120Y0150R180 S1      
327m0375            U6010 -FJ25       A01X+118733Y+155281X0100Y0130R090 S1      
327m0375            R979  -1   M      A01X+117716Y+155104X0120Y0150     S1      
327U21_E2           VIA   -    M      A01X+066797Y+168542X0300Y         S1      
327U21_E2           R6791 -1          A01X+066731Y+168906X0120Y0150R180 S1      
327U21_E2           U21   -3          A01X+066797Y+167902X0350Y0500R180 S1      
317U20_E2           VIA   -    M      A01X+064304Y+168288X0200Y         S2      
017U20_E2           VIA   -    M      A18X+064304Y+168288X0260Y         S2      
017U20_E2                 -    MD0100PA00X+064304Y+168288                       
327U20_E2           R6790 -1          A01X+064346Y+168597X0120Y0150R180 S1      
327U20_E2           U20   -3          A01X+064428Y+167880X0350Y0500R180 S1      
317U19_E2           VIA   -    M      A01X+042995Y+159440X0200Y         S2      
017U19_E2           VIA   -    M      A18X+042995Y+159440X0260Y         S2      
017U19_E2                 -    MD0100PA00X+042995Y+159440                       
327U19_E2           U19   -3          A01X+043037Y+159028X0350Y0500R180 S1      
327U19_E2           R6789 -1          A01X+043149Y+159698X0120Y0150R180 S1      
317U12_E2           VIA   -    M      A01X+040467Y+159432X0200Y         S2      
017U12_E2           VIA   -    M      A18X+040467Y+159432X0260Y         S2      
017U12_E2                 -    MD0100PA00X+040467Y+159432                       
327U12_E2           R6788 -1          A01X+040300Y+159856X0120Y0150R180 S1      
327U12_E2           U12   -3          A01X+040538Y+159028X0350Y0500R180 S1      
317U206_VS          VIA   -    M      A01X+058951Y+046256X0200Y         S2      
017U206_VS          VIA   -    M      A18X+058951Y+046256X0260Y         S2      
017U206_VS                -    MD0100PA00X+058951Y+046256                       
327U206_VS          U206  -5          A01X+060689Y+046509X0250Y0480R270 S1      
327U206_VS          C1561 -1   M      A01X+060007Y+046435X0198Y0197R180 S1      
327U206_VS          R9021 -2   M      A01X+058650Y+046442X0198Y0197R270 S1      
327U206_VS          C9004 -1          A01X+058650Y+046108X0198Y0197R270 S1      
327U142_VS          U142  -5          A18X+070537Y+166963X0250Y0480     S2      
327U142_VS          VIA   -    M      A18X+070728Y+166364X0260Y         S2      
327U142_VS          C6084 -1   M      A18X+070582Y+166053X0198Y0197R090 S2      
327U142_VS          R9020 -2          A18X+071377Y+166054X0198Y0197R270 S2      
327U142_VS          C9003 -1   M      A18X+070977Y+166054X0198Y0197R090 S2      
327m0376            U6017 -FF30       A01X+044568Y+151626X0120Y         S1      
327m0376            VIA   -           A01X+042478Y+151391X0300Y         S1      
327m0376            R922  -2   M      A01X+042956Y+151080X0120Y0150R180 S1      
327m0376            R923  -1   M      A01X+043346Y+151080X0120Y0150     S1      
327m0377            VIA   -           A01X+055340Y+151431X0300Y         S1      
327m0377            U6016 -FF30       A01X+057374Y+151626X0120Y         S1      
327m0377            R883  -1   M      A01X+056152Y+151080X0120Y0150     S1      
327m0377            R882  -2   M      A01X+055762Y+151080X0120Y0150R180 S1      
317m0378            VIA   -    MD0080PA00X+044126Y+151812X0160Y         S0      
327m0378            R920  -2          A18X+043056Y+151442X0120Y0150     S2      
327m0378            R921  -1   M      A18X+043346Y+151442X0120Y0150R180 S2      
327m0378            U6017 -FF27       A01X+044568Y+151863X0120Y         S1      
327m0378            VIA   -    M      A18X+044126Y+151530X0260Y         S2      
317m0379            VIA   -    MD0080PA00X+056932Y+151812X0160Y         S0      
327m0379            R880  -2          A18X+055862Y+151442X0120Y0150     S2      
327m0379            R881  -1   M      A18X+056152Y+151442X0120Y0150R180 S2      
327m0379            U6016 -FF27       A01X+057374Y+151863X0120Y         S1      
327m0379            VIA   -    M      A18X+056932Y+151530X0260Y         S2      
317m0380            VIA   -    MD0080PA00X+044166Y+152161X0160Y         S0      
327m0380            R918  -2          A18X+043056Y+151804X0120Y0150     S2      
327m0380            R919  -1   M      A18X+043346Y+151804X0120Y0150R180 S2      
327m0380            VIA   -    M      A18X+043948Y+152019X0260Y         S2      
327m0380            U6017 -FF24       A01X+044568Y+152099X0120Y         S1      
317m0381            VIA   -    MD0080PA00X+056972Y+152161X0160Y         S0      
327m0381            R878  -2          A18X+055862Y+151804X0120Y0150     S2      
327m0381            R879  -1   M      A18X+056152Y+151804X0120Y0150R180 S2      
327m0381            U6016 -FF24       A01X+057374Y+152099X0120Y         S1      
327m0381            VIA   -    M      A18X+056754Y+152019X0260Y         S2      
327m0382            U193  -14         A01X+128074Y+014005X0150Y0630R090 S1      
327m0382            R1792 -2          A01X+129512Y+014174X0198Y0197R180 S1      
327m0382            VIA   -    M      A01X+129019Y+014174X0300Y         S1      
327m0383            U193  -13         A01X+128074Y+013755X0150Y0630R090 S1      
327m0383            R1793 -2          A01X+129512Y+013774X0198Y0197R180 S1      
327m0383            VIA   -    M      A01X+128769Y+013724X0300Y         S1      
327m0384            U6020 -8          A18X+087209Y+133000X0120Y0630R270 S2      
327m0384            R6746 -2          A18X+085805Y+133300X0120Y0150     S2      
327m0384            VIA   -    M      A18X+086100Y+133250X0260Y         S2      
327m0385            U6020 -9          A18X+087209Y+133256X0120Y0630R270 S2      
327m0385            R6747 -2          A18X+085805Y+133700X0120Y0150     S2      
327m0385            VIA   -    M      A18X+086100Y+133750X0260Y         S2      
327m0386            R6746 -1          A18X+085595Y+133300X0120Y0150R180 S2      
327m0386            R914  -1          A18X+084405Y+133300X0120Y0150     S2      
327m0386            VIA   -    M      A18X+084702Y+133204X0260Y         S2      
327m0386            R6750 -2   M      A18X+085050Y+133355X0120Y0150R090 S2      
327m0387            R6747 -1          A18X+085595Y+133700X0120Y0150R180 S2      
327m0387            R913  -1          A18X+084405Y+133700X0120Y0150     S2      
327m0387            VIA   -    M      A18X+084703Y+133739X0260Y         S2      
327m0387            R6751 -2   M      A18X+085050Y+133645X0120Y0150R270 S2      
327m0388            U22   -8          A18X+096246Y+133000X0120Y0630R270 S2      
327m0388            VIA   -    M      A18X+095137Y+133250X0260Y         S2      
327m0388            R806  -2          A18X+094055Y+133250X0120Y0150     S2      
327m0388            R1399 -2   M      A18X+094345Y+133250X0120Y0150R180 S2      
327m0389            U22   -9          A18X+096246Y+133256X0120Y0630R270 S2      
327m0389            VIA   -    M      A18X+095137Y+133750X0260Y         S2      
327m0389            R807  -2          A18X+094055Y+133700X0120Y0150     S2      
327m0389            R1402 -2   M      A18X+094345Y+133700X0120Y0150R180 S2      
317m0390            VIA   -    MD0080PA00X+053094Y+151634X0160Y         S0      
317m0390            VIA   -    M      A01X+083896Y+134597X0200Y         S2      
017m0390            VIA   -    M      A18X+083896Y+134597X0260Y         S2      
017m0390                  -    MD0100PA00X+083896Y+134597                       
327m0390            U6017 -B28        A01X+052935Y+151744X0100Y0130R090 S1      
327m0390            R914  -2          A18X+084195Y+133300X0120Y0150R180 S2      
317m0391            VIA   -    MD0080PA00X+053100Y+151407X0160Y         S0      
327m0391            R913  -2          A18X+084195Y+133700X0120Y0150R180 S2      
327m0391            U6017 -B31        A01X+052935Y+151508X0100Y0130R090 S1      
317m0391            VIA   -    M      A01X+083924Y+135209X0200Y         S2      
017m0391            VIA   -    M      A18X+083924Y+135209X0260Y         S2      
017m0391                  -    MD0100PA00X+083924Y+135209                       
327m0392            VIA   -    M      A18X+086533Y+134132X0260Y         S2      
327m0392            R6748 -2          A18X+085955Y+134200X0120Y0150     S2      
327m0392            U6020 -10         A18X+087209Y+133512X0120Y0630R270 S2      
327m0393            VIA   -    M      A18X+086250Y+134600X0260Y         S2      
327m0393            R6749 -2          A18X+085955Y+134600X0120Y0150     S2      
327m0393            U6020 -11         A18X+087209Y+133768X0120Y0630R270 S2      
327m0394            VIA   -    M      A18X+085075Y+134200X0260Y         S2      
327m0394            R873  -1          A18X+084775Y+134200X0120Y0150     S2      
327m0394            R6748 -1          A18X+085745Y+134200X0120Y0150R180 S2      
327m0394            R6752 -2   M      A18X+085400Y+134255X0120Y0150R090 S2      
327m0395            R872  -1          A18X+084775Y+134600X0120Y0150     S2      
327m0395            VIA   -    M      A18X+085076Y+134709X0260Y         S2      
327m0395            R6753 -2   M      A18X+085400Y+134545X0120Y0150R270 S2      
327m0395            R6749 -1          A18X+085745Y+134600X0120Y0150R180 S2      
327m0396            U22   -10         A18X+096246Y+133512X0120Y0630R270 S2      
327m0396            VIA   -    M      A18X+095487Y+134150X0260Y         S2      
327m0396            R808  -2          A18X+094055Y+134150X0120Y0150     S2      
327m0396            R1403 -2   M      A18X+094345Y+134150X0120Y0150R180 S2      
327m0397            U22   -11         A18X+096246Y+133768X0120Y0630R270 S2      
327m0397            VIA   -    M      A18X+095487Y+134650X0260Y         S2      
327m0397            R809  -2          A18X+094055Y+134600X0120Y0150     S2      
327m0397            R1407 -2   M      A18X+094345Y+134600X0120Y0150R180 S2      
317m0398            VIA   -    MD0080PA00X+065901Y+151634X0160Y         S0      
327m0398            R873  -2          A18X+084565Y+134200X0120Y0150R180 S2      
317m0398            VIA   -    M      A01X+084104Y+135808X0200Y         S2      
017m0398            VIA   -    M      A18X+084104Y+135808X0260Y         S2      
017m0398                  -    MD0100PA00X+084104Y+135808                       
327m0398            U6016 -B28        A01X+065741Y+151744X0100Y0130R090 S1      
317m0399            VIA   -    MD0080PA00X+065906Y+151407X0160Y         S0      
317m0399            VIA   -    M      A01X+084147Y+136505X0200Y         S2      
017m0399            VIA   -    M      A18X+084147Y+136505X0260Y         S2      
017m0399                  -    MD0100PA00X+084147Y+136505                       
327m0399            R872  -2          A18X+084565Y+134600X0120Y0150R180 S2      
327m0399            U6016 -B31        A01X+065741Y+151508X0100Y0130R090 S1      
327m0400            R803  -2          A18X+094055Y+132350X0120Y0150     S2      
327m0400            R1393 -2   M      A18X+094345Y+132350X0120Y0150R180 S2      
327m0400            U22   -6          A18X+096246Y+132489X0120Y0630R270 S2      
327m0400            VIA   -    M      A18X+095537Y+132350X0260Y         S2      
327m0401            U22   -7          A18X+096246Y+132745X0120Y0630R270 S2      
327m0401            VIA   -    M      A18X+095537Y+132850X0260Y         S2      
327m0401            R805  -2          A18X+094055Y+132800X0120Y0150     S2      
327m0401            R1394 -2   M      A18X+094345Y+132800X0120Y0150R180 S2      
327m0402            VIA   -    M      A18X+095087Y+131450X0260Y         S2      
327m0402            U22   -4          A18X+096246Y+131977X0120Y0630R270 S2      
327m0402            R801  -2          A18X+094055Y+131450X0120Y0150     S2      
327m0402            R1361 -2   M      A18X+094345Y+131450X0120Y0150R180 S2      
327m0403            U22   -5          A18X+096246Y+132233X0120Y0630R270 S2      
327m0403            VIA   -    M      A18X+095087Y+131950X0260Y         S2      
327m0403            R802  -2          A18X+094055Y+131900X0120Y0150     S2      
327m0403            R1390 -2   M      A18X+094345Y+131900X0120Y0150R180 S2      
327m0404            U6020 -17         A18X+089414Y+133000X0120Y0630R270 S2      
327m0404            R6758 -1          A18X+090385Y+132800X0120Y0150R180 S2      
327m0404            VIA   -    M      A18X+090089Y+133000X0260Y    R180 S2      
327m0405            U6020 -18         A18X+089414Y+132745X0120Y0630R270 S2      
327m0405            R6759 -1          A18X+090385Y+132400X0120Y0150R180 S2      
327m0405            VIA   -    M      A18X+090089Y+132490X0260Y    R180 S2      
327m0406            VIA   -    M      A18X+090889Y+132800X0260Y         S2      
327m0406            R6758 -2          A18X+090595Y+132800X0120Y0150     S2      
327m0406            R1110 -1          A18X+091695Y+132800X0120Y0150R180 S2      
327m0406            R6766 -2   M      A18X+091200Y+132745X0120Y0150R270 S2      
327m0407            R6759 -2          A18X+090595Y+132400X0120Y0150     S2      
327m0407            VIA   -    M      A18X+090889Y+132280X0260Y         S2      
327m0407            R1109 -1          A18X+091695Y+132400X0120Y0150R180 S2      
327m0407            R6767 -2   M      A18X+091200Y+132455X0120Y0150R090 S2      
327m0408            U22   -17         A18X+098451Y+133000X0120Y0630R270 S2      
327m0408            VIA   -    M      A18X+099200Y+133100X0260Y    R180 S2      
327m0408            R830  -1          A18X+100645Y+132826X0120Y0150R180 S2      
327m0408            R1375 -2   M      A18X+100355Y+132826X0120Y0150     S2      
327m0409            U22   -18         A18X+098451Y+132745X0120Y0630R270 S2      
327m0409            VIA   -    M      A18X+099650Y+132605X0260Y    R180 S2      
327m0409            R831  -1          A18X+100645Y+132384X0120Y0150R180 S2      
327m0409            R1379 -2   M      A18X+100355Y+132384X0120Y0150     S2      
327m0410            U6020 -19         A18X+089414Y+132489X0120Y0630R270 S2      
327m0410            R6760 -1          A18X+090715Y+131900X0120Y0150R180 S2      
327m0410            VIA   -    M      A18X+090402Y+132089X0260Y    R180 S2      
327m0411            U6020 -20         A18X+089414Y+132233X0120Y0630R270 S2      
327m0411            R6761 -1          A18X+090715Y+131500X0120Y0150R180 S2      
327m0411            VIA   -    M      A18X+090329Y+131582X0260Y    R180 S2      
327m0412            R6760 -2          A18X+090925Y+131900X0120Y0150     S2      
327m0412            VIA   -    M      A18X+091239Y+131900X0260Y         S2      
327m0412            R1068 -1          A18X+091945Y+131900X0120Y0150R180 S2      
327m0412            R6768 -2   M      A18X+091550Y+131845X0120Y0150R270 S2      
327m0413            R6761 -2          A18X+090925Y+131500X0120Y0150     S2      
327m0413            VIA   -    M      A18X+091237Y+131388X0260Y         S2      
327m0413            R1067 -1          A18X+091945Y+131500X0120Y0150R180 S2      
327m0413            R6769 -2   M      A18X+091550Y+131555X0120Y0150R090 S2      
327m0414            U22   -19         A18X+098451Y+132489X0120Y0630R270 S2      
327m0414            VIA   -    M      A18X+099150Y+132350X0260Y    R180 S2      
327m0414            R832  -1          A18X+100645Y+131942X0120Y0150R180 S2      
327m0414            R1382 -2   M      A18X+100355Y+131942X0120Y0150     S2      
327m0415            R833  -1          A18X+100645Y+131500X0120Y0150R180 S2      
327m0415            R1383 -2   M      A18X+100355Y+131500X0120Y0150     S2      
327m0415            U22   -20         A18X+098451Y+132233X0120Y0630R270 S2      
327m0415            VIA   -    M      A18X+099600Y+131850X0260Y    R180 S2      
327m0416            U6020 -15         A18X+089414Y+133512X0120Y0630R270 S2      
327m0416            R6756 -1          A18X+090715Y+133700X0120Y0150R180 S2      
327m0416            VIA   -    M      A18X+090092Y+133772X0260Y    R180 S2      
327m0417            R6757 -1          A18X+090715Y+133300X0120Y0150R180 S2      
327m0417            U6020 -16         A18X+089414Y+133256X0120Y0630R270 S2      
327m0417            VIA   -    M      A18X+090422Y+133384X0260Y    R180 S2      
327m0418            R6756 -2          A18X+090925Y+133700X0120Y0150     S2      
327m0418            VIA   -    M      A18X+091222Y+133751X0260Y         S2      
327m0418            R1026 -1          A18X+091945Y+133700X0120Y0150R180 S2      
327m0418            R6764 -2   M      A18X+091550Y+133645X0120Y0150R270 S2      
327m0419            R6757 -2          A18X+090925Y+133300X0120Y0150     S2      
327m0419            VIA   -    M      A18X+091221Y+133247X0260Y         S2      
327m0419            R6765 -2   M      A18X+091550Y+133355X0120Y0150R090 S2      
327m0419            R1025 -1          A18X+091945Y+133300X0120Y0150R180 S2      
327m0420            U22   -15         A18X+098451Y+133512X0120Y0630R270 S2      
327m0420            VIA   -    M      A18X+099350Y+133937X0260Y    R180 S2      
327m0420            R828  -1          A18X+100645Y+133716X0120Y0150R180 S2      
327m0420            R1371 -2   M      A18X+100355Y+133716X0120Y0150     S2      
327m0421            VIA   -    M      A18X+099650Y+133495X0260Y    R180 S2      
327m0421            U22   -16         A18X+098451Y+133256X0120Y0630R270 S2      
327m0421            R1374 -2   M      A18X+100355Y+133274X0120Y0150     S2      
327m0421            R829  -1          A18X+100645Y+133274X0120Y0150R180 S2      
327m0422            R6754 -1          A18X+090385Y+134600X0120Y0150R180 S2      
327m0422            U6020 -13         A18X+089414Y+134024X0120Y0630R270 S2      
327m0422            VIA   -    M      A18X+089687Y+134600X0260Y    R180 S2      
327m0423            R6755 -1          A18X+090385Y+134200X0120Y0150R180 S2      
327m0423            U6020 -14         A18X+089414Y+133768X0120Y0630R270 S2      
327m0423            VIA   -    M      A18X+090089Y+134281X0260Y    R180 S2      
327m0424            VIA   -    M      A18X+090891Y+134642X0260Y         S2      
327m0424            R6754 -2          A18X+090595Y+134600X0120Y0150     S2      
327m0424            R977  -1          A18X+091695Y+134600X0120Y0150R180 S2      
327m0424            R6762 -2   M      A18X+091200Y+134545X0120Y0150R270 S2      
327m0425            R6755 -2          A18X+090595Y+134200X0120Y0150     S2      
327m0425            VIA   -    M      A18X+090889Y+134134X0260Y         S2      
327m0425            R976  -1          A18X+091695Y+134200X0120Y0150R180 S2      
327m0425            R6763 -2   M      A18X+091200Y+134255X0120Y0150R090 S2      
327m0426            R1366 -2   M      A18X+100355Y+134600X0120Y0150     S2      
327m0426            R797  -1          A18X+100645Y+134600X0120Y0150R180 S2      
327m0426            VIA   -    M      A18X+099594Y+134906X0260Y    R180 S2      
327m0426            U22   -13         A18X+098451Y+134024X0120Y0630R270 S2      
327m0427            R1367 -2   M      A18X+100355Y+134158X0120Y0150     S2      
327m0427            R799  -1          A18X+100645Y+134158X0120Y0150R180 S2      
327m0427            U22   -14         A18X+098451Y+133768X0120Y0630R270 S2      
327m0427            VIA   -    M      A18X+099600Y+134379X0260Y    R180 S2      
327SMB_MUX_RT_SDA   VIA   -    M      A18X+089840Y+130692X0260Y         S2      
327SMB_MUX_RT_SDA   U6020 -23         A18X+089414Y+131465X0120Y0630R270 S2      
327SMB_MUX_RT_SDA   R6779 -1          A18X+090795Y+130200X0120Y0150R180 S2      
327SMB_MUX_RT_SCL   VIA   -    M      A18X+090088Y+131136X0260Y         S2      
327SMB_MUX_RT_SCL   R6780 -1          A18X+090795Y+130600X0120Y0150R180 S2      
327SMB_MUX_RT_SCL   U6020 -22         A18X+089414Y+131721X0120Y0630R270 S2      
327m0428            R850  -1          A18X+100145Y+130300X0120Y0150R180 S2      
327m0428            VIA   -    M      A18X+099685Y+130460X0260Y         S2      
327m0428            U22   -23         A18X+098451Y+131465X0120Y0630R270 S2      
327m0429            R851  -1          A18X+100145Y+130700X0120Y0150R180 S2      
327m0429            VIA   -    M      A18X+099182Y+131200X0260Y         S2      
327m0429            U22   -22         A18X+098451Y+131721X0120Y0630R270 S2      
317m0430            VIA   -    MD0100PA00X+100990Y+130150X0200Y         S0      
317m0430            VIA   -    M      A01X+110096Y+162254X0200Y         S2      
017m0430            VIA   -    M      A18X+110096Y+162254X0260Y         S2      
017m0430                  -    MD0100PA00X+110096Y+162254                       
327m0430            R850  -2          A18X+100355Y+130300X0120Y0150     S2      
327m0430            R6783 -1          A01X+109126Y+163373X0198Y0197     S1      
317m0431            VIA   -    MD0100PA00X+109855Y+162575X0200Y         S0      
327m0431            R851  -2          A18X+100355Y+130700X0120Y0150     S2      
317m0431            VIA   -    M      A01X+100990Y+130550X0200Y         S2      
017m0431            VIA   -    M      A18X+100990Y+130550X0260Y         S2      
017m0431                  -    MD0100PA00X+100990Y+130550                       
327m0431            R6782 -1          A01X+109131Y+162994X0198Y0197     S1      
327m0432            R1515 -1          A18X+096655Y+130420X0120Y0150R180 S2      
327m0432            VIA   -    M      A18X+092872Y+130010X0260Y         S2      
327m0432            R6785 -1   M      A18X+091842Y+130200X0198Y0197R180 S2      
327m0432            R6779 -2          A18X+091005Y+130200X0120Y0150     S2      
327m0433            R1514 -1          A18X+096655Y+130740X0120Y0150R180 S2      
327m0433            VIA   -    M      A18X+092822Y+130808X0260Y         S2      
327m0433            R6784 -1   M      A18X+091842Y+130600X0198Y0197R180 S2      
327m0433            R6780 -2          A18X+091005Y+130600X0120Y0150     S2      
327m0434            VIA   -    M      A18X+091642Y+131000X0260Y         S2      
327m0434            U6020 -21         A18X+089414Y+131977X0120Y0630R270 S2      
327m0434            R6770 -2   M      A18X+090795Y+131000X0120Y0150R180 S2      
327m0434            R6773 -1          A18X+091945Y+131000X0120Y0150R180 S2      
327m0435            VIA   -    M      A18X+085898Y+130600X0260Y         S2      
327m0435            R6774 -1          A18X+084705Y+130600X0120Y0150     S2      
327m0435            R6771 -2   M      A18X+085605Y+130600X0120Y0150     S2      
327m0435            U6020 -2          A18X+087209Y+131465X0120Y0630R270 S2      
327m0436            VIA   -    M      A18X+086383Y+130421X0260Y         S2      
327m0436            R6775 -1          A18X+084705Y+130200X0120Y0150     S2      
327m0436            R6772 -2   M      A18X+085605Y+130200X0120Y0150     S2      
327m0436            U6020 -1          A18X+087209Y+131209X0120Y0630R270 S2      
327m0437            R845  -1          A18X+100645Y+131050X0120Y0150R180 S2      
327m0437            R842  -2   M      A18X+100355Y+131050X0120Y0150     S2      
327m0437            VIA   -    M      A18X+099699Y+131246X0260Y         S2      
327m0437            U22   -21         A18X+098451Y+131977X0120Y0630R270 S2      
327m0438            VIA   -    M      A18X+095352Y+130550X0260Y         S2      
327m0438            R846  -1          A18X+094255Y+130500X0120Y0150     S2      
327m0438            R843  -2   M      A18X+095042Y+130550X0120Y0150     S2      
327m0438            U22   -2          A18X+096246Y+131465X0120Y0630R270 S2      
327m0439            VIA   -    M      A18X+095850Y+130650X0260Y         S2      
327m0439            R847  -1          A18X+094255Y+130150X0120Y0150     S2      
327m0439            R844  -2   M      A18X+095042Y+130150X0120Y0150     S2      
327m0439            U22   -1          A18X+096246Y+131209X0120Y0630R270 S2      
327m0440            VIA   -           A01X+052293Y+155655X0300Y         S1      
327m0440            R6900 -2   M      A01X+052619Y+155655X0120Y0150R090 S1      
327m0440            U6017 -G1         A01X+052527Y+154048X0100Y0130     S1      
327m0440            R6901 -1   M      A01X+052847Y+155360X0120Y0150R270 S1      
317m0441            VIA   -    MD0080PA00X+044292Y+151322X0160Y         S0      
327m0441            U6017 -FF33       A01X+044568Y+151390X0120Y         S1      
327m0441            VIA   -    M      A18X+044003Y+150807X0260Y         S2      
327m0441            R909  -2          A18X+043056Y+151080X0120Y0150     S2      
327m0441            R910  -1   M      A18X+043346Y+151080X0120Y0150R180 S2      
327m0442            R902  -2          A01X+054717Y+151885X0120Y0150R270 S1      
327m0442            R903  -1   M      A01X+054717Y+152175X0120Y0150R090 S1      
327m0442            U6017 -B25        A01X+052935Y+151981X0100Y0130R090 S1      
327m0442            VIA   -    M      A01X+054088Y+152695X0300Y         S1      
327m0443            R904  -2          A01X+055037Y+151885X0120Y0150R270 S1      
327m0443            R906  -1   M      A01X+055037Y+152175X0120Y0150R090 S1      
327m0443            U6017 -B23        A01X+052935Y+152217X0100Y0130R090 S1      
327m0443            VIA   -    M      A01X+054588Y+152695X0300Y         S1      
327m0444            VIA   -           A01X+054764Y+150908X0300Y         S1      
327m0444            R949  -1   M      A01X+054834Y+150396X0120Y0150     S1      
327m0444            U6017 -F34        A01X+052645Y+151150X0120Y         S1      
327m0444            R927  -2   M      A01X+054252Y+150660X0120Y0150     S1      
327m0445            VIA   -           A01X+065100Y+155655X0300Y         S1      
327m0445            R6794 -2   M      A01X+065426Y+155655X0120Y0150R090 S1      
327m0445            U6016 -G1         A01X+065333Y+154048X0100Y0130     S1      
327m0445            R6795 -1   M      A01X+065426Y+155365X0120Y0150R270 S1      
317m0446            VIA   -    MD0080PA00X+057098Y+151322X0160Y         S0      
327m0446            U6016 -FF33       A01X+057374Y+151390X0120Y         S1      
327m0446            VIA   -    M      A18X+056860Y+150932X0260Y         S2      
327m0446            R868  -2          A18X+055862Y+151080X0120Y0150     S2      
327m0446            R869  -1   M      A18X+056152Y+151080X0120Y0150R180 S2      
327m0447            R861  -2          A01X+068911Y+153752X0120Y0150     S1      
327m0447            R863  -1   M      A01X+068621Y+153752X0120Y0150R180 S1      
327m0447            VIA   -    M      A01X+068621Y+153416X0300Y         S1      
327m0447            U6016 -B25        A01X+065741Y+151981X0100Y0130R090 S1      
327m0448            VIA   -    M      A01X+067979Y+153662X0300Y         S1      
327m0448            R864  -2          A01X+068911Y+154072X0120Y0150     S1      
327m0448            U6016 -B23        A01X+065741Y+152217X0100Y0130R090 S1      
327m0448            R865  -1   M      A01X+068621Y+154072X0120Y0150R180 S1      
327m0449            R892  -1          A01X+067210Y+150514X0120Y0150     S1      
327m0449            R887  -2   M      A01X+067210Y+150834X0120Y0150     S1      
327m0449            VIA   -    M      A01X+066895Y+150898X0300Y         S1      
327m0449            U6016 -F34        A01X+065451Y+151150X0120Y         S1      
327m0450            R6744 -1          A01X+069952Y+036648X0198Y0197R270 S1      
327m0450            R6742 -2   M      A01X+070352Y+036648X0198Y0197R090 S1      
327m0450            U18   -H1         A01X+071938Y+041989X0160Y    R090 S1      
327m0450            VIA   -           A18X+071928Y+041380X0260Y         S2      
317m0450            VIA   -    MD0100PA00X+071784Y+041836X0180Y    R090 S0      
317m0450            VIA   -    MD0100PA00X+071136Y+036927X0200Y         S0      
327m0451            R6745 -1   M      A01X+069337Y+036648X0198Y0197R270 S1      
327m0451            R6743 -2          A01X+068944Y+036648X0198Y0197R090 S1      
327m0451            U18   -J4         A01X+072253Y+042934X0160Y    R090 S1      
317m0451            VIA   -    MD0100PA00X+072099Y+042781X0180Y    R090 S2      
317m0451            VIA   -    MD0100PA00X+069639Y+036862X0200Y         S0      
317m0452            VIA   -    M      A01X+084935Y+049907X0300Y         S1      
017m0452            VIA   -    M      A18X+084935Y+049907X0200Y         S1      
017m0452                  -    MD0100PA00X+084935Y+049907                       
327m0452            U18   -V18        A01X+075087Y+047344X0160Y    R090 S1      
317m0452            VIA   -    MD0100PA00X+075241Y+047497X0180Y    R090 S0      
327m0452            R6781 -1          A01X+085302Y+049886X0198Y0197     S1      
327m0453            R6781 -2          A01X+085617Y+049886X0198Y0197     S1      
317m0453            VIA   -    MD0100PA00X+087794Y+131234X0200Y         S0      
317m0453            VIA   -    M      A01X+148600Y+168600X0200Y         S2      
017m0453            VIA   -    M      A18X+148600Y+168600X0260Y         S2      
017m0453                  -    MD0100PA00X+148600Y+168600                       
327m0453            R1211 -1          A18X+116195Y+168200X0120Y0150R180 S2      
327m0453            R1209 -1          A18X+164855Y+168773X0120Y0150R180 S2      
327m0453            R1206 -1          A01X+148455Y+167850X0120Y0150R180 S1      
317m0453            VIA   -    MD0100PA00X+115950Y+168250X0200Y         S0      
327m0453            R1210 -1          A01X+113833Y+156740X0120Y0150R270 S1      
317m0453            VIA   -    MD0100PA00X+113776Y+156954X0200Y         S0      
317m0453            VIA   -    MD0100PA00X+099550Y+136800X0200Y         S0      
317m0453            VIA   -    MD0100PA00X+094562Y+130950X0200Y         S0      
327m0453            R848  -1          A18X+094832Y+130950X0120Y0150R180 S2      
327m0453            R849  -1   M      A18X+094255Y+130950X0120Y0150     S2      
317m0453            VIA   -    MD0100PA00X+088712Y+143674X0200Y         S0      
317m0453            VIA   -    MD0100PA00X+064313Y+163980X0200Y         S0      
327m0453            R1200 -1          A18X+064445Y+164290X0120Y0150     S2      
317m0453            VIA   -    MD0100PA00X+067336Y+167441X0200Y         S0      
327m0453            R1198 -1          A18X+067083Y+167239X0120Y0150R270 S2      
317m0453            VIA   -    MD0100PA00X+067084Y+162086X0200Y         S0      
327m0453            R1199 -1          A01X+044557Y+157984X0120Y0150     S1      
327m0453            R1201 -1          A01X+039501Y+158734X0120Y0150R270 S1      
317m0453            VIA   -    MD0100PA00X+044193Y+158166X0200Y         S0      
327m0454            R848  -2          A18X+095042Y+130950X0120Y0150     S2      
327m0454            U22   -3          A18X+096246Y+131721X0120Y0630R270 S2      
327m0454            VIA   -    M      A18X+095537Y+131150X0260Y         S2      
317m0455            VIA   -    M      A01X+078644Y+048077X0200Y         S2      
017m0455            VIA   -    M      A18X+078644Y+048077X0260Y         S2      
017m0455                  -    MD0100PA00X+078644Y+048077                       
327m0455            R6777 -1          A01X+079030Y+047951X0198Y0197     S1      
327m0455            U18   -Y20        A01X+075717Y+047974X0160Y    R090 S1      
317m0455            VIA   -    MD0100PA00X+075871Y+048127X0180Y    R090 S0      
317m0456            VIA   -    MD0100PA00X+097241Y+131256X0200Y         S0      
317m0456            VIA   -    M      A01X+085068Y+131000X0200Y         S2      
017m0456            VIA   -    M      A18X+085068Y+131000X0260Y         S2      
017m0456                  -    MD0100PA00X+085068Y+131000                       
327m0456            R6778 -1          A18X+084705Y+131000X0120Y0150     S2      
327m0456            R6776 -1          A18X+085395Y+131000X0120Y0150R180 S2      
317m0456            VIA   -    MD0100PA00X+095830Y+065989X0200Y         S0      
317m0456            VIA   -    MD0100PA00X+092259Y+049667X0200Y         S0      
327m0456            R6777 -2          A01X+079345Y+047951X0198Y0197     S1      
317m0456            VIA   -    MD0100PA00X+082647Y+048390X0200Y         S0      
317m0456            VIA   -    MD0100PA00X+101600Y+130300X0200Y         S0      
327RST_SMB_RT_N     R6776 -2          A18X+085605Y+131000X0120Y0150     S2      
327RST_SMB_RT_N     U6020 -3          A18X+087209Y+131721X0120Y0630R270 S2      
327RST_SMB_RT_N     VIA   -    M      A18X+086534Y+131185X0260Y         S2      
327m0457            R911  -2          A01X+044304Y+155581X0120Y0150R090 S1      
327m0457            R6799 -1          A18X+073316Y+052602X0198Y0197R090 S2      
317m0457            VIA   -    MD0100PA00X+073258Y+053719X0200Y         S0      
317m0457            VIA   -    MD0100PA00X+072061Y+067704X0200Y         S0      
317m0457            VIA   -    MD0100PA00X+078454Y+073451X0200Y         S0      
317m0457            VIA   -    MD0100PA00X+043774Y+154439X0200Y         S0      
327m0457            R908  -1   M      A01X+044061Y+155289X0120Y0150R270 S1      
327m0457            R901  -2          A01X+043551Y+153379X0120Y0150R270 S1      
317m0457            VIA   -    M      A01X+086400Y+086661X0200Y         S2      
017m0457            VIA   -    M      A18X+086400Y+086661X0260Y         S2      
017m0457                  -    MD0100PA00X+086400Y+086661                       
327m0458            R6799 -2          A18X+073316Y+052287X0198Y0197R090 S2      
327m0458            U18   -L20        A01X+072883Y+047974X0160Y    R090 S1      
327m0458            VIA   -    M      A18X+072861Y+051048X0260Y         S2      
317m0458            VIA   -    MD0100PA00X+072729Y+048127X0180Y    R090 S0      
327m0459            U6017 -FF11       A01X+044568Y+153044X0120Y         S1      
327m0459            VIA   -           A01X+042244Y+152698X0300Y         S1      
327m0459            R901  -1   M      A01X+043551Y+153169X0120Y0150R090 S1      
327m0460            R6798 -1          A18X+073319Y+051951X0198Y0197R090 S2      
317m0460            VIA   -    M      A01X+073252Y+054599X0200Y    R180 S2      
017m0460            VIA   -    M      A18X+073252Y+054599X0260Y    R180 S2      
017m0460                  -    MD0100PA00X+073252Y+054599                       
317m0460            VIA   -    MD0100PA00X+072056Y+067989X0200Y         S0      
317m0460            VIA   -    MD0100PA00X+076457Y+073618X0200Y         S0      
317m0460            VIA   -    MD0100PA00X+053134Y+154648X0200Y         S0      
327m0460            R895  -2          A01X+053255Y+155655X0120Y0150R090 S1      
327m0460            R907  -1   M      A01X+053158Y+155362X0120Y0150R270 S1      
317m0460            VIA   -    MD0100PA00X+086411Y+086353X0200Y         S0      
327m0461            R6798 -2          A18X+073319Y+051636X0198Y0197R090 S2      
327m0461            U18   -L19        A01X+072883Y+047659X0160Y    R090 S1      
327m0461            VIA   -    M      A18X+073261Y+050748X0260Y         S2      
317m0461            VIA   -    MD0100PA00X+072729Y+047812X0180Y    R090 S0      
327m0462            VIA   -           A01X+052325Y+156454X0300Y         S1      
327m0462            R895  -1   M      A01X+053255Y+155865X0120Y0150R270 S1      
327m0462            U6017 -F2         A01X+052645Y+153843X0120Y         S1      
317m0463            VIA   -    MD0100PA00X+071752Y+067983X0200Y         S0      
317m0463            VIA   -    M      A01X+071971Y+061283X0200Y         S2      
017m0463            VIA   -    M      A18X+071971Y+061283X0260Y         S2      
017m0463                  -    MD0100PA00X+071971Y+061283                       
327m0463            R6793 -1          A18X+071838Y+052852X0198Y0197R090 S2      
317m0463            VIA   -    MD0100PA00X+076240Y+073292X0200Y         S0      
317m0463            VIA   -    MD0100PA00X+056721Y+154430X0200Y         S0      
327m0463            R867  -1   M      A01X+056817Y+155289X0120Y0150R270 S1      
327m0463            R860  -2          A01X+056437Y+155579X0120Y0150R270 S1      
327m0463            R870  -2   M      A01X+056817Y+155579X0120Y0150R090 S1      
317m0463            VIA   -    MD0100PA00X+086402Y+085997X0200Y         S0      
327m0464            R6793 -2          A18X+071838Y+052537X0198Y0197R090 S2      
327m0464            U18   -K19        A01X+072568Y+047659X0160Y    R090 S1      
327m0464            VIA   -    M      A18X+071972Y+050644X0260Y         S2      
317m0464            VIA   -    MD0100PA00X+072414Y+047812X0180Y    R090 S0      
327m0465            VIA   -           A01X+057224Y+156933X0300Y         S1      
327m0465            R860  -1   M      A01X+056437Y+155369X0120Y0150R090 S1      
327m0465            U6016 -FF11       A01X+057374Y+153044X0120Y         S1      
317m0466            VIA   -    MD0100PA00X+072493Y+067836X0200Y         S0      
327m0466            R6792 -1          A01X+073732Y+052708X0198Y0197R270 S1      
317m0466            VIA   -    MD0100PA00X+076253Y+056534X0200Y         S0      
317m0466            VIA   -    MD0100PA00X+076042Y+073623X0200Y         S0      
317m0466            VIA   -    MD0100PA00X+065953Y+154652X0200Y         S0      
327m0466            R854  -2          A01X+066062Y+155655X0120Y0150R090 S1      
327m0466            R866  -1   M      A01X+066062Y+155365X0120Y0150R270 S1      
317m0466            VIA   -    M      A01X+086414Y+085605X0200Y         S2      
017m0466            VIA   -    M      A18X+086414Y+085605X0260Y         S2      
017m0466                  -    MD0100PA00X+086414Y+085605                       
327m0467            R6792 -2          A01X+073732Y+052393X0198Y0197R270 S1      
317m0467            VIA   -    MD0100PA00X+073661Y+051843X0200Y         S0      
327m0467            U18   -K20        A01X+072568Y+047974X0160Y    R090 S1      
317m0467            VIA   -    MD0100PA00X+072414Y+048127X0180Y    R090 S2      
317m0468            VIA   -    M      A01X+065743Y+155523X0200Y         S2      
017m0468            VIA   -    M      A18X+065743Y+155523X0260Y         S2      
017m0468                  -    MD0100PA00X+065743Y+155523                       
327m0468            R854  -1          A01X+066062Y+155865X0120Y0150R270 S1      
327m0468            U6016 -F2         A01X+065451Y+153843X0120Y         S1      
317m0469            VIA   -    MD0100PA00X+068307Y+164176X0200Y         S0      
327m0469            R9007 -1          A01X+068088Y+164784X0198Y0197R180 S1      
327m0469            Q9001 -2          A01X+068978Y+164333X0170Y0200R090 S1      
327m0469            R9006 -2   M      A01X+068087Y+164390X0198Y0197     S1      
327m0469            VIA   -    M      A18X+131201Y+166116X0260Y         S2      
317m0469            J107  -N2   D0142PA00X+131358Y+167201X0302Y    R180 S3      
317m0469            VIA   -    MD0100PA00X+068428Y+145226X0200Y         S0      
317m0469            VIA   -    MD0100PA00X+066698Y+156094X0200Y         S0      
327m0470            VIA   -    M      A01X+074072Y+163362X0300Y         S1      
327m0470            R9012 -2          A01X+074072Y+163010X0198Y0197R090 S1      
327m0470            U181  -11         A01X+073725Y+164333X0160Y0540     S1      
317m0471            VIA   -    M      A01X+068558Y+163748X0200Y         S2      
017m0471            VIA   -    M      A18X+068558Y+163748X0260Y         S2      
017m0471                  -    MD0100PA00X+068558Y+163748                       
327m0471            Q9001 -3          A01X+068978Y+164077X0170Y0200R090 S1      
327m0471            C9001 -1   M      A01X+068088Y+163584X0198Y0197R180 S1      
327m0471            R9009 -2          A01X+068087Y+163970X0198Y0197     S1      
327m0471            R9012 -1          A01X+074072Y+162694X0198Y0197R090 S1      
317m0471            VIA   -    MD0100PA00X+074366Y+162694X0200Y         S0      
327m0472            VIA   -    M      A01X+070216Y+164737X0300Y         S1      
327m0472            Q9001 -5          A01X+069726Y+164333X0170Y0200R090 S1      
327m0472            R9008 -2          A01X+070569Y+164737X0198Y0197R270 S1      
327m0472            Q9001 -6   M      A01X+069726Y+164589X0170Y0200R090 S1      
327m0473            R9003 -1   M      A01X+142687Y+162337X0198Y0197R180 S1      
327m0473            R9002 -2   M      A01X+142687Y+161950X0198Y0197     S1      
327m0473            Q9000 -2          A01X+142907Y+163299X0170Y0200R180 S1      
317m0473            VIA   -    MD0100PA00X+142690Y+161699X0200Y         S0      
317m0473            J106  -A1   D0142PA00X+150295Y+173421X0302Y0302R180 S3      
327m0473            VIA   -    M      A18X+149130Y+173021X0260Y         S2      
327m0474            R9010 -2          A01X+074538Y+168720X0198Y0197R270 S1      
327m0474            VIA   -    M      A01X+074538Y+168366X0300Y         S1      
327m0474            U181  -14         A01X+073725Y+166636X0160Y0540     S1      
327m0475            R9010 -1          A01X+074538Y+169034X0198Y0197R270 S1      
317m0475            VIA   -    MD0100PA00X+074729Y+169306X0200Y         S0      
327m0475            VIA   -    M      A01X+143318Y+162813X0300Y         S1      
317m0475            VIA   -    MD0100PA00X+143759Y+161684X0200Y         S0      
327m0475            C9000 -1   M      A01X+143607Y+162350X0198Y0197R180 S1      
327m0475            R9005 -2   M      A01X+143607Y+161957X0198Y0197     S1      
327m0475            Q9000 -3          A01X+143163Y+163299X0170Y0200R180 S1      
317m0475            VIA   -    MD0100PA00X+113919Y+162160X0200Y         S0      
317m0475            VIA   -    MD0100PA00X+073990Y+152315X0200Y         S0      
327m0476            R9004 -2          A01X+142881Y+164709X0198Y0197R180 S1      
317m0476            VIA   -    M      A01X+142907Y+164366X0200Y         S2      
017m0476            VIA   -    M      A18X+142907Y+164366X0260Y         S2      
017m0476                  -    MD0100PA00X+142907Y+164366                       
327m0476            Q9000 -6          A01X+142651Y+164047X0170Y0200R180 S1      
327m0476            Q9000 -5   M      A01X+142907Y+164047X0170Y0200R180 S1      
327m0477            VIA   -    M      A01X+073648Y+163676X0300Y         S1      
327m0477            R9011 -2          A01X+073672Y+163010X0198Y0197R090 S1      
327m0477            U181  -10         A01X+073469Y+164333X0160Y0540     S1      
317m0478            VIA   -    MD0100PA00X+073672Y+162394X0200Y         S0      
327m0478            R9011 -1          A01X+073672Y+162694X0198Y0197R090 S1      
317m0478            VIA   -    MD0100PA00X+082279Y+077501X0200Y         S0      
317m0478            VIA   -    MD0100PA00X+076440Y+067697X0200Y         S0      
317m0478            VIA   -    M      A01X+068731Y+052214X0200Y         S2      
017m0478            VIA   -    M      A18X+068731Y+052214X0260Y         S2      
017m0478                  -    MD0100PA00X+068731Y+052214                       
327m0478            R4145 -2          A01X+068731Y+051094X0198Y0197R090 S1      
317m0478            VIA   -    MD0100PA00X+065903Y+171005X0200Y         S0      
327m0478            Q132  -3   M      A18X+065572Y+171470X0170Y0200R090 S2      
327m0478            R4573 -2   M      A18X+065126Y+171470X0198Y0197R270 S2      
327m0478            R4129 -2          A18X+064326Y+171470X0198Y0197R090 S2      
327m0478            C13   -1   M      A18X+064726Y+171470X0198Y0197R270 S2      
317m0479            J108  -N8   D0142PA00X+129390Y+167201X0302Y    R180 S3      
317m0479            VIA   -    MD0100PA00X+139888Y+168034X0200Y         S0      
317m0479            VIA   -    M      A01X+143024Y+161714X0200Y         S2      
017m0479            VIA   -    M      A18X+143024Y+161714X0260Y         S2      
017m0479                  -    MD0100PA00X+143024Y+161714                       
317m0479            VIA   -    MD0100PA00X+139678Y+161717X0200Y         S0      
327m0479            R9015 -1   M      A01X+142687Y+160990X0198Y0197R180 S1      
327m0479            R9014 -2   M      A01X+142687Y+161397X0198Y0197     S1      
327m0479            Q9002 -2          A01X+143305Y+159910X0170Y0200R270 S1      
327m0480            R9018 -2          A01X+071531Y+167697X0198Y0197R270 S1      
327m0480            VIA   -    M      A01X+071889Y+167294X0300Y         S1      
327m0480            U181  -20         A01X+072190Y+166636X0160Y0540     S1      
317m0481            VIA   -    MD0100PA00X+071912Y+168272X0200Y         S0      
327m0481            R9018 -1          A01X+071531Y+168012X0198Y0197R270 S1      
317m0481            VIA   -    M      A01X+143856Y+161258X0200Y         S2      
017m0481            VIA   -    M      A18X+143856Y+161258X0260Y         S2      
017m0481                  -    MD0100PA00X+143856Y+161258                       
327m0481            C9002 -1   M      A01X+143588Y+161390X0198Y0197R180 S1      
327m0481            R9017 -2   M      A01X+143588Y+160997X0198Y0197     S1      
327m0481            Q9002 -3          A01X+143305Y+160166X0170Y0200R270 S1      
317m0481            VIA   -    MD0100PA00X+113914Y+161886X0200Y         S0      
317m0481            VIA   -    MD0100PA00X+073755Y+152401X0200Y         S0      
317m0482            VIA   -    M      A01X+141981Y+159908X0200Y         S2      
017m0482            VIA   -    M      A18X+141981Y+159908X0260Y         S2      
017m0482                  -    MD0100PA00X+141981Y+159908                       
327m0482            R9016 -2          A01X+141562Y+159908X0198Y0197R270 S1      
327m0482            Q9002 -6          A01X+142557Y+159654X0170Y0200R270 S1      
327m0482            Q9002 -5   M      A01X+142557Y+159910X0170Y0200R270 S1      
327m0483            VIA   -    M      A01X+074432Y+167313X0300Y         S1      
327m0483            R9013 -2          A01X+074554Y+167707X0198Y0197R270 S1      
327m0483            U181  -13         A01X+074020Y+166636X0240Y0540     S1      
327m0484            R4147 -2          A01X+077823Y+047634X0198Y0197     S1      
327m0484            R9013 -1          A01X+074554Y+168022X0198Y0197R270 S1      
317m0484            VIA   -    MD0100PA00X+074841Y+167937X0200Y         S0      
317m0484            VIA   -    MD0100PA00X+073961Y+145821X0200Y         S0      
327m0484            Q133  -3          A01X+120795Y+168540X0170Y0200     S1      
327m0484            R4578 -2   M      A01X+120795Y+168986X0198Y0197R180 S1      
327m0484            R4142 -2   M      A01X+120795Y+169786X0198Y0197     S1      
327m0484            C19   -1   M      A01X+120795Y+169386X0198Y0197R180 S1      
317m0484            VIA   -    MD0100PA00X+160044Y+143454X0200Y         S0      
317m0484            VIA   -    MD0100PA00X+078688Y+047534X0200Y    R180 S0      
317m0484            VIA   -    M      A01X+120795Y+170334X0200Y    R090 S2      
017m0484            VIA   -    M      A18X+120795Y+170334X0260Y    R090 S2      
017m0484                  -    MD0100PA00X+120795Y+170334                       
317m0484            VIA   -    MD0100PA00X+115482Y+147113X0200Y         S0      
327m0485            R9019 -2          A01X+072191Y+168130X0198Y0197R270 S1      
327m0485            VIA   -    M      A01X+072141Y+167786X0300Y         S1      
327m0485            U181  -19         A01X+072446Y+166636X0160Y0540     S1      
327m0486            Q134  -3          A01X+140506Y+163463X0170Y0200R180 S1      
327m0486            R4574 -2   M      A01X+140506Y+163017X0198Y0197     S1      
327m0486            C15   -1   M      A01X+140506Y+162217X0198Y0197     S1      
327m0486            R4156 -2   M      A01X+140506Y+162617X0198Y0197R180 S1      
327m0486            R4157 -2          A01X+079290Y+046765X0198Y0197     S1      
317m0486            VIA   -    MD0100PA00X+083005Y+047603X0200Y         S0      
317m0486            VIA   -    MD0100PA00X+079395Y+034222X0200Y         S0      
317m0486            VIA   -    M      A01X+140645Y+161957X0200Y         S2      
017m0486            VIA   -    M      A18X+140645Y+161957X0260Y         S2      
017m0486                  -    MD0100PA00X+140645Y+161957                       
317m0486            VIA   -    MD0100PA00X+113904Y+161415X0200Y         S0      
317m0486            VIA   -    MD0100PA00X+073545Y+152537X0200Y         S0      
317m0486            VIA   -    MD0100PA00X+072318Y+168882X0200Y         S0      
327m0486            R9019 -1          A01X+072191Y+168445X0198Y0197R270 S1      
327m0487            R894  -1   M      A01X+054080Y+151612X0180Y0200     S1      
327m0487            R897  -2   M      A01X+054080Y+151222X0180Y0200     S1      
327m0487            R893  -1   M      A01X+054080Y+151222X0180Y0200     S1      
327m0487            L33   -2   M      A01X+054080Y+151612X0180Y0200     S1      
327m0487            U6017 -BV17       A01X+049122Y+152614X0120Y         S1      
317m0487            VIA   -    MD0100PA00X+054080Y+151222X0200Y         S0      
327m0487            C444  -1          A18X+049377Y+152655X0120Y0150R270 S2      
317m0487            VIA   -    MD0080PA00X+049377Y+152635X0160Y    R180 S0      
327m0487            C441  -1          A18X+049322Y+152375X0120Y0150R090 S2      
317m0487            VIA   -    MD0080PA00X+049322Y+152395X0160Y         S0      
317m0487            VIA   -    MD0100PA00X+054080Y+151612X0200Y         S0      
327m0488            R894  -2          A01X+053765Y+151612X0180Y0200     S1      
327m0488            R893  -2          A01X+053765Y+151222X0180Y0200     S1      
327m0488            C435  -1          A01X+053777Y+151984X0198Y0197R090 S1      
327m0488            C437  -1          A18X+048855Y+153921X0198Y0197R090 S2      
327m0488            C438  -1          A18X+048382Y+153921X0198Y0197R090 S2      
327m0488            U6017 -BV20       A01X+049122Y+152417X0120Y         S1      
327m0488            U6017 -CE17       A01X+048650Y+152614X0120Y         S1      
327m0488            U6017 -CE20       A01X+048650Y+152417X0120Y         S1      
327m0488            U6017 -CM17       A01X+048177Y+152614X0120Y         S1      
327m0488            U6017 -CM20       A01X+048177Y+152417X0120Y         S1      
327m0488            VIA   -           A18X+052902Y+151231X0260Y         S2      
327m0488            VIA   -           A18X+052889Y+151796X0260Y         S2      
327m0488            L9    -2   M      A18X+053702Y+151408X0440Y0540R180 S2      
327m0488            C433  -1   M      A18X+053550Y+152045X0400Y0500R090 S2      
317m0488            VIA   -    MD0100PA00X+053400Y+152144X0200Y    R180 S0      
317m0488            VIA   -    MD0100PA00X+053765Y+151222X0200Y    R180 S0      
317m0488            VIA   -    MD0100PA00X+053765Y+151612X0200Y    R180 S0      
317m0488            VIA   -    MD0100PA00X+053777Y+151984X0200Y    R180 S0      
317m0488            VIA   -    MD0100PA00X+053150Y+151925X0200Y    R270 S0      
317m0488            VIA   -    MD0100PA00X+053332Y+151695X0200Y    R270 S0      
317m0488            VIA   -    MD0100PA00X+053332Y+151445X0200Y    R270 S0      
317m0488            VIA   -    MD0100PA00X+053332Y+151195X0200Y    R270 S0      
317m0488            VIA   -    MD0080PA00X+047960Y+152635X0160Y         S0      
317m0488            VIA   -    MD0080PA00X+047905Y+152395X0160Y         S0      
317m0488            VIA   -    MD0080PA00X+048432Y+152635X0160Y         S0      
317m0488            VIA   -    MD0080PA00X+048905Y+152635X0160Y         S0      
317m0488            VIA   -    MD0080PA00X+048377Y+152395X0160Y         S0      
327m0488            C447  -1   M      A18X+048905Y+152655X0120Y0150R270 S2      
327m0488            C446  -1   M      A18X+047905Y+152375X0120Y0150R090 S2      
327m0488            C440  -1   M      A18X+047960Y+152655X0120Y0150R270 S2      
327m0488            C443  -1   M      A18X+048377Y+152375X0120Y0150R090 S2      
327m0488            C442  -1   M      A18X+048432Y+152655X0120Y0150R270 S2      
327m0488            C445  -1   M      A18X+048850Y+152375X0120Y0150R090 S2      
317m0488            VIA   -    MD0080PA00X+048850Y+152395X0160Y         S0      
327m0489            R852  -1   M      A01X+067272Y+152663X0180Y0200     S1      
327m0489            R853  -1   M      A01X+067272Y+153053X0180Y0200     S1      
327m0489            R857  -2   M      A01X+067272Y+152663X0180Y0200     S1      
327m0489            L32   -2   M      A01X+067272Y+153053X0180Y0200     S1      
327m0489            U6016 -BV17       A01X+061928Y+152614X0120Y         S1      
327m0489            VIA   -           A18X+066986Y+152850X0260Y         S2      
317m0489            VIA   -    MD0100PA00X+067272Y+153053X0200Y         S0      
317m0489            VIA   -    MD0100PA00X+067272Y+152663X0200Y         S0      
327m0489            C375  -1          A18X+062128Y+152375X0120Y0150R090 S2      
317m0489            VIA   -    MD0080PA00X+062128Y+152395X0160Y         S0      
327m0489            C378  -1          A18X+062184Y+152655X0120Y0150R270 S2      
317m0489            VIA   -    MD0080PA00X+062184Y+152635X0160Y         S0      
327m0490            R852  -2          A01X+066956Y+152663X0180Y0200     S1      
327m0490            R853  -2          A01X+066956Y+153053X0180Y0200     S1      
327m0490            C369  -1   M      A01X+066583Y+152742X0198Y0197R090 S1      
327m0490            C371  -1          A18X+061189Y+153921X0198Y0197R090 S2      
327m0490            C372  -1          A18X+061661Y+153921X0198Y0197R090 S2      
327m0490            U6016 -BV20       A01X+061928Y+152417X0120Y         S1      
327m0490            U6016 -CE17       A01X+061456Y+152614X0120Y         S1      
327m0490            U6016 -CE20       A01X+061456Y+152417X0120Y         S1      
327m0490            U6016 -CM17       A01X+060984Y+152614X0120Y         S1      
327m0490            U6016 -CM20       A01X+060984Y+152417X0120Y         S1      
317m0490            VIA   -    M      A01X+066171Y+151415X0200Y         S2      
017m0490            VIA   -    M      A18X+066171Y+151415X0260Y         S2      
017m0490                  -    MD0100PA00X+066171Y+151415                       
327m0490            L7    -2          A01X+066686Y+151420X0440Y0540     S1      
327m0490            C367  -1          A01X+066670Y+152120X0400Y0500R180 S1      
317m0490            VIA   -    MD0100PA00X+066066Y+151923X0200Y    R090 S0      
317m0490            VIA   -    MD0100PA00X+066583Y+152742X0200Y         S0      
317m0490            VIA   -    MD0100PA00X+066316Y+152173X0200Y         S0      
317m0490            VIA   -    MD0100PA00X+066316Y+152423X0200Y         S0      
317m0490            VIA   -    MD0100PA00X+066316Y+151923X0200Y         S0      
317m0490            VIA   -    MD0100PA00X+066316Y+151673X0200Y         S0      
317m0490            VIA   -    MD0100PA00X+066316Y+151173X0200Y         S0      
317m0490            VIA   -    MD0080PA00X+061184Y+152395X0160Y         S0      
317m0490            VIA   -    MD0080PA00X+061239Y+152635X0160Y         S0      
317m0490            VIA   -    MD0080PA00X+060766Y+152635X0160Y         S0      
317m0490            VIA   -    MD0080PA00X+060711Y+152395X0160Y         S0      
317m0490            VIA   -    MD0080PA00X+061711Y+152635X0160Y         S0      
327m0490            C381  -1   M      A18X+060711Y+152375X0120Y0150R090 S2      
327m0490            C377  -1   M      A18X+061184Y+152375X0120Y0150R090 S2      
327m0490            C376  -1   M      A18X+061239Y+152655X0120Y0150R270 S2      
327m0490            C374  -1   M      A18X+060766Y+152655X0120Y0150R270 S2      
327m0490            C379  -1   M      A18X+061711Y+152655X0120Y0150R270 S2      
327m0490            C380  -1   M      A18X+061656Y+152375X0120Y0150R090 S2      
317m0490            VIA   -    MD0080PA00X+061656Y+152395X0160Y         S0      
327m0491            U6017 -BD17       A01X+050067Y+152614X0120Y         S1      
327m0491            U6017 -BD20       A01X+050067Y+152417X0120Y         S1      
327m0491            U6017 -DF17       A01X+047232Y+152614X0120Y         S1      
327m0491            U6017 -DF20       A01X+047232Y+152417X0120Y         S1      
327m0491            VIA   -           A18X+042411Y+155393X0260Y         S2      
327m0491            C463  -1          A18X+047015Y+152655X0120Y0150R270 S2      
317m0491            VIA   -    MD0080PA00X+047015Y+152635X0160Y         S0      
327m0491            C456  -1          A18X+046960Y+152375X0120Y0150R090 S2      
317m0491            VIA   -    MD0080PA00X+046960Y+152395X0160Y         S0      
327m0491            C460  -1          A18X+050267Y+152375X0120Y0150R090 S2      
317m0491            VIA   -    MD0080PA00X+050267Y+152395X0160Y         S0      
317m0491            VIA   -    MD0100PA00X+042170Y+155184X0200Y         S0      
317m0491            VIA   -    MD0100PA00X+042412Y+155110X0200Y         S0      
317m0491            VIA   -    MD0100PA00X+042662Y+155184X0200Y         S0      
327m0491            R900  -1   M      A18X+042412Y+154820X0280Y0320R270 S2      
327m0491            R898  -2   M      A18X+042412Y+154820X0280Y0320R270 S2      
317m0491            VIA   -    MD0100PA00X+042412Y+154820X0200Y         S0      
317m0491            VIA   -    MD0080PA00X+050322Y+152635X0160Y         S0      
327m0491            C464  -1          A18X+050322Y+152655X0120Y0150R270 S2      
327m0492            C481  -1          A18X+052855Y+152665X0120Y0150R180 S2      
327m0492            C469  -1          A18X+044719Y+153914X0198Y0197R270 S2      
327m0492            C488  -1          A18X+044404Y+152382X0120Y0150     S2      
327m0492            C498  -1          A18X+044405Y+152873X0120Y0150     S2      
327m0492            C459  -1          A18X+044989Y+151667X0120Y0150R270 S2      
327m0492            C7031 -1          A18X+044690Y+150127X0400Y0500R180 S2      
327m0492            C7029 -1          A18X+045826Y+150044X0950Y1110R180 S2      
327m0492            C7030 -1          A18X+052074Y+150044X0950Y1110     S2      
327m0492            C476  -1          A18X+045548Y+153921X0198Y0197R090 S2      
327m0492            C487  -1          A18X+046965Y+153921X0198Y0197R090 S2      
327m0492            C490  -1          A18X+046493Y+153921X0198Y0197R090 S2      
327m0492            C501  -1          A18X+051217Y+153921X0198Y0197R090 S2      
327m0492            C482  -1          A18X+052162Y+153921X0198Y0197R090 S2      
327m0492            C494  -1          A18X+051690Y+153921X0198Y0197R090 S2      
327m0492            C486  -1          A18X+052695Y+153921X0198Y0197R090 S2      
327m0492            U6017 -AC17       A01X+051484Y+152614X0120Y         S1      
327m0492            U6017 -AC20       A01X+051484Y+152417X0120Y         S1      
327m0492            U6017 -T17        A01X+051957Y+152614X0120Y         S1      
327m0492            U6017 -T20        A01X+051957Y+152417X0120Y         S1      
327m0492            U6017 -AK17       A01X+051012Y+152614X0120Y         S1      
327m0492            U6017 -AK20       A01X+051012Y+152417X0120Y         S1      
327m0492            U6017 -AU17       A01X+050540Y+152614X0120Y         S1      
327m0492            U6017 -AU20       A01X+050540Y+152417X0120Y         S1      
327m0492            U6017 -DN17       A01X+046760Y+152614X0120Y         S1      
327m0492            U6017 -DN20       A01X+046760Y+152417X0120Y         S1      
327m0492            U6017 -DY17       A01X+046288Y+152614X0120Y         S1      
327m0492            U6017 -DY20       A01X+046288Y+152417X0120Y         S1      
327m0492            U6017 -EG17       A01X+045815Y+152614X0120Y         S1      
327m0492            U6017 -EG20       A01X+045815Y+152417X0120Y         S1      
327m0492            U6017 -EP17       A01X+045343Y+152614X0120Y         S1      
327m0492            U6017 -EP20       A01X+045343Y+152417X0120Y         S1      
327m0492            VIA   -           A18X+046071Y+155999X0260Y         S2      
327m0492            VIA   -           A18X+048372Y+156082X0260Y         S2      
327m0492            VIA   -           A18X+050757Y+155957X0260Y         S2      
327m0492            VIA   -           A18X+052765Y+155971X0260Y         S2      
327m0492            VIA   -           A18X+044077Y+155678X0260Y         S2      
327m0492            C471  -1          A18X+053562Y+154258X0400Y0500     S2      
327m0492            C499  -1          A18X+050745Y+153921X0198Y0197R090 S2      
327m0492            C483  -1          A18X+050272Y+153921X0198Y0197R090 S2      
327m0492            C472  -1          A18X+046020Y+153921X0198Y0197R090 S2      
327m0492            C480  -1          A18X+045075Y+153921X0198Y0197R090 S2      
317m0492            VIA   -    MD0100PA00X+042753Y+154180X0200Y         S0      
317m0492            VIA   -    MD0100PA00X+042753Y+154430X0200Y         S0      
317m0492            VIA   -    MD0100PA00X+042753Y+154680X0200Y         S0      
317m0492            VIA   -    MD0100PA00X+042753Y+154930X0200Y         S0      
317m0492            VIA   -    MD0100PA00X+043503Y+154180X0200Y         S0      
317m0492            VIA   -    MD0100PA00X+043503Y+154430X0200Y         S0      
317m0492            VIA   -    MD0100PA00X+043503Y+154680X0200Y         S0      
317m0492            VIA   -    MD0100PA00X+043503Y+154930X0200Y         S0      
327m0492            R900  -2   M      A18X+042992Y+154820X0280Y0320R270 S2      
317m0492            VIA   -    MD0100PA00X+043003Y+154930X0200Y         S0      
327m0492            L10   -2   M      A01X+043129Y+154536X0420Y0990     S1      
317m0492            VIA   -    MD0100PA00X+043003Y+154180X0200Y         S0      
317m0492            VIA   -    MD0100PA00X+043253Y+154430X0200Y         S0      
317m0492            VIA   -    MD0100PA00X+043253Y+154680X0200Y         S0      
317m0492            VIA   -    MD0100PA00X+043253Y+154930X0200Y         S0      
317m0492            VIA   -    MD0100PA00X+043253Y+154180X0200Y         S0      
317m0492            VIA   -    MD0100PA00X+043003Y+154430X0200Y         S0      
317m0492            VIA   -    MD0100PA00X+043003Y+154680X0200Y         S0      
327m0492            C466  -1          A18X+053562Y+153572X0400Y0500     S2      
327m0492            C485  -1          A18X+052631Y+152375X0120Y0150R090 S2      
327m0492            C496  -1   M      A18X+051267Y+152655X0120Y0150R270 S2      
327m0492            C492  -1   M      A18X+051212Y+152375X0120Y0150R090 S2      
327m0492            C473  -1   M      A18X+050795Y+152655X0120Y0150R270 S2      
327m0492            C453  -1   M      A18X+050740Y+152375X0120Y0150R090 S2      
327m0492            C495  -1   M      A18X+052212Y+152655X0120Y0150R270 S2      
327m0492            C462  -1   M      A18X+051740Y+152655X0120Y0150R270 S2      
327m0492            C448  -1   M      A18X+052157Y+152375X0120Y0150R090 S2      
327m0492            C470  -1   M      A18X+051684Y+152375X0120Y0150R090 S2      
317m0492            VIA   -    MD0080PA00X+051684Y+152395X0160Y         S0      
317m0492            VIA   -    MD0080PA00X+051740Y+152635X0160Y         S0      
317m0492            VIA   -    MD0080PA00X+052212Y+152635X0160Y         S0      
317m0492            VIA   -    MD0080PA00X+051267Y+152635X0160Y         S0      
317m0492            VIA   -    MD0080PA00X+051212Y+152395X0160Y         S0      
317m0492            VIA   -    MD0080PA00X+052157Y+152395X0160Y         S0      
317m0492            VIA   -    MD0080PA00X+050740Y+152395X0160Y         S0      
317m0492            VIA   -    MD0080PA00X+050795Y+152635X0160Y         S0      
327m0492            C479  -1          A18X+043468Y+153775X0400Y0500R180 S2      
327m0492            C475  -1          A18X+043465Y+153089X0400Y0500R180 S2      
317m0492            VIA   -    MD0080PA00X+046015Y+152395X0160Y         S0      
317m0492            VIA   -    MD0080PA00X+045543Y+152395X0160Y         S0      
317m0492            VIA   -    MD0080PA00X+046543Y+152635X0160Y         S0      
317m0492            VIA   -    MD0080PA00X+045125Y+152635X0160Y         S0      
317m0492            VIA   -    MD0080PA00X+045598Y+152635X0160Y         S0      
317m0492            VIA   -    MD0080PA00X+046070Y+152635X0160Y         S0      
317m0492            VIA   -    MD0080PA00X+045070Y+152395X0160Y         S0      
317m0492            VIA   -    MD0080PA00X+046488Y+152395X0160Y         S0      
327m0492            C497  -1   M      A18X+046488Y+152375X0120Y0150R090 S2      
327m0492            C452  -1   M      A18X+046015Y+152375X0120Y0150R090 S2      
327m0492            C477  -1   M      A18X+046543Y+152655X0120Y0150R270 S2      
327m0492            C457  -1   M      A18X+045598Y+152655X0120Y0150R270 S2      
327m0492            C450  -1   M      A18X+046070Y+152655X0120Y0150R270 S2      
327m0492            C455  -1   M      A18X+045070Y+152375X0120Y0150R090 S2      
327m0492            C491  -1   M      A18X+045543Y+152375X0120Y0150R090 S2      
327m0492            C500  -1   M      A18X+045125Y+152655X0120Y0150R270 S2      
317m0493            VIA   -    MD0100PA00X+055218Y+154820X0200Y         S0      
327m0493            R858  -2   M      A18X+055218Y+154820X0280Y0320R270 S2      
327m0493            R859  -1   M      A18X+055218Y+154820X0280Y0320R270 S2      
317m0493            VIA   -    MD0100PA00X+055468Y+155184X0200Y         S0      
317m0493            VIA   -    MD0100PA00X+055218Y+155110X0200Y         S0      
317m0493            VIA   -    MD0100PA00X+054976Y+155184X0200Y         S0      
327m0493            VIA   -           A18X+055217Y+155393X0260Y         S2      
327m0493            U6016 -BD17       A01X+062873Y+152614X0120Y         S1      
327m0493            U6016 -BD20       A01X+062873Y+152417X0120Y         S1      
327m0493            U6016 -DF17       A01X+060039Y+152614X0120Y         S1      
327m0493            U6016 -DF20       A01X+060039Y+152417X0120Y         S1      
327m0493            C390  -1          A18X+059766Y+152375X0120Y0150R090 S2      
317m0493            VIA   -    MD0080PA00X+059766Y+152395X0160Y         S0      
327m0493            C396  -1          A18X+059821Y+152655X0120Y0150R270 S2      
317m0493            VIA   -    MD0080PA00X+059821Y+152635X0160Y         S0      
327m0493            C394  -1          A18X+063073Y+152375X0120Y0150R090 S2      
317m0493            VIA   -    MD0080PA00X+063073Y+152395X0160Y         S0      
317m0493            VIA   -    MD0080PA00X+063128Y+152635X0160Y         S0      
327m0493            C397  -1          A18X+063128Y+152655X0120Y0150R270 S2      
327m0494            C413  -1          A18X+057526Y+153914X0198Y0197R270 S2      
327m0494            C384  -1          A18X+057210Y+152382X0120Y0150     S2      
327m0494            C386  -1          A18X+057796Y+151667X0120Y0150R270 S2      
327m0494            C393  -1          A18X+056979Y+153101X0120Y0150R090 S2      
327m0494            C7027 -1          A18X+058632Y+150044X0950Y1110R180 S2      
327m0494            C7028 -1          A18X+057514Y+150198X0400Y0500R180 S2      
327m0494            C7026 -1          A18X+064880Y+150044X0950Y1110     S2      
327m0494            C417  -1          A18X+058354Y+153921X0198Y0197R090 S2      
327m0494            C399  -1          A18X+059771Y+153921X0198Y0197R090 S2      
327m0494            C420  -1          A18X+063551Y+153921X0198Y0197R090 S2      
327m0494            C416  -1          A18X+063078Y+153921X0198Y0197R090 S2      
327m0494            C412  -1          A18X+064496Y+153921X0198Y0197R090 S2      
327m0494            C402  -1          A18X+065501Y+153921X0198Y0197R090 S2      
327m0494            C424  -1          A18X+064023Y+153921X0198Y0197R090 S2      
327m0494            U6016 -AC17       A01X+064291Y+152614X0120Y         S1      
327m0494            U6016 -AC20       A01X+064291Y+152417X0120Y         S1      
327m0494            U6016 -AK17       A01X+063818Y+152614X0120Y         S1      
327m0494            U6016 -AK20       A01X+063818Y+152417X0120Y         S1      
327m0494            U6016 -T17        A01X+064763Y+152614X0120Y         S1      
327m0494            U6016 -T20        A01X+064763Y+152417X0120Y         S1      
327m0494            U6016 -AU17       A01X+063346Y+152614X0120Y         S1      
327m0494            U6016 -AU20       A01X+063346Y+152417X0120Y         S1      
327m0494            U6016 -DN17       A01X+059566Y+152614X0120Y         S1      
327m0494            U6016 -DN20       A01X+059566Y+152417X0120Y         S1      
327m0494            U6016 -DY17       A01X+059094Y+152614X0120Y         S1      
327m0494            U6016 -DY20       A01X+059094Y+152417X0120Y         S1      
327m0494            U6016 -EG17       A01X+058621Y+152614X0120Y         S1      
327m0494            U6016 -EG20       A01X+058621Y+152417X0120Y         S1      
327m0494            U6016 -EP17       A01X+058149Y+152614X0120Y         S1      
327m0494            U6016 -EP20       A01X+058149Y+152417X0120Y         S1      
327m0494            VIA   -           A18X+058539Y+155936X0260Y         S2      
327m0494            VIA   -           A18X+060909Y+156026X0260Y         S2      
327m0494            VIA   -           A18X+062959Y+156054X0260Y         S2      
327m0494            VIA   -           A18X+064884Y+156166X0260Y         S2      
327m0494            VIA   -           A18X+056698Y+155552X0260Y         S2      
327m0494            C401  -1          A01X+066663Y+153674X0400Y0500R180 S1      
327m0494            C398  -1          A01X+066663Y+154360X0400Y0500R180 S1      
317m0494            VIA   -    MD0100PA00X+066095Y+154250X0200Y         S0      
317m0494            VIA   -    MD0100PA00X+066313Y+153874X0200Y         S0      
317m0494            VIA   -    MD0100PA00X+066313Y+154124X0200Y         S0      
317m0494            VIA   -    MD0100PA00X+066313Y+154374X0200Y         S0      
317m0494            VIA   -    MD0100PA00X+066095Y+154000X0200Y         S0      
327m0494            C431  -1          A18X+064968Y+153921X0198Y0197R090 S2      
327m0494            C429  -1          A18X+059299Y+153921X0198Y0197R090 S2      
327m0494            C406  -1          A18X+058826Y+153921X0198Y0197R090 S2      
327m0494            C410  -1          A18X+057881Y+153921X0198Y0197R090 S2      
317m0494            VIA   -    MD0100PA00X+056309Y+154430X0200Y         S0      
317m0494            VIA   -    MD0100PA00X+056309Y+154680X0200Y         S0      
317m0494            VIA   -    MD0100PA00X+056309Y+154930X0200Y         S0      
317m0494            VIA   -    MD0100PA00X+056309Y+154180X0200Y         S0      
317m0494            VIA   -    MD0100PA00X+055559Y+154430X0200Y         S0      
317m0494            VIA   -    MD0100PA00X+055559Y+154680X0200Y         S0      
317m0494            VIA   -    MD0100PA00X+055559Y+154930X0200Y         S0      
317m0494            VIA   -    MD0100PA00X+055559Y+154180X0200Y         S0      
327m0494            R859  -2   M      A18X+055798Y+154820X0280Y0320R270 S2      
317m0494            VIA   -    MD0100PA00X+055809Y+154930X0200Y         S0      
327m0494            L8    -2   M      A01X+055935Y+154536X0420Y0990     S1      
317m0494            VIA   -    MD0100PA00X+056059Y+154930X0200Y         S0      
317m0494            VIA   -    MD0100PA00X+055809Y+154680X0200Y         S0      
317m0494            VIA   -    MD0100PA00X+056059Y+154680X0200Y         S0      
317m0494            VIA   -    MD0100PA00X+056059Y+154430X0200Y         S0      
317m0494            VIA   -    MD0100PA00X+055809Y+154430X0200Y         S0      
317m0494            VIA   -    MD0100PA00X+056059Y+154180X0200Y         S0      
317m0494            VIA   -    MD0100PA00X+055809Y+154180X0200Y         S0      
327m0494            C426  -1          A18X+064996Y+151194X0120Y0150R270 S2      
327m0494            C418  -1          A18X+065438Y+152375X0120Y0150R090 S2      
327m0494            C430  -1   M      A18X+064546Y+152655X0120Y0150R270 S2      
327m0494            C422  -1   M      A18X+064491Y+152375X0120Y0150R090 S2      
327m0494            C427  -1   M      A18X+063601Y+152655X0120Y0150R270 S2      
327m0494            C400  -1   M      A18X+064073Y+152655X0120Y0150R270 S2      
327m0494            C387  -1   M      A18X+063546Y+152375X0120Y0150R090 S2      
327m0494            C391  -1   M      A18X+064018Y+152375X0120Y0150R090 S2      
327m0494            C395  -1   M      A18X+065018Y+152655X0120Y0150R270 S2      
327m0494            C382  -1   M      A18X+064963Y+152375X0120Y0150R090 S2      
317m0494            VIA   -    MD0080PA00X+064963Y+152395X0160Y         S0      
317m0494            VIA   -    MD0080PA00X+064546Y+152635X0160Y         S0      
317m0494            VIA   -    MD0080PA00X+065018Y+152635X0160Y         S0      
317m0494            VIA   -    MD0080PA00X+063601Y+152635X0160Y         S0      
317m0494            VIA   -    MD0080PA00X+063546Y+152395X0160Y         S0      
317m0494            VIA   -    MD0080PA00X+064018Y+152395X0160Y         S0      
317m0494            VIA   -    MD0080PA00X+064073Y+152635X0160Y         S0      
317m0494            VIA   -    MD0080PA00X+064491Y+152395X0160Y         S0      
327m0494            C409  -1          A18X+056272Y+153089X0400Y0500R180 S2      
327m0494            C405  -1          A18X+056274Y+153775X0400Y0500R180 S2      
317m0494            VIA   -    MD0080PA00X+058404Y+152635X0160Y         S0      
317m0494            VIA   -    MD0080PA00X+057932Y+152635X0160Y         S0      
317m0494            VIA   -    MD0080PA00X+058349Y+152395X0160Y         S0      
317m0494            VIA   -    MD0080PA00X+057876Y+152395X0160Y         S0      
317m0494            VIA   -    MD0080PA00X+059349Y+152635X0160Y         S0      
317m0494            VIA   -    MD0080PA00X+058821Y+152395X0160Y         S0      
317m0494            VIA   -    MD0080PA00X+058876Y+152635X0160Y         S0      
317m0494            VIA   -    MD0080PA00X+059294Y+152395X0160Y         S0      
327m0494            C389  -1   M      A18X+059294Y+152375X0120Y0150R090 S2      
327m0494            C403  -1   M      A18X+059349Y+152655X0120Y0150R270 S2      
327m0494            C407  -1   M      A18X+057876Y+152375X0120Y0150R090 S2      
327m0494            C425  -1   M      A18X+058349Y+152375X0120Y0150R090 S2      
327m0494            C428  -1   M      A18X+058404Y+152655X0120Y0150R270 S2      
327m0494            C421  -1   M      A18X+057932Y+152655X0120Y0150R270 S2      
327m0494            C415  -1   M      A18X+058821Y+152375X0120Y0150R090 S2      
327m0494            C411  -1   M      A18X+058876Y+152655X0120Y0150R270 S2      
317m0495            VIA   -    MD0080PA00X+044275Y+150751X0160Y         S0      
317m0495            VIA   -    MD0080PA00X+053071Y+153866X0160Y         S0      
317m0495            VIA   -    MD0080PA00X+052749Y+150736X0160Y         S0      
317m0495            VIA   -    MD0080PA00X+044495Y+150751X0160Y         S0      
317m0495            VIA   -    MD0080PA00X+044722Y+154462X0160Y         S0      
317m0495            VIA   -    MD0080PA00X+044315Y+154032X0160Y         S0      
317m0495            VIA   -    MD0080PA00X+052959Y+150736X0160Y         S0      
327m0495            U6017 -D1         A01X+052763Y+154048X0100Y0130     S1      
327m0495            U6017 -C2  M      A01X+052881Y+153843X0120Y         S1      
327m0495            U6017 -FH2        A01X+044377Y+153843X0120Y         S1      
327m0495            U6017 -FG35       A01X+044495Y+150946X0100Y0130     S1      
327m0495            VIA   -           A18X+053209Y+150822X0260Y         S2      
327m0495            U6017 -A35        A01X+052999Y+150946X0100Y0130     S1      
327m0495            R6903 -1          A18X+053892Y+150740X0120Y0150R180 S2      
327m0495            U6017 -D35 M      A01X+052763Y+150946X0100Y0130     S1      
327m0495            U6017 -C34        A01X+052881Y+151150X0120Y         S1      
327m0495            U6017 -FE2        A01X+044613Y+153843X0120Y         S1      
327m0495            U6017 -FG1 M      A01X+044495Y+154048X0100Y0130     S1      
327m0495            U6017 -FH34M      A01X+044377Y+151150X0120Y         S1      
327m0495            U6017 -FE34       A01X+044613Y+151150X0120Y         S1      
327m0496            U6016 -D1         A01X+065569Y+154048X0100Y0130     S1      
327m0496            U6016 -C2  M      A01X+065687Y+153843X0120Y         S1      
317m0496            VIA   -    MD0080PA00X+065877Y+153866X0160Y         S0      
327m0496            U6016 -FH2        A01X+057183Y+153843X0120Y         S1      
317m0496            VIA   -    MD0080PA00X+057122Y+154032X0160Y         S0      
327m0496            U6016 -FG1 M      A01X+057302Y+154048X0100Y0130     S1      
327m0496            U6016 -FE2        A01X+057420Y+153843X0120Y         S1      
317m0496            VIA   -    MD0080PA00X+057529Y+154462X0160Y         S0      
327m0496            U6016 -FG35       A01X+057302Y+150946X0100Y0130     S1      
317m0496            VIA   -    MD0080PA00X+057307Y+150746X0160Y         S0      
327m0496            U6016 -FE34       A01X+057420Y+151150X0120Y         S1      
327m0496            U6016 -FH34M      A01X+057183Y+151150X0120Y         S1      
317m0496            VIA   -    MD0080PA00X+057082Y+150751X0160Y         S0      
317m0496            VIA   -    MD0080PA00X+065556Y+150736X0160Y         S0      
317m0496            VIA   -    MD0080PA00X+065766Y+150736X0160Y         S0      
327m0496            VIA   -           A18X+066015Y+150822X0260Y         S2      
327m0496            U6016 -A35        A01X+065805Y+150946X0100Y0130     S1      
327m0496            R6797 -1          A18X+066345Y+150907X0120Y0150R180 S2      
327m0496            U6016 -D35 M      A01X+065569Y+150946X0100Y0130     S1      
327m0496            U6016 -C34        A01X+065687Y+151150X0120Y         S1      
327m0497            U6017 -A1         A01X+052999Y+154048X0100Y0130     S1      
327m0497            VIA   -           A01X+052845Y+156440X0300Y         S1      
327m0497            R6902 -1   M      A01X+053755Y+153957X0120Y0150     S1      
327m0498            U6016 -A1         A01X+065805Y+154048X0100Y0130     S1      
317m0498            VIA   -    M      A01X+066609Y+155365X0200Y         S2      
017m0498            VIA   -    M      A18X+066609Y+155365X0260Y         S2      
017m0498                  -    MD0100PA00X+066609Y+155365                       
327m0498            R6796 -1          A01X+066382Y+155365X0120Y0150R270 S1      
327m0499            R925  -2          A01X+044624Y+155581X0120Y0150R090 S1      
317m0499            VIA   -    M      A01X+043994Y+153260X0200Y         S2      
017m0499            VIA   -    M      A18X+043994Y+153260X0260Y         S2      
017m0499                  -    MD0100PA00X+043994Y+153260                       
327m0499            R926  -1   M      A01X+044381Y+155289X0120Y0150R270 S1      
327m0499            U6017 -FJ9        A01X+044363Y+153162X0100Y0130R090 S1      
327m0500            VIA   -           A01X+057240Y+156108X0300Y         S1      
327m0500            R885  -2   M      A01X+057137Y+155579X0120Y0150R090 S1      
327m0500            R886  -1   M      A01X+057137Y+155289X0120Y0150R270 S1      
327m0500            U6016 -FJ9        A01X+057169Y+153162X0100Y0130R090 S1      
327m0501            R912  -2          A01X+045732Y+155541X0120Y0150R090 S1      
327m0501            VIA   -    M      A01X+045347Y+155541X0300Y         S1      
327m0501            U6017 -FF8        A01X+044568Y+153280X0120Y         S1      
327m0501            R924  -1          A01X+044960Y+155704X0120Y0150R270 S1      
327m0502            VIA   -    M      A01X+057894Y+155583X0300Y         S1      
327m0502            U6016 -FF8        A01X+057374Y+153280X0120Y         S1      
327m0502            R871  -2          A01X+057565Y+155994X0120Y0150R090 S1      
327m0502            R884  -1   M      A01X+057565Y+155704X0120Y0150R270 S1      
327m0503            VIA   -    M      A01X+073226Y+163359X0300Y         S1      
327m0503            R9001 -2          A01X+073272Y+163010X0198Y0197R090 S1      
327m0503            U181  -9          A01X+073214Y+164333X0160Y0540     S1      
327m0504            U6017 -FJ28       A01X+044363Y+151744X0100Y0130R090 S1      
327m0504            VIA   -           A01X+043034Y+151431X0300Y         S1      
327m0504            R917  -1   M      A01X+043346Y+151442X0120Y0150     S1      
327m0505            VIA   -           A01X+055840Y+151431X0300Y         S1      
327m0505            U6016 -FJ28       A01X+057169Y+151744X0100Y0130R090 S1      
327m0505            R876  -1   M      A01X+056152Y+151442X0120Y0150     S1      
327m0506            U6017 -FJ25       A01X+044363Y+151981X0100Y0130R090 S1      
327m0506            R916  -1   M      A01X+043346Y+151804X0120Y0150     S1      
327m0506            VIA   -           A01X+042557Y+152020X0300Y         S1      
327m0506            R915  -2   M      A01X+043056Y+151764X0120Y0150R180 S1      
327m0507            U6016 -FJ25       A01X+057169Y+151981X0100Y0130R090 S1      
327m0507            R875  -1   M      A01X+056152Y+151804X0120Y0150     S1      
327m0507            VIA   -           A01X+055363Y+152020X0300Y         S1      
327m0507            R874  -2   M      A01X+055862Y+151764X0120Y0150R180 S1      
327m0508            U6015 -FF30       A01X+030956Y+151626X0120Y         S1      
327m0508            VIA   -           A01X+028922Y+151431X0300Y         S1      
327m0508            R788  -2   M      A01X+029345Y+151080X0120Y0150R180 S1      
327m0508            R791  -1   M      A01X+029735Y+151080X0120Y0150     S1      
317m0509            VIA   -    MD0080PA00X+030515Y+151812X0160Y         S0      
327m0509            U6015 -FF27       A01X+030956Y+151863X0120Y         S1      
327m0509            VIA   -    M      A18X+030515Y+151530X0260Y         S2      
327m0509            R786  -2          A18X+029445Y+151442X0120Y0150     S2      
327m0509            R787  -1   M      A18X+029735Y+151442X0120Y0150R180 S2      
317m0510            VIA   -    MD0080PA00X+030555Y+152161X0160Y         S0      
327m0510            R785  -1   M      A18X+029735Y+151804X0120Y0150R180 S2      
327m0510            R784  -2          A18X+029445Y+151804X0120Y0150     S2      
327m0510            U6015 -FF24       A01X+030956Y+152099X0120Y         S1      
327m0510            VIA   -    M      A18X+030337Y+152019X0260Y         S2      
327m0511            U6020 -6          A18X+087209Y+132489X0120Y0630R270 S2      
327m0511            VIA   -    M      A18X+086500Y+132350X0260Y         S2      
327m0511            R6736 -2          A18X+085955Y+132400X0120Y0150     S2      
327m0512            U6020 -7          A18X+087209Y+132745X0120Y0630R270 S2      
327m0512            VIA   -    M      A18X+086500Y+132850X0260Y         S2      
327m0512            R6737 -2          A18X+085955Y+132800X0120Y0150     S2      
327m0513            VIA   -    M      A18X+085071Y+132349X0260Y         S2      
327m0513            R780  -1          A18X+084775Y+132400X0120Y0150     S2      
327m0513            R6738 -2   M      A18X+085400Y+132455X0120Y0150R090 S2      
327m0513            R6736 -1          A18X+085745Y+132400X0120Y0150R180 S2      
327m0514            R779  -1          A18X+084775Y+132800X0120Y0150     S2      
327m0514            VIA   -    M      A18X+085073Y+132852X0260Y         S2      
327m0514            R6737 -1          A18X+085745Y+132800X0120Y0150R180 S2      
327m0514            R6739 -2   M      A18X+085400Y+132745X0120Y0150R270 S2      
317m0515            VIA   -    MD0080PA00X+039483Y+151634X0160Y         S0      
327m0515            R780  -2          A18X+084565Y+132400X0120Y0150R180 S2      
327m0515            U6015 -B28        A01X+039324Y+151744X0100Y0130R090 S1      
317m0515            VIA   -    M      A01X+083396Y+133946X0200Y         S2      
017m0515            VIA   -    M      A18X+083396Y+133946X0260Y         S2      
017m0515                  -    MD0100PA00X+083396Y+133946                       
317m0516            VIA   -    MD0080PA00X+039489Y+151407X0160Y         S0      
327m0516            VIA   -    M      A18X+084031Y+132930X0260Y         S2      
327m0516            R779  -2          A18X+084565Y+132800X0120Y0150R180 S2      
327m0516            U6015 -B31        A01X+039324Y+151508X0100Y0130R090 S1      
317m0516            VIA   -    MD0100PA00X+083385Y+134583X0200Y         S0      
327m0517            VIA   -           A01X+038682Y+155655X0300Y         S1      
327m0517            R6730 -2   M      A01X+039008Y+155655X0120Y0150R090 S1      
327m0517            R6731 -1   M      A01X+039008Y+155365X0120Y0150R270 S1      
327m0517            U6015 -G1         A01X+038916Y+154048X0100Y0130     S1      
317m0518            VIA   -    MD0080PA00X+030681Y+151322X0160Y         S0      
327m0518            VIA   -    M      A18X+030450Y+150930X0260Y         S2      
327m0518            R756  -1   M      A18X+029735Y+151080X0120Y0150R180 S2      
327m0518            R755  -2          A18X+029445Y+151080X0120Y0150     S2      
327m0518            U6015 -FF33       A01X+030956Y+151390X0120Y         S1      
327m0519            R735  -2          A01X+041106Y+151885X0120Y0150R270 S1      
327m0519            VIA   -    M      A01X+040477Y+152695X0300Y         S1      
327m0519            U6015 -B25        A01X+039324Y+151981X0100Y0130R090 S1      
327m0519            R741  -1   M      A01X+041106Y+152175X0120Y0150R090 S1      
327m0520            R745  -2          A01X+041426Y+151885X0120Y0150R270 S1      
327m0520            U6015 -B23        A01X+039324Y+152217X0100Y0130R090 S1      
327m0520            VIA   -    M      A01X+040977Y+152695X0300Y         S1      
327m0520            R746  -1   M      A01X+041426Y+152175X0120Y0150R090 S1      
327m0521            R796  -1   M      A01X+041161Y+150500X0120Y0150     S1      
327m0521            R795  -2   M      A01X+040641Y+150660X0120Y0150     S1      
327m0521            U6015 -F34        A01X+039034Y+151150X0120Y         S1      
327m0521            VIA   -           A01X+041493Y+150898X0300Y         S1      
317m0522            VIA   -    MD0080PA00X+017874Y+151322X0160Y         S0      
327m0522            U6014 -FF33       A01X+018150Y+151390X0120Y         S1      
327m0522            VIA   -    M      A18X+017651Y+150927X0260Y         S2      
327m0522            R6722 -2   M      A18X+017139Y+150664X0120Y0150     S2      
327m0522            R6723 -1          A18X+016929Y+150984X0120Y0150R180 S2      
327m0523            VIA   -    M      A01X+027670Y+152695X0300Y         S1      
327m0523            R6712 -2          A01X+028300Y+151885X0120Y0150R270 S1      
327m0523            R6713 -1   M      A01X+028300Y+152175X0120Y0150R090 S1      
327m0523            U6014 -B25        A01X+026517Y+151981X0100Y0130R090 S1      
327m0524            U6014 -B23        A01X+026517Y+152217X0100Y0130R090 S1      
327m0524            VIA   -    M      A01X+028170Y+152695X0300Y         S1      
327m0524            R6714 -2          A01X+028620Y+151885X0120Y0150R270 S1      
327m0524            R6715 -1   M      A01X+028620Y+152175X0120Y0150R090 S1      
327m0525            VIA   -           A01X+028687Y+150898X0300Y         S1      
327m0525            R6717 -1   M      A01X+028355Y+150500X0120Y0150     S1      
327m0525            R6716 -2   M      A01X+027835Y+150660X0120Y0150     S1      
327m0525            U6014 -F34        A01X+026228Y+151150X0120Y         S1      
317m0526            VIA   -    MD0100PA00X+030304Y+154430X0200Y         S0      
327m0526            R732  -2          A01X+030020Y+155579X0120Y0150R270 S1      
327m0526            R752  -1   M      A01X+030400Y+155289X0120Y0150R270 S1      
327m0526            R758  -2   M      A01X+030400Y+155579X0120Y0150R090 S1      
317m0526            VIA   -    MD0100PA00X+089062Y+134299X0200Y         S0      
317m0526            VIA   -    M      A01X+086477Y+084482X0200Y         S2      
017m0526            VIA   -    M      A18X+086477Y+084482X0260Y         S2      
017m0526                  -    MD0100PA00X+086477Y+084482                       
317m0526            VIA   -    MD0100PA00X+072758Y+073676X0200Y         S0      
317m0526            VIA   -    MD0100PA00X+070570Y+067953X0200Y         S0      
317m0526            VIA   -    MD0100PA00X+071212Y+054187X0200Y         S0      
327m0526            R6741 -1          A01X+070851Y+052692X0198Y0197R270 S1      
327m0527            R6741 -2          A01X+070851Y+052377X0198Y0197R270 S1      
327m0527            U18   -G18        A01X+071623Y+047344X0160Y    R090 S1      
317m0527            VIA   -    M      A01X+070850Y+051736X0200Y    R180 S2      
017m0527            VIA   -    M      A18X+070850Y+051736X0260Y    R180 S2      
017m0527                  -    MD0100PA00X+070850Y+051736                       
317m0527            VIA   -    MD0100PA00X+071469Y+047497X0180Y    R090 S0      
327m0528            VIA   -           A01X+031272Y+157598X0300Y         S1      
327m0528            R732  -1   M      A01X+030020Y+155369X0120Y0150R090 S1      
327m0528            U6015 -FF11       A01X+030956Y+153044X0120Y         S1      
327m0529            R731  -2          A01X+039644Y+155655X0120Y0150R090 S1      
327m0529            R749  -1   M      A01X+039644Y+155365X0120Y0150R270 S1      
317m0529            VIA   -    MD0100PA00X+039536Y+154652X0200Y         S0      
317m0529            VIA   -    MD0100PA00X+088885Y+133794X0200Y         S0      
317m0529            VIA   -    M      A01X+086511Y+085080X0200Y         S2      
017m0529            VIA   -    M      A18X+086511Y+085080X0260Y         S2      
017m0529                  -    MD0100PA00X+086511Y+085080                       
317m0529            VIA   -    MD0100PA00X+072939Y+073414X0200Y         S0      
317m0529            VIA   -    MD0100PA00X+070801Y+067684X0200Y         S0      
317m0529            VIA   -    MD0100PA00X+071046Y+055704X0200Y         S0      
327m0529            R6740 -1          A01X+071046Y+055255X0198Y0197R270 S1      
317m0530            VIA   -    MD0100PA00X+071469Y+047812X0180Y    R090 S0      
317m0530            VIA   -    M      A01X+071043Y+054575X0200Y         S2      
017m0530            VIA   -    M      A18X+071043Y+054575X0260Y         S2      
017m0530                  -    MD0100PA00X+071043Y+054575                       
327m0530            R6740 -2          A01X+071046Y+054940X0198Y0197R270 S1      
327m0530            U18   -G19        A01X+071623Y+047659X0160Y    R090 S1      
327m0531            VIA   -           A01X+039326Y+156078X0300Y         S1      
327m0531            R731  -1   M      A01X+039644Y+155865X0120Y0150R270 S1      
327m0531            U6015 -F2         A01X+039034Y+153843X0120Y         S1      
317m0532            VIA   -    MD0100PA00X+086560Y+084122X0200Y         S0      
317m0532            VIA   -    MD0100PA00X+072571Y+073414X0200Y         S0      
317m0532            VIA   -    MD0100PA00X+070358Y+067654X0200Y         S0      
327m0532            R6711 -1          A18X+070465Y+050092X0198Y0197R090 S2      
317m0532            VIA   -    MD0100PA00X+070266Y+053370X0200Y         S0      
317m0532            VIA   -    MD0100PA00X+075016Y+151645X0200Y         S0      
327m0532            R6709 -2          A01X+016255Y+153480X0120Y0150     S1      
327m0532            R6721 -1   M      A01X+016255Y+153160X0120Y0150     S1      
317m0532            VIA   -    M      A01X+015900Y+152548X0200Y         S2      
017m0532            VIA   -    M      A18X+015900Y+152548X0260Y         S2      
017m0532                  -    MD0100PA00X+015900Y+152548                       
327m0532            R6724 -2   M      A01X+015900Y+153055X0120Y0150R090 S1      
327m0533            R6711 -2          A18X+070465Y+049777X0198Y0197R090 S2      
327m0533            U18   -E21        A01X+070993Y+048288X0160Y    R090 S1      
317m0533            VIA   -    MD0100PA00X+070840Y+048442X0180Y    R090 S2      
327m0534            R6709 -1          A01X+016465Y+153480X0120Y0150R180 S1      
327m0534            VIA   -    M      A01X+016790Y+153000X0300Y         S1      
327m0534            U6014 -FF11       A01X+018150Y+153044X0120Y         S1      
317m0535            VIA   -    MD0100PA00X+075020Y+151231X0200Y         S0      
317m0535            VIA   -    MD0100PA00X+086367Y+083906X0200Y         S0      
317m0535            VIA   -    MD0100PA00X+072381Y+073678X0200Y         S0      
317m0535            VIA   -    MD0100PA00X+070139Y+067968X0200Y         S0      
327m0535            R6710 -1          A01X+070467Y+051089X0198Y0197R270 S1      
327m0535            VIA   -    M      A01X+070046Y+051716X0300Y         S1      
317m0535            VIA   -    MD0100PA00X+069683Y+053360X0200Y         S0      
317m0535            VIA   -    MD0100PA00X+026730Y+154612X0200Y         S0      
327m0535            R6708 -2          A01X+026838Y+155655X0120Y0150R090 S1      
327m0535            R6720 -1   M      A01X+026838Y+155365X0120Y0150R270 S1      
327m0536            R6710 -2          A01X+070467Y+050774X0198Y0197R270 S1      
327m0536            VIA   -    M      A01X+070604Y+050010X0300Y         S1      
327m0536            U18   -E22        A01X+070993Y+048604X0160Y    R090 S1      
327m0537            VIA   -           A01X+026462Y+156152X0300Y         S1      
327m0537            R6708 -1   M      A01X+026838Y+155865X0120Y0150R270 S1      
327m0537            U6014 -F2         A01X+026228Y+153843X0120Y         S1      
327m0538            R699  -1          A01X+026153Y+155322X0120Y0150R090 S1      
317m0538            VIA   -    MD0100PA00X+026153Y+155030X0200Y         S0      
317m0538            VIA   -    MD0100PA00X+038929Y+156125X0200Y         S0      
327m0538            R793  -1          A01X+030720Y+155789X0120Y0150R270 S1      
327m0538            R6730 -1          A01X+039008Y+155865X0120Y0150R270 S1      
327m0538            R759  -1          A01X+031148Y+156204X0120Y0150R270 S1      
327m0538            R758  -1          A01X+030400Y+155789X0120Y0150R270 S1      
317m0538            VIA   -    MD0100PA00X+043791Y+155391X0200Y         S0      
327m0538            R1464 -1          A01X+017979Y+165557X0120Y0150     S1      
327m0538            R1466 -1          A01X+017979Y+165237X0120Y0150     S1      
327m0538            R1465 -1          A01X+017979Y+164917X0120Y0150     S1      
327m0538            R1467 -1          A01X+017979Y+165877X0120Y0150     S1      
317m0538            VIA   -    MD0100PA00X+017767Y+165754X0200Y         S0      
317m0538            VIA   -    MD0100PA00X+017767Y+164922X0200Y         S0      
317m0538            VIA   -    MD0100PA00X+017751Y+165382X0200Y         S0      
327m0538            R857  -1          A01X+067586Y+152663X0180Y0200     S1      
327m0538            R897  -1   M      A01X+054395Y+151222X0180Y0200     S1      
327m0538            R704  -1   M      A01X+040784Y+151222X0180Y0200     S1      
327m0538            R6701 -1   M      A01X+027977Y+151222X0180Y0200     S1      
327m0538            C434  -1   M      A01X+054367Y+151984X0198Y0197R090 S1      
327m0538            C368  -1          A01X+068812Y+151645X0198Y0197R090 S1      
327m0538            C110  -1   M      A01X+040756Y+151984X0198Y0197R090 S1      
327m0538            C115  -1   M      A01X+027950Y+151984X0198Y0197R090 S1      
327m0538            PC6534-2   M      A01X+088937Y+114465X0198Y0197R090 S1      
327m0538            PR6524-2          A01X+089337Y+114465X0198Y0197R090 S1      
327m0538            L32   -1          A01X+067586Y+153053X0180Y0200     S1      
327m0538            L27   -1   M      A01X+027977Y+151612X0180Y0200     S1      
327m0538            L31   -1   M      A01X+040784Y+151612X0180Y0200     S1      
327m0538            L33   -1   M      A01X+054395Y+151612X0180Y0200     S1      
317m0538            VIA   -    MD0100PA00X+087691Y+122959X0200Y         S0      
317m0538            VIA   -    MD0100PA00X+087691Y+123259X0200Y         S0      
317m0538            VIA   -    MD0100PA00X+087691Y+123559X0200Y         S0      
317m0538            VIA   -    MD0100PA00X+090501Y+123594X0200Y         S0      
317m0538            VIA   -    MD0100PA00X+090501Y+123294X0200Y         S0      
317m0538            VIA   -    MD0100PA00X+090501Y+122994X0200Y         S0      
317m0538            VIA   -    MD0100PA00X+088169Y+123576X0200Y         S0      
317m0538            VIA   -    MD0100PA00X+088169Y+123276X0200Y         S0      
317m0538            VIA   -    MD0100PA00X+088169Y+122976X0200Y         S0      
327m0538            R1463 -1          A18X+066620Y+165752X0120Y0150R270 S2      
327m0538            R1462 -1          A18X+066260Y+165752X0120Y0150R270 S2      
317m0538            VIA   -    MD0100PA00X+066432Y+165448X0200Y         S0      
327m0538            R1513 -1          A18X+064700Y+167060X0120Y0150R270 S2      
327m0538            R1512 -1          A18X+064060Y+167060X0120Y0150R270 S2      
327m0538            R1511 -1          A18X+064380Y+167060X0120Y0150R270 S2      
317m0538            VIA   -    MD0100PA00X+064757Y+166850X0200Y         S0      
317m0538            VIA   -    MD0100PA00X+064307Y+166850X0200Y         S0      
317m0538            VIA   -    MD0100PA00X+065007Y+166850X0200Y         S0      
327m0538            R1510 -1          A18X+065020Y+167060X0120Y0150R270 S2      
317m0538            VIA   -    MD0100PA00X+067812Y+166279X0200Y         S0      
327m0538            U21   -8          A01X+067797Y+165855X0350Y0500R180 S1      
327m0538            C7504 -1          A01X+067664Y+165276X0120Y0150R180 S1      
317m0538            VIA   -    MD0100PA00X+065471Y+165381X0200Y         S0      
327m0538            U20   -8          A01X+065428Y+165833X0350Y0500R180 S1      
327m0538            C7503 -1   M      A01X+065185Y+165240X0120Y0150R180 S1      
327m0538            R826  -1          A18X+064609Y+165532X0120Y0150R090 S2      
327m0538            R827  -1   M      A18X+064922Y+165532X0120Y0150R090 S2      
317m0538            VIA   -    MD0100PA00X+066965Y+164092X0200Y         S0      
327m0538            R810  -1          A01X+066344Y+164040X0120Y0150R090 S1      
327m0538            R812  -1   M      A01X+066673Y+164040X0120Y0150R090 S1      
327m0538            R1469 -1          A18X+061795Y+163840X0120Y0150R180 S2      
327m0538            R1468 -1   M      A18X+061795Y+164160X0120Y0150R180 S2      
317m0538            VIA   -    MD0100PA00X+061395Y+164160X0200Y         S0      
327m0538            R870  -1          A01X+056817Y+155789X0120Y0150R270 S1      
327m0538            R6794 -1          A01X+065426Y+155865X0120Y0150R270 S1      
327m0538            R871  -1          A01X+057565Y+156204X0120Y0150R270 S1      
327m0538            R885  -1          A01X+057137Y+155789X0120Y0150R270 S1      
327m0538            R1448 -1   M      A01X+046395Y+157940X0120Y0150     S1      
327m0538            R1451 -1          A01X+046395Y+157620X0120Y0150     S1      
317m0538            VIA   -    MD0100PA00X+046222Y+158151X0200Y         S0      
327m0538            R927  -1          A01X+054462Y+150660X0120Y0150R180 S1      
327m0538            R1407 -1          A18X+094555Y+134600X0120Y0150     S2      
317m0538            VIA   -    MD0100PA00X+094765Y+134600X0200Y    R180 S0      
327m0538            R1403 -1          A18X+094555Y+134150X0120Y0150     S2      
317m0538            VIA   -    MD0100PA00X+094765Y+134150X0200Y    R180 S0      
327m0538            R1399 -1          A18X+094555Y+133250X0120Y0150     S2      
317m0538            VIA   -    MD0100PA00X+094765Y+133250X0200Y    R180 S0      
327m0538            R1402 -1          A18X+094555Y+133700X0120Y0150     S2      
317m0538            VIA   -    MD0100PA00X+094765Y+133700X0200Y    R180 S0      
327m0538            R1394 -1          A18X+094555Y+132800X0120Y0150     S2      
317m0538            VIA   -    MD0100PA00X+094765Y+132800X0200Y    R180 S0      
327m0538            R1393 -1          A18X+094555Y+132350X0120Y0150     S2      
317m0538            VIA   -    MD0100PA00X+094765Y+132350X0200Y    R180 S0      
327m0538            R1390 -1          A18X+094555Y+131900X0120Y0150     S2      
317m0538            VIA   -    MD0100PA00X+094765Y+131900X0200Y    R180 S0      
327m0538            R1361 -1          A18X+094555Y+131450X0120Y0150     S2      
317m0538            VIA   -    MD0100PA00X+094765Y+131450X0200Y    R180 S0      
327m0538            R1456 -1          A01X+037925Y+164580X0120Y0150R180 S1      
317m0538            VIA   -    MD0100PA00X+038135Y+164580X0200Y    R180 S0      
317m0538            VIA   -    MD0100PA00X+038135Y+164290X0200Y    R180 S0      
317m0538            VIA   -    MD0100PA00X+038135Y+164900X0200Y    R180 S0      
327m0538            R1455 -1          A01X+037925Y+164900X0120Y0150R180 S1      
327m0538            R1454 -1          A01X+037925Y+164260X0120Y0150R180 S1      
327m0538            R1461 -1          A01X+037925Y+163940X0120Y0150R180 S1      
327m0538            R1377 -1          A01X+040915Y+153800X0120Y0150     S1      
317m0538            VIA   -    MD0100PA00X+041011Y+153568X0200Y         S0      
317m0538            VIA   -    MD0100PA00X+071996Y+147704X0200Y    R180 S0      
317m0538            VIA   -    MD0100PA00X+071736Y+147704X0200Y    R180 S0      
317m0538            VIA   -    MD0100PA00X+072127Y+147479X0200Y    R180 S0      
317m0538            VIA   -    MD0100PA00X+071867Y+147479X0200Y    R180 S0      
317m0538            VIA   -    MD0100PA00X+071607Y+147479X0200Y    R180 S0      
317m0538            VIA   -    MD0100PA00X+071313Y+146981X0200Y    R180 S0      
317m0538            VIA   -    MD0100PA00X+071573Y+146981X0200Y    R180 S0      
317m0538            VIA   -    MD0100PA00X+071833Y+146981X0200Y    R180 S0      
317m0538            VIA   -    MD0100PA00X+072093Y+146981X0200Y    R180 S0      
317m0538            VIA   -    MD0100PA00X+071502Y+147229X0200Y    R180 S0      
317m0538            VIA   -    MD0100PA00X+071762Y+147229X0200Y    R180 S0      
317m0538            VIA   -    MD0100PA00X+072022Y+147229X0200Y    R180 S0      
317m0538            VIA   -    MD0100PA00X+071687Y+146742X0200Y    R180 S0      
317m0538            VIA   -    MD0100PA00X+071427Y+146742X0200Y    R180 S0      
317m0538            VIA   -    MD0100PA00X+071167Y+146742X0200Y    R180 S0      
317m0538            VIA   -    MD0100PA00X+071947Y+146742X0200Y    R180 S0      
327m0538            R1426 -1          A01X+069899Y+153625X0120Y0150     S1      
327m0538            R1490 -1          A01X+069899Y+154180X0120Y0150     S1      
327m0538            R1489 -1          A01X+069899Y+153170X0120Y0150     S1      
327m0538            R1499 -1          A01X+069899Y+155170X0120Y0150     S1      
327m0538            R1488 -1          A01X+069899Y+154840X0120Y0150     S1      
327m0538            R6707 -1          A01X+040298Y+155288X0120Y0150R090 S1      
327m0538            R6706 -1   M      A01X+040609Y+155284X0120Y0150R090 S1      
317m0538            VIA   -    MD0100PA00X+040533Y+154893X0200Y         S0      
327m0538            R1434 -1          A01X+056038Y+153285X0120Y0150R180 S1      
317m0538            VIA   -    MD0100PA00X+055922Y+153060X0200Y         S0      
317m0538            VIA   -    M      A01X+092011Y+122992X0200Y         S2      
017m0538            VIA   -    M      A18X+092011Y+122992X0260Y         S2      
017m0538                  -    MD0100PA00X+092011Y+122992                       
317m0538            VIA   -    MD0100PA00X+089125Y+122552X0200Y         S0      
317m0538            VIA   -    M      A01X+089125Y+121952X0200Y         S2      
017m0538            VIA   -    M      A18X+089125Y+121952X0260Y         S2      
017m0538                  -    MD0100PA00X+089125Y+121952                       
317m0538            VIA   -    M      A01X+091205Y+122552X0200Y         S2      
017m0538            VIA   -    M      A18X+091205Y+122552X0260Y         S2      
017m0538                  -    MD0100PA00X+091205Y+122552                       
317m0538            VIA   -    M      A01X+088671Y+123592X0200Y         S2      
017m0538            VIA   -    M      A18X+088671Y+123592X0260Y         S2      
017m0538                  -    MD0100PA00X+088671Y+123592                       
317m0538            VIA   -    M      A01X+089697Y+122987X0200Y         S2      
017m0538            VIA   -    M      A18X+089697Y+122987X0260Y         S2      
017m0538                  -    MD0100PA00X+089697Y+122987                       
317m0538            VIA   -    M      A01X+091071Y+123592X0200Y         S2      
017m0538            VIA   -    M      A18X+091071Y+123592X0260Y         S2      
017m0538                  -    MD0100PA00X+091071Y+123592                       
317m0538            VIA   -    M      A01X+087692Y+123952X0200Y         S2      
017m0538            VIA   -    M      A18X+087692Y+123952X0260Y         S2      
017m0538                  -    MD0100PA00X+087692Y+123952                       
317m0538            VIA   -    M      A01X+069925Y+150806X0200Y    R180 S2      
017m0538            VIA   -    M      A18X+069925Y+150806X0260Y    R180 S2      
017m0538                  -    MD0100PA00X+069925Y+150806                       
317m0538            VIA   -    M      A01X+069914Y+151377X0200Y    R180 S2      
017m0538            VIA   -    M      A18X+069914Y+151377X0260Y    R180 S2      
017m0538                  -    MD0100PA00X+069914Y+151377                       
317m0538            VIA   -    M      A01X+069350Y+151930X0200Y    R180 S2      
017m0538            VIA   -    M      A18X+069350Y+151930X0260Y    R180 S2      
017m0538                  -    MD0100PA00X+069350Y+151930                       
327m0538            R1388 -1          A01X+029621Y+153285X0120Y0150R180 S1      
317m0538            VIA   -    MD0100PA00X+029504Y+153060X0200Y         S0      
327m0538            R795  -1          A01X+040851Y+150660X0120Y0150R180 S1      
327m0538            R6724 -1          A01X+015900Y+153265X0120Y0150R270 S1      
327m0538            C436  -1          A18X+055184Y+152105X0198Y0197R270 S2      
327m0538            C439  -1          A18X+054784Y+152105X0198Y0197R270 S2      
317m0538            VIA   -    MD0100PA00X+054820Y+151209X0200Y    R180 S0      
317m0538            VIA   -    MD0100PA00X+055047Y+151103X0200Y    R180 S0      
317m0538            VIA   -    MD0100PA00X+055047Y+151358X0200Y    R180 S0      
317m0538            VIA   -    MD0100PA00X+054820Y+151464X0200Y    R180 S0      
317m0538            VIA   -    MD0100PA00X+054081Y+152144X0200Y         S0      
317m0538            VIA   -    MD0100PA00X+054367Y+151984X0200Y         S0      
327m0538            R902  -1          A01X+054717Y+151675X0120Y0150R090 S1      
327m0538            R904  -1          A01X+055037Y+151675X0120Y0150R090 S1      
327m0538            R874  -1          A01X+055652Y+151764X0120Y0150     S1      
327m0538            R882  -1          A01X+055552Y+151080X0120Y0150     S1      
317m0538            VIA   -    MD0100PA00X+054395Y+151222X0200Y    R180 S0      
327m0538            R878  -1          A18X+055652Y+151804X0120Y0150R180 S2      
327m0538            R880  -1          A18X+055652Y+151442X0120Y0150R180 S2      
327m0538            C432  -1   M      A18X+054230Y+152045X0400Y0500R090 S2      
327m0538            R868  -1          A18X+055652Y+151080X0120Y0150R180 S2      
327m0538            L9    -1   M      A18X+054450Y+151408X0440Y0540R180 S2      
317m0538            VIA   -    MD0100PA00X+054395Y+151612X0200Y    R180 S0      
327m0538            C122  -1          A18X+028367Y+152105X0198Y0197R270 S2      
327m0538            C118  -1          A18X+028767Y+152105X0198Y0197R270 S2      
327m0538            R786  -1          A18X+029235Y+151442X0120Y0150R180 S2      
327m0538            R784  -1          A18X+029235Y+151804X0120Y0150R180 S2      
327m0538            R755  -1          A18X+029235Y+151080X0120Y0150R180 S2      
327m0538            R788  -1          A01X+029135Y+151080X0120Y0150     S1      
327m0538            R781  -1          A01X+029235Y+151764X0120Y0150     S1      
327m0538            R6714 -1          A01X+028620Y+151675X0120Y0150R090 S1      
327m0538            R6712 -1          A01X+028300Y+151675X0120Y0150R090 S1      
327m0538            R6716 -1          A01X+028045Y+150660X0120Y0150R180 S1      
317m0538            VIA   -    MD0100PA00X+028402Y+151208X0200Y    R180 S0      
317m0538            VIA   -    MD0100PA00X+027664Y+152144X0200Y         S0      
317m0538            VIA   -    MD0100PA00X+027950Y+151984X0200Y         S0      
317m0538            VIA   -    MD0100PA00X+028402Y+151458X0200Y    R180 S0      
317m0538            VIA   -    MD0100PA00X+027977Y+151612X0200Y    R180 S0      
317m0538            VIA   -    MD0100PA00X+027977Y+151222X0200Y    R180 S0      
317m0538            VIA   -    MD0100PA00X+028259Y+150947X0200Y    R180 S0      
317m0538            VIA   -    MD0100PA00X+028009Y+150947X0200Y    R180 S0      
327m0538            L3    -1   M      A18X+028032Y+151408X0440Y0540R180 S2      
327m0538            C113  -1   M      A18X+027813Y+152045X0400Y0500R090 S2      
327m0538            C127  -1          A18X+041173Y+152105X0198Y0197R270 S2      
327m0538            C200  -1          A18X+041573Y+152105X0198Y0197R270 S2      
327m0538            R745  -1          A01X+041426Y+151675X0120Y0150R090 S1      
327m0538            R735  -1          A01X+041106Y+151675X0120Y0150R090 S1      
317m0538            VIA   -    MD0100PA00X+040470Y+152144X0200Y         S0      
317m0538            VIA   -    MD0100PA00X+040756Y+151984X0200Y         S0      
327m0538            C102  -1   M      A18X+040619Y+152045X0400Y0500R090 S2      
317m0538            VIA   -    MD0100PA00X+040784Y+151612X0200Y    R180 S0      
317m0538            VIA   -    MD0100PA00X+040784Y+151222X0200Y    R180 S0      
327m0538            L5    -1   M      A18X+040839Y+151408X0440Y0540R180 S2      
317m0538            VIA   -    MD0100PA00X+041209Y+151458X0200Y    R180 S0      
317m0538            VIA   -    MD0100PA00X+041209Y+151208X0200Y    R180 S0      
317m0538            VIA   -    MD0100PA00X+040815Y+150947X0200Y    R180 S0      
317m0538            VIA   -    MD0100PA00X+041065Y+150947X0200Y    R180 S0      
327m0538            R724  -1          A01X+016329Y+151080X0120Y0150     S1      
327m0538            R706  -1          A01X+016429Y+151804X0120Y0150     S1      
327m0538            R727  -1          A01X+015900Y+153595X0120Y0150R090 S1      
327m0538            R6725 -1          A01X+015900Y+154345X0120Y0150R270 S1      
327m0538            R6722 -1          A18X+016929Y+150664X0120Y0150R180 S2      
327m0538            R716  -1          A18X+016929Y+152254X0120Y0150R180 S2      
327m0538            R720  -1          A18X+016929Y+151614X0120Y0150R180 S2      
317m0538            VIA   -    MD0100PA00X+016219Y+151804X0200Y    R180 S0      
317m0538            VIA   -    MD0100PA00X+016119Y+151080X0200Y    R180 S0      
317m0538            VIA   -    MD0100PA00X+042313Y+151714X0200Y         S0      
317m0538            VIA   -    MD0100PA00X+042259Y+151071X0200Y         S0      
317m0538            VIA   -    MD0100PA00X+042509Y+151071X0200Y         S0      
317m0538            VIA   -    MD0100PA00X+042563Y+151714X0200Y         S0      
327m0538            R909  -1          A18X+042846Y+151080X0120Y0150R180 S2      
327m0538            R918  -1          A18X+042846Y+151804X0120Y0150R180 S2      
327m0538            R920  -1          A18X+042846Y+151442X0120Y0150R180 S2      
327m0538            R915  -1          A01X+042846Y+151764X0120Y0150     S1      
327m0538            R922  -1          A01X+042746Y+151080X0120Y0150     S1      
327m0538            C7502 -1   M      A01X+043666Y+156391X0120Y0150R180 S1      
327m0538            U19   -8          A01X+044037Y+156980X0350Y0500R180 S1      
327m0538            R6735 -1   M      A01X+042685Y+155710X0120Y0150R090 S1      
327m0538            R6734 -1   M      A01X+042996Y+155715X0120Y0150R090 S1      
317m0538            VIA   -    MD0100PA00X+042129Y+155773X0200Y         S0      
327m0538            C7501 -1   M      A01X+041342Y+156352X0120Y0150R180 S1      
317m0538            VIA   -    MD0100PA00X+041420Y+155940X0200Y         S0      
327m0538            U12   -8          A01X+041538Y+156980X0350Y0500R180 S1      
317m0538            VIA   -    MD0100PA00X+069340Y+150806X0200Y    R180 S0      
317m0538            VIA   -    MD0100PA00X+069068Y+150806X0200Y    R180 S0      
317m0538            VIA   -    MD0100PA00X+068753Y+150817X0200Y    R180 S0      
317m0538            VIA   -    MD0100PA00X+069624Y+150815X0200Y    R180 S0      
317m0538            VIA   -    MD0100PA00X+067834Y+151096X0200Y    R180 S0      
317m0538            VIA   -    MD0100PA00X+067839Y+150796X0200Y    R180 S0      
317m0538            VIA   -    MD0100PA00X+068156Y+151071X0200Y    R180 S0      
317m0538            VIA   -    MD0100PA00X+068152Y+150803X0200Y    R180 S0      
317m0538            VIA   -    MD0100PA00X+068456Y+151068X0200Y    R180 S0      
317m0538            VIA   -    MD0100PA00X+068460Y+150785X0200Y    R180 S0      
317m0538            VIA   -    MD0100PA00X+069633Y+151658X0200Y    R180 S0      
317m0538            VIA   -    MD0100PA00X+068072Y+151329X0200Y    R180 S0      
317m0538            VIA   -    MD0100PA00X+067550Y+151261X0200Y    R180 S0      
317m0538            VIA   -    MD0100PA00X+068367Y+151519X0200Y    R180 S0      
317m0538            VIA   -    MD0100PA00X+067317Y+151581X0200Y    R180 S0      
317m0538            VIA   -    MD0100PA00X+069075Y+151652X0200Y    R180 S0      
317m0538            VIA   -    MD0100PA00X+069359Y+151647X0200Y    R180 S0      
317m0538            VIA   -    MD0100PA00X+069366Y+151382X0200Y    R180 S0      
317m0538            VIA   -    MD0100PA00X+069075Y+151375X0200Y    R180 S0      
317m0538            VIA   -    MD0100PA00X+068771Y+151361X0200Y    R180 S0      
317m0538            VIA   -    MD0100PA00X+068767Y+151087X0200Y    R180 S0      
317m0538            VIA   -    MD0100PA00X+069082Y+151076X0200Y    R180 S0      
317m0538            VIA   -    MD0100PA00X+069353Y+151076X0200Y    R180 S0      
317m0538            VIA   -    MD0100PA00X+069633Y+151382X0200Y    R180 S0      
317m0538            VIA   -    MD0100PA00X+069637Y+151085X0200Y    R180 S0      
317m0538            VIA   -    MD0100PA00X+069905Y+151089X0200Y    R180 S0      
327m0538            R864  -1          A01X+069121Y+154072X0120Y0150R180 S1      
327m0538            R861  -1          A01X+069121Y+153752X0120Y0150R180 S1      
317m0538            VIA   -    MD0100PA00X+067787Y+151958X0200Y    R180 S0      
317m0538            VIA   -    MD0100PA00X+067834Y+151699X0200Y    R180 S0      
317m0538            VIA   -    MD0100PA00X+067812Y+152852X0200Y    R180 S0      
317m0538            VIA   -    MD0100PA00X+067787Y+152458X0200Y    R180 S0      
317m0538            VIA   -    MD0100PA00X+067787Y+152208X0200Y    R180 S0      
327m0538            C370  -1          A01X+068020Y+152653X0198Y0197     S1      
327m0538            C373  -1          A01X+068020Y+153053X0198Y0197     S1      
327m0538            C366  -1   M      A01X+068220Y+151430X0400Y0500R270 S1      
327m0538            R887  -1          A01X+067420Y+150834X0120Y0150R180 S1      
327m0538            L7    -1   M      A01X+067434Y+151420X0440Y0540     S1      
327m0538            R6753 -1          A18X+085400Y+134755X0120Y0150R090 S2      
317m0538            VIA   -    MD0100PA00X+085650Y+134850X0200Y         S0      
317m0538            VIA   -    MD0100PA00X+085650Y+133950X0200Y         S0      
317m0538            VIA   -    MD0100PA00X+085278Y+133836X0200Y         S0      
327m0538            R6752 -1   M      A18X+085400Y+134045X0120Y0150R270 S2      
327m0538            R6751 -1          A18X+085050Y+133855X0120Y0150R090 S2      
317m0538            VIA   -    MD0100PA00X+085650Y+133050X0200Y         S0      
317m0538            VIA   -    MD0100PA00X+085310Y+133169X0200Y         S0      
327m0538            R6750 -1          A18X+085050Y+133145X0120Y0150R270 S2      
327m0538            R6739 -1   M      A18X+085400Y+132955X0120Y0150R090 S2      
317m0538            VIA   -    MD0100PA00X+085650Y+132150X0200Y         S0      
317m0538            VIA   -    MD0100PA00X+085296Y+132032X0200Y         S0      
327m0538            R6738 -1   M      A18X+085400Y+132245X0120Y0150R270 S2      
327m0538            R6719 -1          A18X+085050Y+132055X0120Y0150R090 S2      
317m0538            VIA   -    MD0100PA00X+085281Y+131345X0200Y         S0      
327m0538            R6718 -1          A18X+085050Y+131345X0120Y0150R270 S2      
327m0538            PC6533-1   M      A01X+087692Y+124234X0198Y0197R090 S1      
317m0538            VIA   -    MD0100PA00X+092011Y+124192X0200Y         S0      
317m0538            VIA   -    MD0100PA00X+092011Y+123892X0200Y         S0      
317m0538            VIA   -    MD0100PA00X+092011Y+123292X0200Y         S0      
317m0538            VIA   -    MD0100PA00X+092011Y+123592X0200Y         S0      
317m0538            VIA   -    MD0100PA00X+090501Y+124192X0200Y         S0      
317m0538            VIA   -    MD0100PA00X+090501Y+123892X0200Y         S0      
317m0538            VIA   -    MD0100PA00X+091071Y+123292X0200Y         S0      
317m0538            VIA   -    MD0100PA00X+091071Y+122992X0200Y         S0      
317m0538            VIA   -    MD0100PA00X+091205Y+121952X0200Y         S0      
317m0538            VIA   -    MD0100PA00X+091205Y+122252X0200Y         S0      
317m0538            VIA   -    MD0100PA00X+091505Y+122252X0200Y         S0      
317m0538            VIA   -    MD0100PA00X+091505Y+121952X0200Y         S0      
317m0538            VIA   -    MD0100PA00X+091505Y+122552X0200Y         S0      
317m0538            VIA   -    MD0100PA00X+089691Y+123892X0200Y         S0      
317m0538            VIA   -    MD0100PA00X+089691Y+124192X0200Y         S0      
317m0538            VIA   -    MD0100PA00X+089697Y+123587X0200Y         S0      
317m0538            VIA   -    MD0100PA00X+089697Y+123287X0200Y         S0      
317m0538            VIA   -    MD0100PA00X+089125Y+122252X0200Y         S0      
317m0538            VIA   -    MD0100PA00X+088825Y+122252X0200Y         S0      
317m0538            VIA   -    MD0100PA00X+088825Y+122552X0200Y         S0      
317m0538            VIA   -    MD0100PA00X+088825Y+121952X0200Y         S0      
317m0538            VIA   -    MD0100PA00X+088181Y+124192X0200Y         S0      
317m0538            VIA   -    MD0100PA00X+088181Y+123892X0200Y         S0      
317m0538            VIA   -    MD0100PA00X+088671Y+123292X0200Y         S0      
317m0538            VIA   -    MD0100PA00X+088671Y+122992X0200Y         S0      
327m0538            PC6530-1          A18X+091602Y+124042X0400Y0500R090 S2      
327m0538            PC6529-1          A18X+090902Y+124042X0400Y0500R090 S2      
327m0538            PC6527-1          A18X+090092Y+124042X0400Y0500R090 S2      
327m0538            PC6528-1          A18X+089282Y+124042X0400Y0500R090 S2      
327m0538            PC6531-1          A18X+088582Y+124042X0400Y0500R090 S2      
327m0538            PC6532-1          A01X+091542Y+123476X0630Y1190R180 S1      
327m0538            PC6804-1          A01X+089142Y+123476X0630Y1190R180 S1      
327m0538            PL6502-2          A01X+090165Y+121974X1300Y1692R090 S1      
317m0538            VIA   -    MD0100PA00X+094103Y+128212X0200Y    R180 S0      
327m0538            R1234 -1          A18X+093821Y+128212X0198Y0197     S2      
327m0538            R1436 -1          A01X+037185Y+157940X0120Y0150R180 S1      
327m0538            R1437 -1   M      A01X+037185Y+158260X0120Y0150R180 S1      
317m0538            VIA   -    MD0100PA00X+037443Y+158260X0200Y         S0      
327m0538            R6900 -1          A01X+052619Y+155865X0120Y0150R270 S1      
327m0538            R912  -1   M      A01X+045732Y+155751X0120Y0150R270 S1      
327m0538            R925  -1   M      A01X+044624Y+155791X0120Y0150R270 S1      
327m0538            R911  -1   M      A01X+044304Y+155791X0120Y0150R270 S1      
327m0539            R664  -1   M      A01X+040469Y+151612X0180Y0200     S1      
327m0539            R653  -1   M      A01X+040469Y+151222X0180Y0200     S1      
327m0539            R704  -2   M      A01X+040469Y+151222X0180Y0200     S1      
327m0539            L31   -2   M      A01X+040469Y+151612X0180Y0200     S1      
327m0539            U6015 -BV17       A01X+035511Y+152614X0120Y         S1      
327m0539            C203  -1          A18X+035711Y+152375X0120Y0150R090 S2      
327m0539            C206  -1          A18X+035766Y+152655X0120Y0150R270 S2      
317m0539            VIA   -    MD0080PA00X+035711Y+152395X0160Y         S0      
317m0539            VIA   -    MD0080PA00X+035766Y+152635X0160Y         S0      
317m0539            VIA   -    MD0100PA00X+040469Y+151222X0200Y         S0      
317m0539            VIA   -    MD0100PA00X+040469Y+151612X0200Y         S0      
327m0540            VIA   -           A18X+039283Y+151802X0260Y         S2      
327m0540            R664  -2          A01X+040154Y+151612X0180Y0200     S1      
327m0540            R653  -2          A01X+040154Y+151222X0180Y0200     S1      
327m0540            C111  -1          A01X+040166Y+151984X0198Y0197R090 S1      
327m0540            C199  -1          A18X+035244Y+153921X0198Y0197R090 S2      
327m0540            C195  -1          A18X+034771Y+153921X0198Y0197R090 S2      
327m0540            U6015 -BV20       A01X+035511Y+152417X0120Y         S1      
327m0540            U6015 -CE17       A01X+035039Y+152614X0120Y         S1      
327m0540            U6015 -CE20       A01X+035039Y+152417X0120Y         S1      
327m0540            U6015 -CM17       A01X+034566Y+152614X0120Y         S1      
327m0540            U6015 -CM20       A01X+034566Y+152417X0120Y         S1      
327m0540            VIA   -           A18X+039279Y+151225X0260Y         S2      
317m0540            VIA   -    MD0100PA00X+040166Y+151984X0200Y    R180 S0      
317m0540            VIA   -    MD0100PA00X+039789Y+152144X0200Y    R180 S0      
327m0540            C103  -1   M      A18X+039939Y+152045X0400Y0500R090 S2      
317m0540            VIA   -    MD0100PA00X+039721Y+151445X0200Y         S0      
317m0540            VIA   -    MD0100PA00X+039721Y+151195X0200Y         S0      
317m0540            VIA   -    MD0100PA00X+039721Y+151695X0200Y         S0      
317m0540            VIA   -    MD0100PA00X+039538Y+151925X0200Y         S0      
317m0540            VIA   -    MD0100PA00X+040154Y+151222X0200Y         S0      
327m0540            L5    -2   M      A18X+040091Y+151408X0440Y0540R180 S2      
317m0540            VIA   -    MD0100PA00X+040154Y+151612X0200Y         S0      
327m0540            C217  -1   M      A18X+035239Y+152375X0120Y0150R090 S2      
327m0540            C287  -1   M      A18X+035294Y+152655X0120Y0150R270 S2      
327m0540            C288  -1   M      A18X+034766Y+152375X0120Y0150R090 S2      
327m0540            C202  -1   M      A18X+034821Y+152655X0120Y0150R270 S2      
327m0540            C204  -1   M      A18X+034349Y+152655X0120Y0150R270 S2      
327m0540            C205  -1   M      A18X+034294Y+152375X0120Y0150R090 S2      
317m0540            VIA   -    MD0080PA00X+035294Y+152635X0160Y         S0      
317m0540            VIA   -    MD0080PA00X+035239Y+152395X0160Y         S0      
317m0540            VIA   -    MD0080PA00X+034294Y+152395X0160Y         S0      
317m0540            VIA   -    MD0080PA00X+034349Y+152635X0160Y         S0      
317m0540            VIA   -    MD0080PA00X+034821Y+152635X0160Y         S0      
317m0540            VIA   -    MD0080PA00X+034766Y+152395X0160Y         S0      
327m0541            U6014 -BV17       A01X+022705Y+152614X0120Y         S1      
317m0541            VIA   -    MD0080PA00X+022960Y+152635X0160Y    R180 S0      
327m0541            C130  -1          A18X+022960Y+152655X0120Y0150R270 S2      
317m0541            VIA   -    MD0080PA00X+022905Y+152395X0160Y         S0      
327m0541            C125  -1          A18X+022905Y+152375X0120Y0150R090 S2      
317m0541            VIA   -    MD0100PA00X+027662Y+151222X0200Y         S0      
327m0541            R6703 -1   M      A01X+027662Y+151222X0180Y0200     S1      
327m0541            R6701 -2   M      A01X+027662Y+151222X0180Y0200     S1      
317m0541            VIA   -    MD0100PA00X+027662Y+151612X0200Y         S0      
327m0541            L27   -2   M      A01X+027662Y+151612X0180Y0200     S1      
327m0541            R6702 -1   M      A01X+027662Y+151612X0180Y0200     S1      
327m0542            VIA   -           A18X+026477Y+151800X0260Y         S2      
327m0542            R6702 -2          A01X+027347Y+151612X0180Y0200     S1      
327m0542            R6703 -2          A01X+027347Y+151222X0180Y0200     S1      
327m0542            C117  -1          A01X+027360Y+151984X0198Y0197R090 S1      
327m0542            C119  -1          A18X+022438Y+153921X0198Y0197R090 S2      
327m0542            C121  -1          A18X+021965Y+153921X0198Y0197R090 S2      
327m0542            U6014 -BV20       A01X+022705Y+152417X0120Y         S1      
327m0542            U6014 -CE17       A01X+022232Y+152614X0120Y         S1      
327m0542            U6014 -CE20       A01X+022232Y+152417X0120Y         S1      
327m0542            U6014 -CM17       A01X+021760Y+152614X0120Y         S1      
327m0542            U6014 -CM20       A01X+021760Y+152417X0120Y         S1      
327m0542            VIA   -           A18X+026467Y+151247X0260Y         S2      
317m0542            VIA   -    MD0100PA00X+026732Y+151925X0200Y    R270 S0      
317m0542            VIA   -    MD0100PA00X+026914Y+151695X0200Y    R270 S0      
317m0542            VIA   -    MD0100PA00X+026914Y+151445X0200Y    R270 S0      
317m0542            VIA   -    MD0100PA00X+027347Y+151222X0200Y    R180 S0      
317m0542            VIA   -    MD0100PA00X+027347Y+151612X0200Y    R180 S0      
317m0542            VIA   -    MD0100PA00X+026914Y+151195X0200Y    R270 S0      
327m0542            L3    -2   M      A18X+027284Y+151408X0440Y0540R180 S2      
317m0542            VIA   -    MD0100PA00X+027360Y+151984X0200Y    R180 S0      
317m0542            VIA   -    MD0100PA00X+026983Y+152144X0200Y    R180 S0      
327m0542            C114  -1   M      A18X+027132Y+152045X0400Y0500R090 S2      
317m0542            VIA   -    MD0080PA00X+021543Y+152635X0160Y         S0      
317m0542            VIA   -    MD0080PA00X+021488Y+152395X0160Y         S0      
327m0542            C123  -1   M      A18X+021543Y+152655X0120Y0150R270 S2      
327m0542            C134  -1   M      A18X+021488Y+152375X0120Y0150R090 S2      
317m0542            VIA   -    MD0080PA00X+021960Y+152395X0160Y         S0      
327m0542            C133  -1   M      A18X+021960Y+152375X0120Y0150R090 S2      
317m0542            VIA   -    MD0080PA00X+022432Y+152395X0160Y         S0      
327m0542            C131  -1   M      A18X+022432Y+152375X0120Y0150R090 S2      
317m0542            VIA   -    MD0080PA00X+022488Y+152635X0160Y         S0      
327m0542            C129  -1   M      A18X+022488Y+152655X0120Y0150R270 S2      
317m0542            VIA   -    MD0080PA00X+022015Y+152635X0160Y         S0      
327m0542            C126  -1   M      A18X+022015Y+152655X0120Y0150R270 S2      
327m0543            C7040 -1          A01X+055935Y+157872X0400Y0500R270 S1      
327m0543            C7038 -1          A01X+020477Y+157913X0400Y0500R270 S1      
327m0543            C7037 -1          A01X+021531Y+157778X0950Y1110     S1      
327m0543            C7041 -1          A01X+019785Y+157911X0400Y0500R270 S1      
327m0543            C7039 -1          A01X+029994Y+157888X0400Y0500R270 S1      
327m0543            C7007 -1          A01X+029275Y+157872X0400Y0500R270 S1      
327m0543            C7004 -1          A01X+027791Y+157783X0950Y1110R180 S1      
327m0543            C7006 -1          A01X+055240Y+157865X0400Y0500R270 S1      
327m0543            C7005 -1          A01X+054203Y+157783X0950Y1110R180 S1      
327m0543            C478  -1          A18X+049327Y+153921X0198Y0197R090 S2      
327m0543            C408  -1          A18X+062134Y+153921X0198Y0197R090 S2      
327m0543            C327  -1          A18X+035716Y+153921X0198Y0197R090 S2      
327m0543            C244  -1          A18X+022910Y+153921X0198Y0197R090 S2      
327m0543            PR6625-1          A18X+003000Y+150510X0280Y0320     S2      
327m0543            PC6807-1          A18X+010318Y+150580X0198Y0197R270 S2      
327m0543            PC6815-1          A18X+009148Y+149740X0950Y1110R270 S2      
327m0543            PC6643-1          A18X+007775Y+150452X0400Y0500R090 S2      
327m0543            PC6642-1          A18X+007086Y+150449X0400Y0500R090 S2      
327m0543            PC6813-1          A18X+005646Y+149740X0950Y1110R270 S2      
327m0543            PC6625-1          A18X+004296Y+150458X0400Y0500R090 S2      
327m0543            PC6624-1          A18X+003615Y+150458X0400Y0500R090 S2      
327m0543            PC6814-1          A18X+009608Y+148244X0950Y1110R090 S2      
327m0543            PC6627-1          A18X+007418Y+148244X0950Y1110R090 S2      
327m0543            PC6626-1          A18X+005008Y+148244X0950Y1110R090 S2      
327m0543            PC6628-1          A18X+002618Y+148244X0950Y1110R090 S2      
327m0543            C423  -1          A18X+062606Y+154006X0120Y0150R090 S2      
327m0543            VIA   -           A18X+061592Y+154672X0260Y         S2      
327m0543            C414  -1          A18X+060716Y+153921X0198Y0197R090 S2      
327m0543            C419  -1          A18X+060244Y+153921X0198Y0197R090 S2      
327m0543            VIA   -           A18X+048780Y+154672X0260Y         S2      
327m0543            C454  -1          A18X+049800Y+154006X0120Y0150R090 S2      
327m0543            C484  -1          A18X+047438Y+153921X0198Y0197R090 S2      
327m0543            C489  -1          A18X+047910Y+153921X0198Y0197R090 S2      
327m0543            VIA   -           A18X+035643Y+154672X0260Y         S2      
327m0543            C342  -1          A18X+036189Y+154006X0120Y0150R090 S2      
327m0543            VIA   -           A18X+034228Y+154679X0260Y         S2      
327m0543            C338  -1          A18X+033826Y+153921X0198Y0197R090 S2      
327m0543            C333  -1          A18X+034299Y+153921X0198Y0197R090 S2      
327m0543            C185  -1          A18X+023382Y+154006X0120Y0150R090 S2      
327m0543            VIA   -           A18X+022367Y+154680X0260Y         S2      
327m0543            C261  -1          A18X+021493Y+153921X0198Y0197R090 S2      
327m0543            C256  -1          A18X+021020Y+153921X0198Y0197R090 S2      
317m0543            VIA   -    MD0100PA00X+010897Y+148218X0200Y         S0      
317m0543            VIA   -    MD0100PA00X+010637Y+148218X0200Y         S0      
317m0543            VIA   -    MD0100PA00X+010900Y+148511X0200Y         S0      
317m0543            VIA   -    MD0100PA00X+010640Y+148511X0200Y         S0      
327m0543            U6016 -BL17       A01X+062401Y+152614X0120Y         S1      
327m0543            U6016 -BL20       A01X+062401Y+152417X0120Y         S1      
327m0543            U6016 -CW17       A01X+060511Y+152614X0120Y         S1      
327m0543            U6016 -CW20       A01X+060511Y+152417X0120Y         S1      
327m0543            U6017 -BL17       A01X+049595Y+152614X0120Y         S1      
327m0543            U6017 -BL20       A01X+049595Y+152417X0120Y         S1      
327m0543            U6017 -CW17       A01X+047705Y+152614X0120Y         S1      
327m0543            U6017 -CW20       A01X+047705Y+152417X0120Y         S1      
327m0543            U6015 -BL17       A01X+035984Y+152614X0120Y         S1      
327m0543            U6015 -BL20       A01X+035984Y+152417X0120Y         S1      
327m0543            U6015 -CW17       A01X+034094Y+152614X0120Y         S1      
327m0543            U6015 -CW20       A01X+034094Y+152417X0120Y         S1      
327m0543            U6014 -BL17       A01X+023177Y+152614X0120Y         S1      
327m0543            U6014 -BL20       A01X+023177Y+152417X0120Y         S1      
327m0543            U6014 -CW17       A01X+021288Y+152614X0120Y         S1      
327m0543            U6014 -CW20       A01X+021288Y+152417X0120Y         S1      
317m0543            VIA   -    MD0100PA00X+017779Y+158259X0200Y    R090 S0      
317m0543            VIA   -    MD0100PA00X+018029Y+158259X0200Y    R090 S0      
317m0543            VIA   -    MD0100PA00X+006670Y+148801X0200Y         S0      
317m0543            VIA   -    MD0100PA00X+005777Y+148805X0200Y    R090 S0      
317m0543            VIA   -    MD0100PA00X+004926Y+149345X0200Y         S0      
317m0543            VIA   -    MD0100PA00X+004926Y+149095X0200Y         S0      
317m0543            VIA   -    MD0100PA00X+007240Y+149649X0200Y         S0      
317m0543            VIA   -    MD0100PA00X+007240Y+149389X0200Y         S0      
317m0543            VIA   -    MD0100PA00X+007240Y+149129X0200Y         S0      
317m0543            VIA   -    MD0100PA00X+008405Y+150169X0200Y         S0      
317m0543            VIA   -    MD0100PA00X+010988Y+150188X0200Y         S0      
317m0543            VIA   -    MD0100PA00X+010158Y+149129X0200Y         S0      
317m0543            VIA   -    MD0100PA00X+010184Y+150186X0200Y         S0      
317m0543            VIA   -    MD0100PA00X+010293Y+148810X0200Y         S0      
317m0543            VIA   -    MD0100PA00X+006403Y+149660X0200Y         S0      
317m0543            VIA   -    MD0100PA00X+006403Y+149410X0200Y         S0      
317m0543            VIA   -    MD0100PA00X+006403Y+149160X0200Y         S0      
317m0543            VIA   -    MD0100PA00X+004918Y+149627X0200Y         S0      
317m0543            VIA   -    MD0100PA00X+055094Y+153665X0200Y         S0      
317m0543            VIA   -    MD0100PA00X+054967Y+153889X0200Y         S0      
317m0543            VIA   -    MD0100PA00X+017017Y+156262X0200Y    R090 S0      
317m0543            VIA   -    MD0100PA00X+016767Y+156262X0200Y    R090 S0      
317m0543            VIA   -    MD0100PA00X+016517Y+156262X0200Y    R090 S0      
317m0543            VIA   -    MD0100PA00X+016267Y+156262X0200Y    R090 S0      
317m0543            VIA   -    MD0100PA00X+016997Y+157012X0200Y    R090 S0      
317m0543            VIA   -    MD0100PA00X+016747Y+157012X0200Y    R090 S0      
317m0543            VIA   -    MD0100PA00X+016497Y+157012X0200Y    R090 S0      
317m0543            VIA   -    MD0100PA00X+016247Y+157012X0200Y    R090 S0      
317m0543            VIA   -    MD0100PA00X+016267Y+156512X0200Y    R090 S0      
317m0543            VIA   -    MD0100PA00X+016517Y+156512X0200Y    R090 S0      
317m0543            VIA   -    MD0100PA00X+016767Y+156512X0200Y    R090 S0      
317m0543            VIA   -    MD0100PA00X+017017Y+156512X0200Y    R090 S0      
317m0543            VIA   -    MD0100PA00X+016267Y+156762X0200Y    R090 S0      
317m0543            VIA   -    MD0100PA00X+016517Y+156762X0200Y    R090 S0      
317m0543            VIA   -    MD0100PA00X+016767Y+156762X0200Y    R090 S0      
317m0543            VIA   -    MD0100PA00X+017017Y+156762X0200Y    R090 S0      
327m0543            C229  -1          A01X+019104Y+157995X0400Y0500R090 S1      
327m0543            R6704 -1          A01X+017278Y+157249X0280Y0320R270 S1      
327m0543            L4    -1   M      A01X+016660Y+156638X0420Y0990R270 S1      
317m0543            VIA   -    MD0080PA00X+060294Y+152635X0160Y         S0      
317m0543            VIA   -    MD0080PA00X+060239Y+152395X0160Y         S0      
317m0543            VIA   -    MD0080PA00X+062656Y+152635X0160Y         S0      
317m0543            VIA   -    MD0080PA00X+062601Y+152395X0160Y         S0      
327m0543            C392  -1   M      A18X+062601Y+152375X0120Y0150R090 S2      
327m0543            C388  -1   M      A18X+062656Y+152655X0120Y0150R270 S2      
327m0543            C385  -1   M      A18X+060239Y+152375X0120Y0150R090 S2      
327m0543            C383  -1   M      A18X+060294Y+152655X0120Y0150R270 S2      
317m0543            VIA   -    MD0100PA00X+053872Y+154680X0200Y         S0      
317m0543            VIA   -    MD0100PA00X+053872Y+154930X0200Y         S0      
317m0543            VIA   -    MD0100PA00X+054122Y+154930X0200Y         S0      
317m0543            VIA   -    MD0100PA00X+054122Y+154680X0200Y         S0      
317m0543            VIA   -    MD0100PA00X+055122Y+154180X0200Y         S0      
317m0543            VIA   -    MD0100PA00X+055122Y+154430X0200Y         S0      
317m0543            VIA   -    MD0100PA00X+054872Y+154430X0200Y         S0      
317m0543            VIA   -    MD0100PA00X+054872Y+154180X0200Y         S0      
317m0543            VIA   -    MD0100PA00X+054872Y+154680X0200Y         S0      
317m0543            VIA   -    MD0100PA00X+054872Y+154930X0200Y         S0      
317m0543            VIA   -    MD0100PA00X+054372Y+154680X0200Y         S0      
317m0543            VIA   -    MD0100PA00X+054372Y+154930X0200Y         S0      
317m0543            VIA   -    MD0100PA00X+054622Y+154430X0200Y         S0      
317m0543            VIA   -    MD0100PA00X+054622Y+154680X0200Y         S0      
317m0543            VIA   -    MD0100PA00X+054622Y+154180X0200Y         S0      
327m0543            C404  -1   M      A18X+054946Y+153765X0400Y0500R270 S2      
327m0543            R858  -1   M      A18X+054638Y+154820X0280Y0320R270 S2      
317m0543            VIA   -    MD0100PA00X+054622Y+154930X0200Y         S0      
327m0543            L8    -1   M      A01X+054498Y+154536X0420Y0990     S1      
317m0543            VIA   -    MD0080PA00X+047488Y+152635X0160Y         S0      
317m0543            VIA   -    MD0080PA00X+047432Y+152395X0160Y         S0      
317m0543            VIA   -    MD0080PA00X+049850Y+152635X0160Y         S0      
317m0543            VIA   -    MD0080PA00X+049795Y+152395X0160Y         S0      
327m0543            C493  -1   M      A18X+049795Y+152375X0120Y0150R090 S2      
327m0543            C458  -1   M      A18X+049850Y+152655X0120Y0150R270 S2      
327m0543            C449  -1   M      A18X+047432Y+152375X0120Y0150R090 S2      
327m0543            C451  -1   M      A18X+047488Y+152655X0120Y0150R270 S2      
317m0543            VIA   -    MD0100PA00X+041710Y+153641X0200Y         S0      
317m0543            VIA   -    MD0100PA00X+042006Y+153760X0200Y         S0      
317m0543            VIA   -    MD0100PA00X+042256Y+153760X0200Y         S0      
317m0543            VIA   -    MD0100PA00X+041710Y+153891X0200Y         S0      
317m0543            VIA   -    MD0100PA00X+042066Y+154930X0200Y         S0      
317m0543            VIA   -    MD0100PA00X+042066Y+154680X0200Y         S0      
317m0543            VIA   -    MD0100PA00X+042066Y+154430X0200Y         S0      
317m0543            VIA   -    MD0100PA00X+042066Y+154180X0200Y         S0      
317m0543            VIA   -    MD0100PA00X+041566Y+154430X0200Y         S0      
317m0543            VIA   -    MD0100PA00X+041566Y+154680X0200Y         S0      
317m0543            VIA   -    MD0100PA00X+041566Y+154930X0200Y         S0      
317m0543            VIA   -    MD0100PA00X+041816Y+154180X0200Y         S0      
317m0543            VIA   -    MD0100PA00X+041816Y+154430X0200Y         S0      
317m0543            VIA   -    MD0100PA00X+041816Y+154680X0200Y         S0      
317m0543            VIA   -    MD0100PA00X+041566Y+154180X0200Y         S0      
317m0543            VIA   -    MD0100PA00X+042316Y+154430X0200Y         S0      
317m0543            VIA   -    MD0100PA00X+042316Y+154180X0200Y         S0      
327m0543            C474  -1   M      A18X+042140Y+153765X0400Y0500R270 S2      
327m0543            R898  -1   M      A18X+041832Y+154820X0280Y0320R270 S2      
317m0543            VIA   -    MD0100PA00X+041816Y+154930X0200Y         S0      
327m0543            L10   -1   M      A01X+041692Y+154536X0420Y0990     S1      
327m0543            C300  -1   M      A18X+036184Y+152375X0120Y0150R090 S2      
327m0543            C311  -1   M      A18X+036239Y+152655X0120Y0150R270 S2      
327m0543            C292  -1   M      A18X+033821Y+152375X0120Y0150R090 S2      
327m0543            C290  -1   M      A18X+033876Y+152655X0120Y0150R270 S2      
317m0543            VIA   -    MD0080PA00X+036184Y+152395X0160Y         S0      
317m0543            VIA   -    MD0080PA00X+036239Y+152635X0160Y         S0      
317m0543            VIA   -    MD0080PA00X+033821Y+152395X0160Y         S0      
317m0543            VIA   -    MD0080PA00X+033876Y+152635X0160Y         S0      
317m0543            VIA   -    MD0100PA00X+027455Y+154680X0200Y         S0      
317m0543            VIA   -    MD0100PA00X+027455Y+154930X0200Y         S0      
327m0543            R705  -1   M      A18X+028220Y+154820X0280Y0320R270 S2      
317m0543            VIA   -    MD0100PA00X+028205Y+154180X0200Y         S0      
317m0543            VIA   -    MD0100PA00X+027955Y+154680X0200Y         S0      
317m0543            VIA   -    MD0100PA00X+027955Y+154930X0200Y         S0      
317m0543            VIA   -    MD0100PA00X+028205Y+154430X0200Y         S0      
317m0543            VIA   -    MD0100PA00X+028205Y+154680X0200Y         S0      
317m0543            VIA   -    MD0100PA00X+028205Y+154930X0200Y         S0      
327m0543            L6    -1   M      A01X+028081Y+154536X0420Y0990     S1      
317m0543            VIA   -    MD0100PA00X+027705Y+154930X0200Y         S0      
317m0543            VIA   -    MD0100PA00X+027705Y+154680X0200Y         S0      
317m0543            VIA   -    MD0100PA00X+028705Y+154180X0200Y         S0      
317m0543            VIA   -    MD0100PA00X+028705Y+154430X0200Y         S0      
317m0543            VIA   -    MD0100PA00X+028455Y+154430X0200Y         S0      
317m0543            VIA   -    MD0100PA00X+028455Y+154180X0200Y         S0      
317m0543            VIA   -    MD0100PA00X+028455Y+154680X0200Y         S0      
317m0543            VIA   -    MD0100PA00X+028455Y+154930X0200Y         S0      
317m0543            VIA   -    MD0100PA00X+028651Y+153868X0200Y         S0      
317m0543            VIA   -    MD0100PA00X+028401Y+153868X0200Y         S0      
327m0543            C323  -1   M      A18X+028529Y+153765X0400Y0500R270 S2      
317m0543            VIA   -    MD0080PA00X+023432Y+152635X0160Y         S0      
327m0543            C137  -1   M      A18X+023432Y+152655X0120Y0150R270 S2      
317m0543            VIA   -    MD0080PA00X+023377Y+152395X0160Y         S0      
327m0543            C266  -1   M      A18X+023377Y+152375X0120Y0150R090 S2      
317m0543            VIA   -    MD0080PA00X+021015Y+152395X0160Y         S0      
327m0543            C139  -1   M      A18X+021015Y+152375X0120Y0150R090 S2      
317m0543            VIA   -    MD0080PA00X+021070Y+152635X0160Y         S0      
327m0543            C189  -1   M      A18X+021070Y+152655X0120Y0150R270 S2      
317m0543            VIA   -    MD0100PA00X+004832Y+154596X0200Y    R090 S0      
317m0543            VIA   -    MD0100PA00X+003382Y+147708X0200Y    R090 S0      
317m0543            VIA   -    MD0100PA00X+003382Y+148008X0200Y    R090 S0      
317m0543            VIA   -    MD0100PA00X+003382Y+148308X0200Y    R090 S0      
317m0543            VIA   -    MD0100PA00X+003382Y+148608X0200Y    R090 S0      
317m0543            VIA   -    MD0100PA00X+004282Y+147708X0200Y    R090 S0      
317m0543            VIA   -    MD0100PA00X+004282Y+148008X0200Y    R090 S0      
317m0543            VIA   -    MD0100PA00X+004282Y+148608X0200Y    R090 S0      
317m0543            VIA   -    MD0100PA00X+004282Y+148308X0200Y    R090 S0      
317m0543            VIA   -    MD0100PA00X+005782Y+147708X0200Y    R090 S0      
317m0543            VIA   -    MD0100PA00X+005782Y+148008X0200Y    R090 S0      
317m0543            VIA   -    MD0100PA00X+005782Y+148529X0200Y    R090 S0      
317m0543            VIA   -    MD0100PA00X+005782Y+148279X0200Y    R090 S0      
317m0543            VIA   -    MD0100PA00X+006678Y+147918X0200Y    R090 S0      
317m0543            VIA   -    MD0100PA00X+006671Y+148232X0200Y    R090 S0      
317m0543            VIA   -    MD0100PA00X+006701Y+147629X0200Y    R090 S0      
317m0543            VIA   -    MD0100PA00X+006671Y+148532X0200Y    R090 S0      
317m0543            VIA   -    MD0100PA00X+008182Y+148608X0200Y    R090 S0      
317m0543            VIA   -    MD0100PA00X+008182Y+148308X0200Y    R090 S0      
317m0543            VIA   -    MD0100PA00X+008872Y+148574X0200Y    R090 S0      
317m0543            VIA   -    MD0100PA00X+008872Y+148274X0200Y    R090 S0      
317m0543            VIA   -    MD0100PA00X+008182Y+147708X0200Y    R090 S0      
317m0543            VIA   -    MD0100PA00X+008182Y+148008X0200Y    R090 S0      
317m0543            VIA   -    MD0100PA00X+008872Y+147674X0200Y    R090 S0      
317m0543            VIA   -    MD0100PA00X+008872Y+147974X0200Y    R090 S0      
317m0543            VIA   -    MD0100PA00X+003865Y+149933X0200Y    R090 S0      
317m0543            VIA   -    MD0100PA00X+004131Y+149617X0200Y    R090 S0      
317m0543            VIA   -    MD0100PA00X+004136Y+149897X0200Y         S0      
317m0543            VIA   -    MD0100PA00X+004919Y+149918X0200Y    R090 S0      
317m0543            VIA   -    MD0100PA00X+005778Y+149058X0200Y         S0      
327m0543            PL6511-2   M      A01X+007112Y+149364X0790Y1660R270 S1      
317m0543            VIA   -    MD0100PA00X+006403Y+150160X0200Y         S0      
317m0543            VIA   -    MD0100PA00X+006403Y+149910X0200Y         S0      
317m0543            VIA   -    MD0100PA00X+007524Y+149664X0200Y         S0      
317m0543            VIA   -    MD0100PA00X+007524Y+149404X0200Y         S0      
317m0543            VIA   -    MD0100PA00X+007524Y+149924X0200Y         S0      
317m0543            VIA   -    MD0100PA00X+007524Y+149144X0200Y         S0      
317m0543            VIA   -    MD0100PA00X+008085Y+148864X0200Y         S0      
317m0543            VIA   -    MD0100PA00X+008093Y+149144X0200Y         S0      
317m0543            VIA   -    MD0100PA00X+008093Y+149664X0200Y         S0      
317m0543            VIA   -    MD0100PA00X+008093Y+149404X0200Y         S0      
317m0543            VIA   -    MD0100PA00X+007788Y+149144X0200Y         S0      
317m0543            VIA   -    MD0100PA00X+007788Y+149664X0200Y         S0      
317m0543            VIA   -    MD0100PA00X+007788Y+149404X0200Y         S0      
317m0543            VIA   -    MD0100PA00X+008399Y+149654X0200Y         S0      
317m0543            VIA   -    MD0100PA00X+010163Y+149399X0200Y    R180 S0      
327m0543            PL6512-2   M      A01X+009970Y+149364X0790Y1660R270 S1      
317m0543            VIA   -    MD0100PA00X+010153Y+149924X0200Y         S0      
317m0543            VIA   -    MD0100PA00X+010418Y+149389X0200Y         S0      
317m0543            VIA   -    MD0100PA00X+010418Y+149649X0200Y         S0      
317m0543            VIA   -    MD0100PA00X+010451Y+149920X0200Y         S0      
317m0543            VIA   -    MD0100PA00X+008389Y+148884X0200Y         S0      
317m0543            VIA   -    MD0100PA00X+008399Y+149144X0200Y         S0      
317m0543            VIA   -    MD0100PA00X+008399Y+149404X0200Y         S0      
317m0543            VIA   -    MD0100PA00X+008904Y+148851X0200Y         S0      
317m0543            VIA   -    MD0100PA00X+008909Y+149111X0200Y         S0      
317m0543            VIA   -    MD0100PA00X+010163Y+149649X0200Y    R180 S0      
317m0543            VIA   -    MD0100PA00X+010678Y+149649X0200Y         S0      
317m0543            VIA   -    MD0100PA00X+010805Y+148789X0200Y         S0      
317m0543            VIA   -    MD0100PA00X+010545Y+148789X0200Y         S0      
317m0543            VIA   -    MD0100PA00X+010678Y+149129X0200Y         S0      
317m0543            VIA   -    MD0100PA00X+010418Y+149129X0200Y         S0      
317m0543            VIA   -    MD0100PA00X+010678Y+149389X0200Y         S0      
317m0543            VIA   -    MD0100PA00X+010973Y+149657X0200Y         S0      
317m0543            VIA   -    MD0100PA00X+011060Y+148790X0200Y         S0      
317m0543            VIA   -    MD0100PA00X+010973Y+149137X0200Y         S0      
317m0543            VIA   -    MD0100PA00X+010973Y+149397X0200Y         S0      
317m0543            VIA   -    MD0100PA00X+008083Y+149924X0200Y         S0      
317m0543            VIA   -    MD0100PA00X+007788Y+149924X0200Y         S0      
317m0543            VIA   -    MD0100PA00X+007239Y+149921X0200Y         S0      
317m0543            VIA   -    MD0100PA00X+008389Y+149914X0200Y         S0      
317m0543            VIA   -    MD0100PA00X+010711Y+149920X0200Y         S0      
317m0543            VIA   -    MD0100PA00X+010462Y+150181X0200Y         S0      
317m0543            VIA   -    MD0100PA00X+010971Y+149920X0200Y         S0      
317m0543            VIA   -    MD0100PA00X+010720Y+150176X0200Y         S0      
317m0543            VIA   -    MD0100PA00X+010356Y+148213X0200Y    R090 S0      
317m0543            VIA   -    MD0100PA00X+010357Y+147648X0200Y    R090 S0      
317m0543            VIA   -    MD0100PA00X+010356Y+147913X0200Y    R090 S0      
317m0543            VIA   -    MD0100PA00X+010356Y+148513X0200Y    R090 S0      
327m0543            PC6632-1          A01X+002627Y+147894X0630Y1190     S1      
327m0543            PC6629-1          A01X+005027Y+147894X0630Y1190     S1      
327m0543            PC6630-1          A01X+007427Y+147894X0630Y1190     S1      
327m0543            PC6631-1          A01X+009827Y+147894X0630Y1190     S1      
327m0543            PR6600-2          A01X+003467Y+149791X0198Y0197     S1      
327m0543            PR6626-2          A01X+005070Y+154744X0198Y0197R090 S1      
327m0543            PC6623-1          A01X+005204Y+149922X0198Y0197R090 S1      
327m0543            PR6631-2          A01X+008312Y+154487X0198Y0197R180 S1      
317m0543            VIA   -    MD0100PA00X+008312Y+154229X0200Y         S0      
327m0544            U6015 -BD17       A01X+036456Y+152614X0120Y         S1      
327m0544            U6015 -BD20       A01X+036456Y+152417X0120Y         S1      
327m0544            U6015 -DF17       A01X+033621Y+152614X0120Y         S1      
327m0544            U6015 -DF20       A01X+033621Y+152417X0120Y         S1      
327m0544            VIA   -           A18X+028800Y+155393X0260Y         S2      
317m0544            VIA   -    MD0100PA00X+028800Y+154820X0200Y         S0      
327m0544            R705  -2   M      A18X+028800Y+154820X0280Y0320R270 S2      
327m0544            R712  -1   M      A18X+028800Y+154820X0280Y0320R270 S2      
317m0544            VIA   -    MD0100PA00X+029051Y+155184X0200Y         S0      
317m0544            VIA   -    MD0100PA00X+028800Y+155110X0200Y         S0      
317m0544            VIA   -    MD0100PA00X+028559Y+155184X0200Y         S0      
327m0544            C315  -1          A18X+036656Y+152375X0120Y0150R090 S2      
327m0544            C316  -1          A18X+036711Y+152655X0120Y0150R270 S2      
317m0544            VIA   -    MD0080PA00X+036656Y+152395X0160Y         S0      
317m0544            VIA   -    MD0080PA00X+036711Y+152635X0160Y         S0      
327m0544            C306  -1          A18X+033349Y+152375X0120Y0150R090 S2      
327m0544            C313  -1          A18X+033404Y+152655X0120Y0150R270 S2      
317m0544            VIA   -    MD0080PA00X+033349Y+152395X0160Y         S0      
317m0544            VIA   -    MD0080PA00X+033404Y+152635X0160Y         S0      
327m0545            C336  -1          A18X+031108Y+153914X0198Y0197R270 S2      
327m0545            C293  -1          A18X+031378Y+151667X0120Y0150R270 S2      
327m0545            C312  -1          A18X+030562Y+153101X0120Y0150R090 S2      
327m0545            C301  -1          A18X+030792Y+152382X0120Y0150     S2      
327m0545            C349  -1          A18X+039244Y+152665X0120Y0150R180 S2      
327m0545            C7023 -1          A18X+038463Y+150044X0950Y1110     S2      
327m0545            C7024 -1          A18X+032215Y+150044X0950Y1110R180 S2      
327m0545            C7025 -1          A18X+031087Y+150094X0400Y0500R180 S2      
327m0545            C329  -1          A18X+031937Y+153921X0198Y0197R090 S2      
327m0545            C318  -1          A18X+033354Y+153921X0198Y0197R090 S2      
327m0545            C339  -1          A18X+037134Y+153921X0198Y0197R090 S2      
327m0545            C343  -1          A18X+036661Y+153921X0198Y0197R090 S2      
327m0545            C331  -1          A18X+038078Y+153921X0198Y0197R090 S2      
327m0545            C351  -1          A18X+039084Y+153921X0198Y0197R090 S2      
327m0545            C335  -1          A18X+037606Y+153921X0198Y0197R090 S2      
327m0545            U6015 -T17        A01X+038346Y+152614X0120Y         S1      
327m0545            U6015 -T20        A01X+038346Y+152417X0120Y         S1      
327m0545            U6015 -AC17       A01X+037873Y+152614X0120Y         S1      
327m0545            U6015 -AC20       A01X+037873Y+152417X0120Y         S1      
327m0545            U6015 -AK17       A01X+037401Y+152614X0120Y         S1      
327m0545            U6015 -AK20       A01X+037401Y+152417X0120Y         S1      
327m0545            U6015 -AU17       A01X+036928Y+152614X0120Y         S1      
327m0545            U6015 -AU20       A01X+036928Y+152417X0120Y         S1      
327m0545            U6015 -DN17       A01X+033149Y+152614X0120Y         S1      
327m0545            U6015 -DN20       A01X+033149Y+152417X0120Y         S1      
327m0545            U6015 -DY17       A01X+032676Y+152614X0120Y         S1      
327m0545            U6015 -DY20       A01X+032676Y+152417X0120Y         S1      
327m0545            U6015 -EG17       A01X+032204Y+152614X0120Y         S1      
327m0545            U6015 -EG20       A01X+032204Y+152417X0120Y         S1      
327m0545            U6015 -EP17       A01X+031732Y+152614X0120Y         S1      
327m0545            U6015 -EP20       A01X+031732Y+152417X0120Y         S1      
327m0545            VIA   -           A18X+032628Y+156068X0260Y         S2      
327m0545            VIA   -           A18X+034943Y+156026X0260Y         S2      
327m0545            VIA   -           A18X+037397Y+155956X0260Y         S2      
327m0545            VIA   -           A18X+039294Y+155733X0260Y         S2      
327m0545            VIA   -           A18X+030341Y+155775X0260Y         S2      
327m0545            C328  -1          A18X+039961Y+154258X0400Y0500     S2      
327m0545            C354  -1          A18X+038551Y+153921X0198Y0197R090 S2      
327m0545            C321  -1          A18X+032882Y+153921X0198Y0197R090 S2      
327m0545            C325  -1          A18X+032409Y+153921X0198Y0197R090 S2      
327m0545            C332  -1          A18X+031464Y+153921X0198Y0197R090 S2      
317m0545            VIA   -    MD0100PA00X+029892Y+154430X0200Y         S0      
317m0545            VIA   -    MD0100PA00X+029892Y+154680X0200Y         S0      
317m0545            VIA   -    MD0100PA00X+029892Y+154930X0200Y         S0      
317m0545            VIA   -    MD0100PA00X+029892Y+154180X0200Y         S0      
327m0545            R712  -2   M      A18X+029380Y+154820X0280Y0320R270 S2      
317m0545            VIA   -    MD0100PA00X+029392Y+154180X0200Y         S0      
317m0545            VIA   -    MD0100PA00X+029642Y+154180X0200Y         S0      
317m0545            VIA   -    MD0100PA00X+029392Y+154430X0200Y         S0      
317m0545            VIA   -    MD0100PA00X+029642Y+154430X0200Y         S0      
317m0545            VIA   -    MD0100PA00X+029642Y+154680X0200Y         S0      
317m0545            VIA   -    MD0100PA00X+029392Y+154680X0200Y         S0      
317m0545            VIA   -    MD0100PA00X+029392Y+154930X0200Y         S0      
317m0545            VIA   -    MD0100PA00X+029642Y+154930X0200Y         S0      
327m0545            L6    -2   M      A01X+029518Y+154536X0420Y0990     S1      
317m0545            VIA   -    MD0100PA00X+029142Y+154430X0200Y         S0      
317m0545            VIA   -    MD0100PA00X+029142Y+154680X0200Y         S0      
317m0545            VIA   -    MD0100PA00X+029142Y+154930X0200Y         S0      
317m0545            VIA   -    MD0100PA00X+029142Y+154180X0200Y         S0      
327m0545            C317  -1          A18X+039961Y+153572X0400Y0500     S2      
327m0545            C353  -1          A18X+039020Y+152375X0120Y0150R090 S2      
327m0545            C289  -1   M      A18X+038546Y+152375X0120Y0150R090 S2      
327m0545            C291  -1   M      A18X+038601Y+152655X0120Y0150R270 S2      
327m0545            C346  -1   M      A18X+038073Y+152375X0120Y0150R090 S2      
327m0545            C340  -1   M      A18X+038128Y+152655X0120Y0150R270 S2      
327m0545            C344  -1   M      A18X+037656Y+152655X0120Y0150R270 S2      
327m0545            C307  -1   M      A18X+037601Y+152375X0120Y0150R090 S2      
327m0545            C314  -1   M      A18X+037128Y+152375X0120Y0150R090 S2      
327m0545            C350  -1   M      A18X+037184Y+152655X0120Y0150R270 S2      
317m0545            VIA   -    MD0080PA00X+038601Y+152635X0160Y         S0      
317m0545            VIA   -    MD0080PA00X+038128Y+152635X0160Y         S0      
317m0545            VIA   -    MD0080PA00X+038546Y+152395X0160Y         S0      
317m0545            VIA   -    MD0080PA00X+037184Y+152635X0160Y         S0      
317m0545            VIA   -    MD0080PA00X+037128Y+152395X0160Y         S0      
317m0545            VIA   -    MD0080PA00X+037601Y+152395X0160Y         S0      
317m0545            VIA   -    MD0080PA00X+037656Y+152635X0160Y         S0      
317m0545            VIA   -    MD0080PA00X+038073Y+152395X0160Y         S0      
327m0545            C324  -1          A18X+029854Y+153089X0400Y0500R180 S2      
327m0545            C320  -1          A18X+029857Y+153775X0400Y0500R180 S2      
327m0545            C294  -1   M      A18X+032876Y+152375X0120Y0150R090 S2      
327m0545            C334  -1   M      A18X+032932Y+152655X0120Y0150R270 S2      
327m0545            C337  -1   M      A18X+032404Y+152375X0120Y0150R090 S2      
327m0545            C319  -1   M      A18X+032459Y+152655X0120Y0150R270 S2      
327m0545            C322  -1   M      A18X+031987Y+152655X0120Y0150R270 S2      
327m0545            C326  -1   M      A18X+031459Y+152375X0120Y0150R090 S2      
327m0545            C330  -1   M      A18X+031932Y+152375X0120Y0150R090 S2      
327m0545            C341  -1   M      A18X+031514Y+152655X0120Y0150R270 S2      
317m0545            VIA   -    MD0080PA00X+032932Y+152635X0160Y         S0      
317m0545            VIA   -    MD0080PA00X+032876Y+152395X0160Y         S0      
317m0545            VIA   -    MD0080PA00X+032459Y+152635X0160Y         S0      
317m0545            VIA   -    MD0080PA00X+032404Y+152395X0160Y         S0      
317m0545            VIA   -    MD0080PA00X+031459Y+152395X0160Y         S0      
317m0545            VIA   -    MD0080PA00X+031932Y+152395X0160Y         S0      
317m0545            VIA   -    MD0080PA00X+031514Y+152635X0160Y         S0      
317m0545            VIA   -    MD0080PA00X+031987Y+152635X0160Y         S0      
327m0546            U6014 -BD17       A01X+023650Y+152614X0120Y         S1      
327m0546            U6014 -BD20       A01X+023650Y+152417X0120Y         S1      
327m0546            U6014 -DF17       A01X+020815Y+152614X0120Y         S1      
327m0546            U6014 -DF20       A01X+020815Y+152417X0120Y         S1      
327m0546            VIA   -           A18X+018212Y+157226X0260Y         S2      
327m0546            C198  -1          A18X+023905Y+152655X0120Y0150R270 S2      
317m0546            VIA   -    MD0080PA00X+023905Y+152635X0160Y         S0      
317m0546            VIA   -    MD0100PA00X+017858Y+156959X0200Y    R090 S0      
317m0546            VIA   -    MD0100PA00X+017858Y+157249X0200Y    R090 S0      
327m0546            R6704 -2   M      A01X+017858Y+157249X0280Y0320R270 S1      
327m0546            R6705 -1   M      A01X+017858Y+157249X0280Y0320R270 S1      
317m0546            VIA   -    MD0100PA00X+018109Y+157614X0200Y         S0      
317m0546            VIA   -    MD0100PA00X+017858Y+157539X0200Y         S0      
327m0546            C187  -1          A18X+023850Y+152375X0120Y0150R090 S2      
317m0546            VIA   -    MD0080PA00X+023850Y+152395X0160Y         S0      
317m0546            VIA   -    MD0080PA00X+020598Y+152635X0160Y         S0      
327m0546            C191  -1          A18X+020598Y+152655X0120Y0150R270 S2      
317m0546            VIA   -    MD0080PA00X+020543Y+152395X0160Y         S0      
327m0546            C201  -1          A18X+020543Y+152375X0120Y0150R090 S2      
327m0547            C7022 -1          A18X+018432Y+150245X0400Y0500R180 S2      
327m0547            C7020 -1          A18X+025657Y+150044X0950Y1110     S2      
327m0547            C7021 -1          A18X+019408Y+150044X0950Y1110R180 S2      
327m0547            C259  -1          A18X+019130Y+153921X0198Y0197R090 S2      
327m0547            C255  -1          A18X+020548Y+153921X0198Y0197R090 S2      
327m0547            C254  -1          A18X+020075Y+153921X0198Y0197R090 S2      
327m0547            C284  -1          A18X+024800Y+153921X0198Y0197R090 S2      
327m0547            C269  -1          A18X+025745Y+153921X0198Y0197R090 S2      
327m0547            C258  -1          A18X+025272Y+153921X0198Y0197R090 S2      
327m0547            C262  -1          A18X+026278Y+153921X0198Y0197R090 S2      
317m0547            VIA   -    MD0100PA00X+017017Y+155075X0200Y    R090 S0      
327m0547            U6014 -AC17       A01X+025067Y+152614X0120Y         S1      
327m0547            U6014 -AC20       A01X+025067Y+152417X0120Y         S1      
327m0547            U6014 -T17        A01X+025540Y+152614X0120Y         S1      
327m0547            U6014 -T20        A01X+025540Y+152417X0120Y         S1      
327m0547            U6014 -AK17       A01X+024595Y+152614X0120Y         S1      
327m0547            U6014 -AK20       A01X+024595Y+152417X0120Y         S1      
327m0547            U6014 -AU17       A01X+024122Y+152614X0120Y         S1      
327m0547            U6014 -AU20       A01X+024122Y+152417X0120Y         S1      
327m0547            U6014 -DN17       A01X+020343Y+152614X0120Y         S1      
327m0547            U6014 -DN20       A01X+020343Y+152417X0120Y         S1      
327m0547            U6014 -DY17       A01X+019870Y+152614X0120Y         S1      
327m0547            U6014 -DY20       A01X+019870Y+152417X0120Y         S1      
327m0547            U6014 -EG17       A01X+019398Y+152614X0120Y         S1      
327m0547            U6014 -EG20       A01X+019398Y+152417X0120Y         S1      
327m0547            U6014 -EP17       A01X+018925Y+152614X0120Y         S1      
327m0547            U6014 -EP20       A01X+018925Y+152417X0120Y         S1      
327m0547            VIA   -           A18X+020049Y+155733X0260Y         S2      
327m0547            VIA   -           A18X+023005Y+155998X0260Y         S2      
327m0547            VIA   -           A18X+025125Y+156054X0260Y         S2      
327m0547            VIA   -           A18X+026938Y+155510X0260Y         S2      
327m0547            VIA   -           A18X+018013Y+155176X0260Y         S2      
327m0547            C220  -1          A18X+027155Y+154258X0400Y0500     S2      
327m0547            C286  -1          A18X+024327Y+153921X0198Y0197R090 S2      
327m0547            C241  -1          A18X+023855Y+153921X0198Y0197R090 S2      
327m0547            C227  -1          A18X+019603Y+153921X0198Y0197R090 S2      
327m0547            C221  -1          A18X+018302Y+153914X0198Y0197R270 S2      
327m0547            C250  -1          A18X+018658Y+153921X0198Y0197R090 S2      
327m0547            L4    -2   M      A01X+016660Y+155202X0420Y0990R270 S1      
317m0547            VIA   -    MD0100PA00X+016267Y+155325X0200Y    R090 S0      
317m0547            VIA   -    MD0100PA00X+016267Y+155075X0200Y    R090 S0      
317m0547            VIA   -    MD0100PA00X+016517Y+155075X0200Y    R090 S0      
317m0547            VIA   -    MD0100PA00X+016517Y+155325X0200Y    R090 S0      
317m0547            VIA   -    MD0100PA00X+016767Y+155325X0200Y    R090 S0      
317m0547            VIA   -    MD0100PA00X+016767Y+155075X0200Y    R090 S0      
317m0547            VIA   -    MD0100PA00X+017017Y+155325X0200Y    R090 S0      
317m0547            VIA   -    MD0100PA00X+017017Y+155575X0200Y    R090 S0      
317m0547            VIA   -    MD0100PA00X+016767Y+155575X0200Y    R090 S0      
317m0547            VIA   -    MD0100PA00X+016517Y+155575X0200Y    R090 S0      
317m0547            VIA   -    MD0100PA00X+016267Y+155575X0200Y    R090 S0      
317m0547            VIA   -    MD0100PA00X+017305Y+155325X0200Y    R090 S0      
317m0547            VIA   -    MD0100PA00X+017305Y+155575X0200Y    R090 S0      
317m0547            VIA   -    MD0100PA00X+016015Y+155575X0200Y    R090 S0      
317m0547            VIA   -    MD0100PA00X+016015Y+155325X0200Y    R090 S0      
327m0547            C247  -1          A01X+018496Y+155910X0400Y0500R180 S1      
327m0547            C240  -1          A01X+018493Y+156595X0400Y0500R180 S1      
327m0547            R6705 -2          A01X+018438Y+157249X0280Y0320R270 S1      
327m0547            C280  -1          A18X+026214Y+152375X0120Y0150R090 S2      
327m0547            C225  -1          A18X+027155Y+153572X0400Y0500     S2      
327m0547            C264  -1          A18X+026437Y+152665X0120Y0150R180 S2      
327m0547            C283  -1   M      A18X+024377Y+152655X0120Y0150R270 S2      
317m0547            VIA   -    MD0080PA00X+024377Y+152635X0160Y         S0      
327m0547            C190  -1   M      A18X+024322Y+152375X0120Y0150R090 S2      
317m0547            VIA   -    MD0080PA00X+024322Y+152395X0160Y         S0      
327m0547            C222  -1   M      A18X+024795Y+152375X0120Y0150R090 S2      
317m0547            VIA   -    MD0080PA00X+024795Y+152395X0160Y         S0      
327m0547            C228  -1   M      A18X+024850Y+152655X0120Y0150R270 S2      
317m0547            VIA   -    MD0080PA00X+024850Y+152635X0160Y         S0      
327m0547            C253  -1   M      A18X+025795Y+152655X0120Y0150R270 S2      
317m0547            VIA   -    MD0080PA00X+025795Y+152635X0160Y         S0      
327m0547            C285  -1   M      A18X+025267Y+152375X0120Y0150R090 S2      
317m0547            VIA   -    MD0080PA00X+025267Y+152395X0160Y         S0      
327m0547            C192  -1   M      A18X+025322Y+152655X0120Y0150R270 S2      
317m0547            VIA   -    MD0080PA00X+025322Y+152635X0160Y         S0      
327m0547            C188  -1   M      A18X+025740Y+152375X0120Y0150R090 S2      
317m0547            VIA   -    MD0080PA00X+025740Y+152395X0160Y         S0      
327m0547            C186  -1          A18X+018572Y+151667X0120Y0150R270 S2      
327m0547            C281  -1          A18X+017756Y+153101X0120Y0150R090 S2      
327m0547            C257  -1          A18X+017986Y+152382X0120Y0150     S2      
327m0547            C135  -1   M      A18X+018653Y+152375X0120Y0150R090 S2      
317m0547            VIA   -    MD0080PA00X+018653Y+152395X0160Y         S0      
327m0547            C243  -1   M      A18X+019125Y+152375X0120Y0150R090 S2      
317m0547            VIA   -    MD0080PA00X+019125Y+152395X0160Y         S0      
327m0547            C260  -1   M      A18X+020125Y+152655X0120Y0150R270 S2      
317m0547            VIA   -    MD0080PA00X+020125Y+152635X0160Y         S0      
327m0547            C265  -1   M      A18X+020070Y+152375X0120Y0150R090 S2      
317m0547            VIA   -    MD0080PA00X+020070Y+152395X0160Y         S0      
327m0547            C282  -1   M      A18X+018708Y+152655X0120Y0150R270 S2      
317m0547            VIA   -    MD0080PA00X+018708Y+152635X0160Y         S0      
327m0547            C141  -1   M      A18X+019180Y+152655X0120Y0150R270 S2      
317m0547            VIA   -    MD0080PA00X+019180Y+152635X0160Y         S0      
327m0547            C184  -1   M      A18X+019653Y+152655X0120Y0150R270 S2      
317m0547            VIA   -    MD0080PA00X+019653Y+152635X0160Y         S0      
327m0547            C138  -1   M      A18X+019598Y+152375X0120Y0150R090 S2      
317m0547            VIA   -    MD0080PA00X+019598Y+152395X0160Y         S0      
317m0548            VIA   -    MD0080PA00X+039138Y+150736X0160Y         S0      
317m0548            VIA   -    MD0080PA00X+039348Y+150736X0160Y         S0      
317m0548            VIA   -    MD0080PA00X+030704Y+154032X0160Y         S0      
317m0548            VIA   -    MD0080PA00X+031111Y+154462X0160Y         S0      
317m0548            VIA   -    MD0080PA00X+039460Y+153866X0160Y         S0      
317m0548            VIA   -    MD0080PA00X+030889Y+150746X0160Y         S0      
327m0548            U6015 -C2  M      A01X+039270Y+153843X0120Y         S1      
327m0548            U6015 -D1         A01X+039152Y+154048X0100Y0130     S1      
327m0548            U6015 -FH2        A01X+030766Y+153843X0120Y         S1      
317m0548            VIA   -    MD0080PA00X+030669Y+150728X0160Y    R180 S0      
327m0548            U6015 -FG35       A01X+030884Y+150946X0100Y0130     S1      
327m0548            VIA   -           A18X+039598Y+150822X0260Y         S2      
327m0548            R6733 -1          A18X+040281Y+150740X0120Y0150R180 S2      
327m0548            U6015 -A35        A01X+039388Y+150946X0100Y0130     S1      
327m0548            U6015 -C34        A01X+039270Y+151150X0120Y         S1      
327m0548            U6015 -D35 M      A01X+039152Y+150946X0100Y0130     S1      
327m0548            U6015 -FG1 M      A01X+030884Y+154048X0100Y0130     S1      
327m0548            U6015 -FE2        A01X+031002Y+153843X0120Y         S1      
327m0548            U6015 -FH34M      A01X+030766Y+151150X0120Y         S1      
327m0548            U6015 -FE34       A01X+031002Y+151150X0120Y         S1      
327m0549            VIA   -           A01X+039118Y+156570X0300Y         S1      
327m0549            R6732 -1   M      A01X+039964Y+155365X0120Y0150R270 S1      
327m0549            U6015 -A1         A01X+039388Y+154048X0100Y0130     S1      
327m0550            VIA   -           A01X+030822Y+156108X0300Y         S1      
327m0550            R793  -2   M      A01X+030720Y+155579X0120Y0150R090 S1      
327m0550            R794  -1   M      A01X+030720Y+155289X0120Y0150R270 S1      
327m0550            U6015 -FJ9        A01X+030752Y+153162X0100Y0130R090 S1      
327m0551            U6015 -FF8        A01X+030956Y+153280X0120Y         S1      
327m0551            VIA   -    M      A01X+031477Y+155583X0300Y         S1      
327m0551            R759  -2          A01X+031148Y+155994X0120Y0150R090 S1      
327m0551            R792  -1   M      A01X+031148Y+155704X0120Y0150R270 S1      
327m0552            U6015 -FJ28       A01X+030752Y+151744X0100Y0130R090 S1      
327m0552            VIA   -           A01X+029422Y+151431X0300Y         S1      
327m0552            R783  -1   M      A01X+029735Y+151442X0120Y0150     S1      
327m0553            U6015 -FJ25       A01X+030752Y+151981X0100Y0130R090 S1      
327m0553            VIA   -           A01X+028946Y+152020X0300Y         S1      
327m0553            R781  -2   M      A01X+029445Y+151764X0120Y0150R180 S1      
327m0553            R782  -1   M      A01X+029735Y+151804X0120Y0150     S1      
327m0554            U6014 -FF30       A01X+018150Y+151626X0120Y         S1      
327m0554            VIA   -           A01X+016116Y+151431X0300Y         S1      
327m0554            R724  -2   M      A01X+016539Y+151080X0120Y0150R180 S1      
327m0554            R725  -1   M      A01X+016929Y+151080X0120Y0150     S1      
317m0555            VIA   -    MD0080PA00X+017709Y+151812X0160Y         S0      
327m0555            U6014 -FF27       A01X+018150Y+151863X0120Y         S1      
327m0555            VIA   -    M      A18X+017626Y+151552X0260Y         S2      
327m0555            R723  -1          A18X+016929Y+151294X0120Y0150R180 S2      
327m0555            R720  -2   M      A18X+017139Y+151614X0120Y0150     S2      
317m0556            VIA   -    MD0080PA00X+017749Y+152161X0160Y         S0      
327m0556            U6014 -FF24       A01X+018150Y+152099X0120Y         S1      
327m0556            VIA   -    M      A18X+017463Y+152254X0260Y         S2      
327m0556            R719  -1          A18X+016929Y+151934X0120Y0150R180 S2      
327m0556            R716  -2   M      A18X+017139Y+152254X0120Y0150     S2      
327m0557            VIA   -    M      A01X+016790Y+153500X0300Y         S1      
327m0557            U6014 -FJ9        A01X+017946Y+153162X0100Y0130R090 S1      
327m0557            R728  -1   M      A01X+016255Y+153800X0120Y0150     S1      
327m0557            R727  -2          A01X+015900Y+153805X0120Y0150R270 S1      
327m0558            VIA   -    M      A01X+016790Y+154000X0300Y         S1      
327m0558            U6014 -FF8        A01X+018150Y+153280X0120Y         S1      
327m0558            R6725 -2          A01X+015900Y+154135X0120Y0150R090 S1      
327m0558            R726  -1   M      A01X+016255Y+154250X0120Y0150     S1      
327m0559            U6014 -FJ28       A01X+017946Y+151744X0100Y0130R090 S1      
327m0559            VIA   -           A01X+016618Y+151442X0300Y         S1      
327m0559            R715  -1   M      A01X+016929Y+151442X0120Y0150     S1      
327m0560            U6014 -FJ25       A01X+017946Y+151981X0100Y0130R090 S1      
327m0560            VIA   -           A01X+015792Y+152097X0300Y         S1      
327m0560            R706  -2   M      A01X+016639Y+151804X0120Y0150R180 S1      
327m0560            R707  -1   M      A01X+016929Y+151804X0120Y0150     S1      
327m0561            VIA   -    M      A18X+007968Y+160529X0260Y         S2      
327m0561            PR6812-2          A18X+008167Y+160883X0198Y0197R090 S2      
327m0561            PR6816-2          A18X+007767Y+160883X0198Y0197R090 S2      
327m0562            PR6802-1          A18X+007906Y+162540X0198Y0197R180 S2      
317m0562            VIA   -    M      A01X+007538Y+162762X0200Y    R270 S2      
017m0562            VIA   -    M      A18X+007538Y+162762X0260Y    R270 S2      
017m0562                  -    MD0100PA00X+007538Y+162762                       
327m0562            PR6818-2          A01X+007906Y+162540X0198Y0197R180 S1      
327m0562            PU6510-19         A01X+006922Y+162092X0070Y0240R090 S1      
327m0563            VIA   -    M      A18X+173932Y+167744X0260Y         S2      
327m0563            PR6616-2          A18X+173143Y+167553X0198Y0197R270 S2      
327m0563            PR6615-2          A18X+172743Y+167553X0198Y0197R270 S2      
327m0564            PR6817-2          A01X+173004Y+165896X0198Y0197     S1      
327m0564            PR883 -1          A18X+173004Y+165896X0198Y0197     S2      
327m0564            PU6502-19         A01X+173988Y+166344X0070Y0240R270 S1      
317m0564            VIA   -    M      A01X+173450Y+165696X0200Y    R270 S2      
017m0564            VIA   -    M      A18X+173450Y+165696X0260Y    R270 S2      
017m0564                  -    MD0100PA00X+173450Y+165696                       
327m0565            PC6526-1          A01X+089539Y+115976X0198Y0197R090 S1      
327m0565            PR6801-2          A01X+089932Y+115983X0198Y0197R180 S1      
327m0566            PC6507-1          A01X+094242Y+115976X0198Y0197R090 S1      
327m0566            PR6800-2          A01X+094634Y+115983X0198Y0197R180 S1      
327m0567            PC6641-2          A01X+008433Y+151934X0198Y0197R180 S1      
327m0567            PR6630-1          A01X+008440Y+152326X0198Y0197R090 S1      
327m0568            PC6622-2          A01X+004859Y+151934X0198Y0197R180 S1      
327m0568            PR6624-1          A01X+004866Y+152326X0198Y0197R090 S1      
327m0569            U6020 -4          A18X+087209Y+131977X0120Y0630R270 S2      
327m0569            R6810 -2          A18X+085805Y+131500X0120Y0150     S2      
327m0569            VIA   -    M      A18X+086102Y+131450X0260Y         S2      
327m0570            U6020 -5          A18X+087209Y+132233X0120Y0630R270 S2      
327m0570            R6811 -2          A18X+085805Y+131900X0120Y0150     S2      
327m0570            VIA   -    M      A18X+086176Y+131950X0260Y         S2      
327m0571            R6813 -1          A18X+084405Y+131500X0120Y0150     S2      
327m0571            R6810 -1          A18X+085595Y+131500X0120Y0150R180 S2      
327m0571            VIA   -    M      A18X+084697Y+131387X0260Y         S2      
327m0571            R6718 -2   M      A18X+085050Y+131555X0120Y0150R090 S2      
327m0572            R6812 -1          A18X+084405Y+131900X0120Y0150     S2      
327m0572            R6811 -1          A18X+085595Y+131900X0120Y0150R180 S2      
327m0572            VIA   -    M      A18X+084703Y+131900X0260Y         S2      
327m0572            R6719 -2   M      A18X+085050Y+131845X0120Y0150R270 S2      
317m0573            VIA   -    MD0080PA00X+026677Y+151634X0160Y         S0      
327m0573            R6813 -2          A18X+084195Y+131500X0120Y0150R180 S2      
327m0573            U6014 -B28        A01X+026517Y+151744X0100Y0130R090 S1      
317m0573            VIA   -    M      A01X+083376Y+133016X0200Y         S2      
017m0573            VIA   -    M      A18X+083376Y+133016X0260Y         S2      
017m0573                  -    MD0100PA00X+083376Y+133016                       
317m0574            VIA   -    MD0080PA00X+026683Y+151407X0160Y         S0      
327m0574            R6812 -2          A18X+084195Y+131900X0120Y0150R180 S2      
327m0574            VIA   -    M      A18X+083753Y+132342X0260Y         S2      
327m0574            U6014 -B31        A01X+026517Y+151508X0100Y0130R090 S1      
317m0574            VIA   -    MD0100PA00X+083402Y+133625X0200Y         S0      
327m0575            PC6646-1   M      A01X+008877Y+154937X0198Y0197R180 S1      
327m0575            PC6611-1   M      A01X+005200Y+155137X0198Y0197R090 S1      
327m0575            PU6512-39         A01X+009311Y+154234X0090Y0240     S1      
317m0575            VIA   -    MD0100PA00X+008851Y+155230X0200Y         S0      
317m0575            VIA   -    MD0100PA00X+004920Y+155129X0200Y         S0      
327m0575            PU6511-39         A01X+005737Y+154234X0090Y0240     S1      
327m0575            PC6546-1          A01X+005013Y+159847X0198Y0197R270 S1      
327m0575            PC6545-1          A01X+004563Y+159847X0198Y0197R270 S1      
317m0575            VIA   -    M      A01X+004763Y+160090X0200Y    R090 S2      
017m0575            VIA   -    M      A18X+004763Y+160090X0260Y    R090 S2      
017m0575                  -    MD0100PA00X+004763Y+160090                       
327m0575            PU6510-40         A01X+005032Y+160832X0070Y0240R090 S1      
327m0576            PU6502-40         A01X+175878Y+167604X0070Y0240R270 S1      
317m0576            VIA   -    M      A01X+176146Y+168346X0200Y    R270 S2      
017m0576            VIA   -    M      A18X+176146Y+168346X0260Y    R270 S2      
017m0576                  -    MD0100PA00X+176146Y+168346                       
327m0576            PC6606-1          A01X+175896Y+168589X0198Y0197R090 S1      
327m0576            PC6605-1          A01X+176346Y+168589X0198Y0197R090 S1      
327m0576            PU6503-39         A01X+174465Y+157538X0090Y0240     S1      
327m0576            PC6553-1   M      A01X+173928Y+158440X0198Y0197R090 S1      
317m0576            VIA   -    M      A01X+173648Y+158433X0200Y    R090 S2      
017m0576            VIA   -    M      A18X+173648Y+158433X0260Y    R090 S2      
017m0576                  -    MD0100PA00X+173648Y+158433                       
327m0576            PC6576-1   M      A01X+177605Y+158240X0198Y0197R180 S1      
327m0576            PU6504-39         A01X+178040Y+157538X0090Y0240     S1      
317m0576            VIA   -    MD0100PA00X+177579Y+158533X0200Y         S0      
327m0577            PR6816-1          A18X+007767Y+161198X0198Y0197R090 S2      
317m0577            VIA   -    M      A01X+007413Y+161090X0200Y    R270 S2      
017m0577            VIA   -    M      A18X+007413Y+161090X0260Y    R270 S2      
017m0577                  -    MD0100PA00X+007413Y+161090                       
327m0577            PU6510-14         A01X+006922Y+161304X0070Y0240R090 S1      
327m0578            PR6548-1          A18X+003873Y+161367X0198Y0197R090 S2      
327m0578            PU6510-36         A01X+005032Y+161462X0070Y0240R090 S1      
317m0578            VIA   -    M      A01X+004393Y+161382X0200Y    R270 S2      
017m0578            VIA   -    M      A18X+004393Y+161382X0260Y    R270 S2      
017m0578                  -    MD0100PA00X+004393Y+161382                       
327m0579            PR6820-1          A18X+007906Y+162090X0198Y0197R180 S2      
317m0579            VIA   -    M      A01X+007413Y+162140X0200Y    R090 S2      
017m0579            VIA   -    M      A18X+007413Y+162140X0260Y    R090 S2      
017m0579                  -    MD0100PA00X+007413Y+162140                       
327m0579            PR6804-2          A01X+007906Y+162090X0198Y0197R180 S1      
327m0579            PU6510-18         A01X+006922Y+161934X0070Y0240R090 S1      
327m0580            PR6806-2          A01X+007906Y+161640X0198Y0197R180 S1      
327m0580            PR6811-1          A18X+007906Y+161640X0198Y0197R180 S2      
317m0580            VIA   -    M      A01X+007226Y+161673X0200Y    R090 S2      
017m0580            VIA   -    M      A18X+007226Y+161673X0260Y    R090 S2      
017m0580                  -    MD0100PA00X+007226Y+161673                       
327m0580            PU6510-17         A01X+006922Y+161777X0070Y0240R090 S1      
327m0581            PR6601-1          A01X+007374Y+163490X0198Y0197R180 S1      
317m0581            VIA   -    M      A01X+007916Y+163699X0200Y    R090 S2      
017m0581            VIA   -    M      A18X+007916Y+163699X0260Y    R090 S2      
017m0581                  -    MD0100PA00X+007916Y+163699                       
327m0581            PR6600-1          A01X+003152Y+149791X0198Y0197     S1      
317m0581            VIA   -    MD0100PA00X+002720Y+149823X0200Y         S0      
317m0581            VIA   -    MD0100PA00X+012672Y+163589X0200Y         S0      
317m0581            VIA   -    MD0100PA00X+040892Y+157680X0200Y         S0      
317m0582            VIA   -    M      A01X+012431Y+163349X0200Y         S2      
017m0582            VIA   -    M      A18X+012431Y+163349X0260Y         S2      
017m0582                  -    MD0100PA00X+012431Y+163349                       
327m0582            PU6510-22         A01X+006528Y+162485X0070Y0240     S1      
317m0582            VIA   -    MD0100PA00X+007576Y+163699X0200Y    R090 S0      
327m0582            PC6600-2   M      A01X+006706Y+163040X0198Y0197R180 S1      
327m0582            PR6602-1          A01X+003152Y+150221X0198Y0197     S1      
317m0582            VIA   -    MD0100PA00X+002720Y+150163X0200Y         S0      
317m0582            VIA   -    MD0100PA00X+040892Y+157380X0200Y         S0      
327m0583            R6800 -2          A18X+007909Y+162990X0198Y0197     S2      
317m0583            VIA   -    M      A01X+007057Y+162560X0200Y    R270 S2      
017m0583            VIA   -    M      A18X+007057Y+162560X0260Y    R270 S2      
017m0583                  -    MD0100PA00X+007057Y+162560                       
327m0583            PU6510-20         A01X+006922Y+162249X0070Y0240R090 S1      
327m0584            R662  -2          A01X+008261Y+160778X0198Y0197R090 S1      
327m0584            R6787 -1   M      A01X+007841Y+160778X0198Y0197R270 S1      
327m0584            PU6510-13         A01X+006922Y+161147X0070Y0240R090 S1      
327m0584            VIA   -    M      A01X+007423Y+160785X0300Y    R090 S1      
327m0585            R663  -2          A01X+004121Y+162690X0198Y0197     S1      
327m0585            PU6510-33         A01X+005032Y+161934X0070Y0240R090 S1      
327m0585            VIA   -    M      A01X+004583Y+162650X0300Y         S1      
327m0586            PR6533-2          A01X+004121Y+162290X0198Y0197     S1      
327m0586            PU6510-34         A01X+005032Y+161777X0070Y0240R090 S1      
327m0587            PR6616-1          A18X+173143Y+167238X0198Y0197R270 S2      
317m0587            VIA   -    M      A01X+173496Y+167346X0200Y    R090 S2      
017m0587            VIA   -    M      A18X+173496Y+167346X0260Y    R090 S2      
017m0587                  -    MD0100PA00X+173496Y+167346                       
327m0587            PU6502-14         A01X+173988Y+167132X0070Y0240R270 S1      
327m0588            PR6618-1          A18X+176929Y+166904X0198Y0197R180 S2      
317m0588            VIA   -    M      A01X+176516Y+167054X0200Y    R090 S2      
017m0588            VIA   -    M      A18X+176516Y+167054X0260Y    R090 S2      
017m0588                  -    MD0100PA00X+176516Y+167054                       
327m0588            PU6502-36         A01X+175878Y+166974X0070Y0240R270 S1      
327m0589            PR6803-2          A01X+173004Y+166346X0198Y0197     S1      
327m0589            PR6819-1          A18X+173004Y+166346X0198Y0197     S2      
327m0589            PU6502-18         A01X+173988Y+166502X0070Y0240R270 S1      
317m0589            VIA   -    M      A01X+173496Y+166296X0200Y    R270 S2      
017m0589            VIA   -    M      A18X+173496Y+166296X0260Y    R270 S2      
017m0589                  -    MD0100PA00X+173496Y+166296                       
327m0590            PR6810-1          A18X+173004Y+166796X0198Y0197     S2      
317m0590            VIA   -    M      A01X+173459Y+166620X0300Y         S1      
017m0590            VIA   -    M      A18X+173459Y+166620X0200Y         S1      
017m0590                  -    MD0100PA00X+173459Y+166620                       
327m0590            PR6805-2          A01X+173004Y+166796X0198Y0197     S1      
327m0590            PU6502-17         A01X+173988Y+166659X0070Y0240R270 S1      
317m0591            VIA   -    M      A01X+172660Y+154097X0200Y         S2      
017m0591            VIA   -    M      A18X+172660Y+154097X0260Y         S2      
017m0591                  -    MD0100PA00X+172660Y+154097                       
317m0591            VIA   -    MD0100PA00X+172638Y+164739X0200Y    R270 S0      
327m0591            PR6531-1          A01X+173535Y+164946X0198Y0197     S1      
327m0591            PR6530-1          A01X+173000Y+153095X0198Y0197     S1      
317m0592            VIA   -    M      A01X+173038Y+164739X0200Y    R270 S2      
017m0592            VIA   -    M      A18X+173038Y+164739X0260Y    R270 S2      
017m0592                  -    MD0100PA00X+173038Y+164739                       
327m0592            PC6540-2   M      A01X+174204Y+165396X0198Y0197     S1      
327m0592            PU6502-22         A01X+174382Y+165951X0070Y0240R180 S1      
317m0592            VIA   -    MD0100PA00X+173000Y+154097X0200Y         S0      
327m0592            PR6532-1          A01X+173000Y+153525X0198Y0197     S1      
327m0593            R6801 -2          A18X+173000Y+165446X0198Y0197R180 S2      
317m0593            VIA   -    M      A01X+173546Y+165196X0200Y    R090 S2      
017m0593            VIA   -    M      A18X+173546Y+165196X0260Y    R090 S2      
017m0593                  -    MD0100PA00X+173546Y+165196                       
327m0593            PU6502-20         A01X+173988Y+166187X0070Y0240R270 S1      
327m0594            VIA   -    M      A01X+173486Y+167651X0300Y    R270 S1      
327m0594            R651  -2          A01X+172084Y+167691X0198Y0197R090 S1      
327m0594            R6786 -1   M      A01X+173004Y+167696X0198Y0197R180 S1      
327m0594            PU6502-13         A01X+173988Y+167289X0070Y0240R270 S1      
327m0595            R652  -2          A01X+176789Y+165746X0198Y0197R180 S1      
327m0595            PU6502-33         A01X+175878Y+166502X0070Y0240R270 S1      
327m0595            VIA   -    M      A01X+176326Y+165786X0300Y    R180 S1      
327m0596            PR6603-2          A01X+176789Y+166146X0198Y0197R180 S1      
327m0596            PU6502-34         A01X+175878Y+166659X0070Y0240R270 S1      
327m0597            R699  -2   M      A01X+026153Y+155532X0120Y0150R270 S1      
327m0597            R701  -1          A01X+025447Y+155534X0120Y0150R270 S1      
327m0597            VIA   -    M      A01X+025856Y+155866X0300Y         S1      
327m0597            U6014 -G1         A01X+026110Y+154048X0100Y0130     S1      
317m0598            VIA   -    MD0080PA00X+026654Y+153866X0160Y         S0      
317m0598            VIA   -    MD0080PA00X+018305Y+154462X0160Y         S0      
317m0598            VIA   -    MD0080PA00X+017898Y+154032X0160Y         S0      
317m0598            VIA   -    MD0080PA00X+017858Y+150751X0160Y         S0      
317m0598            VIA   -    MD0080PA00X+026332Y+150736X0160Y         S0      
317m0598            VIA   -    MD0080PA00X+026542Y+150736X0160Y         S0      
317m0598            VIA   -    MD0080PA00X+018078Y+150751X0160Y         S0      
327m0598            U6014 -C2  M      A01X+026464Y+153843X0120Y         S1      
327m0598            U6014 -D1         A01X+026346Y+154048X0100Y0130     S1      
327m0598            U6014 -FH2        A01X+017960Y+153843X0120Y         S1      
327m0598            U6014 -FE2        A01X+018196Y+153843X0120Y         S1      
327m0598            U6014 -FG1 M      A01X+018078Y+154048X0100Y0130     S1      
327m0598            U6014 -FG35       A01X+018078Y+150946X0100Y0130     S1      
327m0598            VIA   -           A18X+026792Y+150822X0260Y         S2      
327m0598            U6014 -C34        A01X+026464Y+151150X0120Y         S1      
327m0598            U6014 -D35 M      A01X+026346Y+150946X0100Y0130     S1      
327m0598            R709  -1          A18X+027475Y+150740X0120Y0150R180 S2      
327m0598            U6014 -A35        A01X+026582Y+150946X0100Y0130     S1      
327m0598            U6014 -FH34M      A01X+017960Y+151150X0120Y         S1      
327m0598            U6014 -FE34       A01X+018196Y+151150X0120Y         S1      
327m0599            VIA   -           A01X+025949Y+156511X0300Y         S1      
327m0599            R711  -1   M      A01X+027158Y+155435X0120Y0150R270 S1      
327m0599            U6014 -A1         A01X+026582Y+154048X0100Y0130     S1      
327m0600            PC6600-1   M      A01X+007021Y+163040X0198Y0197R180 S1      
327m0600            PR6601-2          A01X+007059Y+163490X0198Y0197R180 S1      
327m0600            PU6510-21         A01X+006685Y+162485X0070Y0240     S1      
327m0601            PC6540-1   M      A01X+173889Y+165396X0198Y0197     S1      
327m0601            PR6531-2          A01X+173850Y+164946X0198Y0197     S1      
327m0601            PU6502-21         A01X+174224Y+165951X0070Y0240R180 S1      
327UV_P2V5_COMP     C8020 -1   M      A01X+056042Y+045100X0198Y0197     S1      
327UV_P2V5_COMP     R8120 -2   M      A01X+055358Y+045100X0198Y0197     S1      
327UV_P2V5_COMP     VIA   -    M      A01X+055698Y+045100X0300Y         S1      
327UV_P2V5_COMP     U8009 -1          A01X+055574Y+044416X0240Y0420R180 S1      
327UV_P2V5_COMP     U8010 -1          A01X+056582Y+045876X0240Y0420R090 S1      
327m0602            C8017 -1   M      A01X+050150Y+042642X0198Y0197R090 S1      
327m0602            R8113 -2   M      A01X+050150Y+042258X0198Y0197R090 S1      
327m0602            VIA   -    M      A01X+051160Y+044574X0300Y         S1      
327m0602            U8007 -1          A01X+049574Y+042266X0240Y0420R180 S1      
327m0602            U8008 -1          A01X+051918Y+044574X0240Y0420R270 S1      
317m0603            VIA   -    M      A01X+006363Y+158748X0200Y    R270 S2      
017m0603            VIA   -    M      A18X+006363Y+158748X0260Y    R270 S2      
017m0603                  -    MD0100PA00X+006363Y+158748                       
327m0603            R6858 -2          A18X+005535Y+158998X0198Y0197R180 S2      
327m0603            R657  -1          A01X+006363Y+159032X0198Y0197R090 S1      
317m0604            VIA   -    M      A01X+005863Y+158748X0200Y    R270 S2      
017m0604            VIA   -    M      A18X+005863Y+158748X0260Y    R270 S2      
017m0604                  -    MD0100PA00X+005863Y+158748                       
327m0604            R6859 -2          A18X+005535Y+158598X0198Y0197R180 S2      
327m0604            R658  -1          A01X+005863Y+159032X0198Y0197R090 S1      
327m0605            R646  -1          A01X+174046Y+169204X0198Y0197R270 S1      
327m0605            R6856 -2          A01X+165361Y+145541X0198Y0197R090 S1      
317m0605            VIA   -    M      A01X+168906Y+145150X0200Y         S2      
017m0605            VIA   -    M      A18X+168906Y+145150X0260Y         S2      
017m0605                  -    MD0100PA00X+168906Y+145150                       
317m0605            VIA   -    MD0100PA00X+170609Y+169157X0200Y    R090 S0      
327m0606            R647  -1          A01X+174546Y+169204X0198Y0197R270 S1      
327m0606            R6857 -2          A01X+165789Y+145544X0198Y0197R090 S1      
317m0606            VIA   -    M      A01X+168154Y+145152X0200Y         S2      
017m0606            VIA   -    M      A18X+168154Y+145152X0260Y         S2      
017m0606                  -    MD0100PA00X+168154Y+145152                       
317m0606            VIA   -    MD0100PA00X+170275Y+169618X0200Y    R090 S0      
327U124_VCC         R8017 -2          A01X+169300Y+022842X0198Y0197R270 S1      
317U124_VCC         VIA   -           A01X+168241Y+022834X0200Y         S2      
017U124_VCC         VIA   -           A18X+168241Y+022834X0260Y         S2      
017U124_VCC               -     D0100PA00X+168241Y+022834                       
327U124_VCC         R8018 -2          A01X+168900Y+022842X0198Y0197R270 S1      
327U124_VCC         C693  -1          A01X+168494Y+022834X0198Y0197R090 S1      
327U124_VCC         U124  -5          A01X+167826Y+022834X0220Y0530R270 S1      
317TP_J45_A1        J45   -A1   D0402PA00X+093878Y+171489X0657Y0657R270 S3      
327TP_CHASI         R4809 -1          A18X+054861Y+005166X0198Y0197R270 S2      
327TP_CHASI         J41   -A54        A01X+054861Y+005354X0150Y0570R180 S1      
317TP_CHASI         VIA   -    M      A01X+054861Y+004808X0200Y         S2      
017TP_CHASI         VIA   -    M      A18X+054861Y+004808X0260Y         S2      
017TP_CHASI               -    MD0100PA00X+054861Y+004808                       
327m0607            PR8000-2          A01X+080258Y+133000X0198Y0197     S1      
327m0607            PC128 -1          A01X+080650Y+133008X0198Y0197R270 S1      
327m0608            PR8002-2          A01X+026387Y+058788X0198Y0197R270 S1      
327m0608            PC19  -1          A01X+026392Y+058400X0198Y0197R180 S1      
327m0609            PR8001-2          A01X+130911Y+056577X0198Y0197R180 S1      
327m0609            PC209 -1          A01X+130519Y+056570X0198Y0197R090 S1      
327m0610            PC6526-2          A01X+089539Y+116291X0198Y0197R090 S1      
327m0610            PL6502-1          A01X+090165Y+117524X1300Y1692R090 S1      
327m0610            PU6501-20         A01X+091231Y+115379X0120Y0790     S1      
327m0611            PR6801-1          A01X+090247Y+115983X0198Y0197R180 S1      
327m0611            PU6501-1          A01X+090582Y+115536X0354Y0118     S1      
327m0612            PR8003-2          A01X+057557Y+030424X0198Y0197R090 S1      
327m0612            PC641 -1          A01X+057554Y+030763X0198Y0197R090 S1      
327m0613            PR8004-2          A01X+048854Y+029510X0198Y0197R090 S1      
327m0613            PC6017-1          A01X+048854Y+029863X0198Y0197R090 S1      
327m0614            PC6904-1          A01X+090850Y+113140X0400Y0500     S1      
327m0614            PC6905-1          A01X+091470Y+113020X0400Y0500R180 S1      
327m0614            PC6903-1          A01X+090850Y+112460X0400Y0500     S1      
327m0614            PC6524-1          A01X+090962Y+116117X0198Y0197R180 S1      
327m0614            PU6501-21         A01X+090995Y+115379X0120Y0790     S1      
327m0614            PU6501-10         A01X+090995Y+114355X0120Y0790     S1      
327m0614            PC6522-1          A01X+091470Y+112320X0400Y0500R180 S1      
327m0614            PC6803-1          A01X+091470Y+110920X0400Y0500R180 S1      
327m0614            PC6523-1          A01X+090850Y+111098X0400Y0500     S1      
327m0614            PC6521-1          A01X+091470Y+111620X0400Y0500R180 S1      
327m0614            PC6520-1          A01X+090850Y+111779X0400Y0500     S1      
327m0614            PC6801-1          A01X+089736Y+109281X0630Y1380R090 S1      
327m0614            PL6503-2          A01X+089467Y+106853X0420Y0990     S1      
327m0615            PC6818-1          A18X+011222Y+158131X0400Y0500R090 S2      
327m0615            PC6638-1          A01X+007467Y+155936X0400Y0500     S1      
317m0615            VIA   -    MD0100PA00X+008409Y+157028X0200Y    R090 S0      
317m0615            VIA   -    MD0100PA00X+008147Y+157028X0200Y    R090 S0      
317m0615            VIA   -    MD0100PA00X+007852Y+156789X0200Y    R090 S0      
317m0615            VIA   -    MD0100PA00X+007852Y+157039X0200Y    R090 S0      
317m0615            VIA   -    MD0100PA00X+010856Y+157746X0200Y    R090 S0      
317m0615            VIA   -    MD0100PA00X+010856Y+157466X0200Y    R090 S0      
327m0615            PC473 -1          A01X+011625Y+158031X0630Y1190R090 S1      
327m0615            PC6619-1          A01X+008015Y+157519X0630Y1190R270 S1      
327m0615            PC6616-1          A18X+007452Y+157169X0400Y0500R180 S2      
327m0615            PC6617-1          A18X+007452Y+156479X0400Y0500R180 S2      
327m0615            PC6819-1          A18X+007444Y+157856X0400Y0500R180 S2      
327m0615            PC6618-1          A18X+007452Y+155789X0400Y0500R180 S2      
327m0615            PC6636-1          A18X+010489Y+153357X0400Y0500R270 S2      
327m0615            PC6635-1          A18X+011283Y+153363X0400Y0500R270 S2      
327m0615            PC6614-1          A18X+007840Y+153417X0400Y0500R270 S2      
327m0615            PC6615-1          A18X+007048Y+153417X0400Y0500R270 S2      
327m0615            VIA   -           A01X+009299Y+156048X0300Y    R270 S1      
317m0615            VIA   -    MD0100PA00X+008110Y+158031X0200Y         S0      
317m0615            VIA   -    MD0100PA00X+008360Y+158031X0200Y         S0      
317m0615            VIA   -    MD0100PA00X+009749Y+157670X0200Y         S0      
317m0615            VIA   -    MD0100PA00X+009999Y+157670X0200Y         S0      
317m0615            VIA   -    MD0100PA00X+009999Y+157420X0200Y         S0      
317m0615            VIA   -    MD0100PA00X+009749Y+157420X0200Y         S0      
317m0615            VIA   -    MD0100PA00X+009479Y+157670X0200Y         S0      
317m0615            VIA   -    MD0100PA00X+009479Y+157420X0200Y         S0      
327m0615            PL6510-1   M      A01X+009748Y+157785X0420Y0990R090 S1      
317m0615            VIA   -    MD0100PA00X+007840Y+158031X0200Y         S0      
317m0615            VIA   -    MD0100PA00X+007852Y+156514X0200Y    R090 S0      
327m0615            PC6639-1          A01X+011835Y+155764X0400Y0500R180 S1      
327m0615            PC6637-1          A01X+011830Y+156455X0400Y0500R180 S1      
317m0615            VIA   -    MD0100PA00X+011242Y+155818X0200Y    R090 S0      
317m0615            VIA   -    MD0100PA00X+011234Y+156252X0200Y    R090 S0      
317m0615            VIA   -    MD0100PA00X+011234Y+156502X0200Y    R090 S0      
327m0615            PC6633-1          A01X+010770Y+155407X0198Y0197R180 S1      
327m0615            VIA   -           A01X+010720Y+155811X0300Y    R270 S1      
317m0615            VIA   -    MD0100PA00X+007852Y+156264X0200Y    R090 S0      
317m0615            VIA   -    MD0100PA00X+007837Y+155892X0200Y    R090 S0      
317m0615            VIA   -    MD0100PA00X+007837Y+155642X0200Y    R090 S0      
317m0615            VIA   -    MD0100PA00X+011461Y+154554X0200Y    R090 S0      
317m0615            VIA   -    MD0100PA00X+011190Y+154554X0200Y    R090 S0      
317m0615            VIA   -    MD0100PA00X+011242Y+155568X0200Y    R090 S0      
317m0615            VIA   -    MD0100PA00X+011120Y+154257X0200Y    R090 S0      
327m0615            PU6512-30         A01X+010906Y+154234X0090Y0240     S1      
317m0615            VIA   -    MD0100PA00X+007810Y+154244X0200Y    R090 S0      
317m0615            VIA   -    MD0100PA00X+007880Y+154567X0200Y    R090 S0      
317m0615            VIA   -    MD0100PA00X+007540Y+154237X0200Y    R090 S0      
317m0615            VIA   -    MD0100PA00X+007580Y+154567X0200Y    R090 S0      
317m0615            VIA   -    MD0100PA00X+007792Y+153824X0200Y    R090 S0      
327m0615            PC6613-1          A01X+007862Y+154937X0198Y0197     S1      
327m0615            PU6511-30         A01X+007332Y+154234X0090Y0240     S1      
317m0615            VIA   -    MD0100PA00X+011310Y+153735X0200Y    R090 S0      
317m0615            VIA   -    MD0100PA00X+011403Y+154242X0200Y    R090 S0      
327m0615            PC6634-1          A01X+011507Y+153280X0198Y0197R270 S1      
317m0615            VIA   -    MD0100PA00X+011066Y+153895X0180Y    R180 S0      
317m0615            VIA   -    MD0100PA00X+010833Y+153895X0180Y    R180 S0      
317m0615            VIA   -    MD0100PA00X+010590Y+153895X0180Y    R180 S0      
317m0615            VIA   -    MD0100PA00X+010347Y+153895X0180Y    R180 S0      
327m0615            PU6512-25_2M      A01X+010705Y+153596X0810Y0910R270 S1      
327m0615            PC6612-1          A01X+007932Y+153310X0198Y0197R270 S1      
317m0615            VIA   -    MD0100PA00X+007016Y+153895X0180Y    R180 S0      
317m0615            VIA   -    MD0100PA00X+006772Y+153895X0180Y    R180 S0      
317m0615            VIA   -    MD0100PA00X+007258Y+153895X0180Y    R180 S0      
317m0615            VIA   -    MD0100PA00X+007491Y+153895X0180Y    R180 S0      
327m0615            PU6511-25_2M      A01X+007131Y+153596X0810Y0910R270 S1      
327m0616            PC6810-1          A01X+179709Y+162155X0630Y1190R090 S1      
327m0616            PC6561-1          A01X+176247Y+162165X0630Y1190R270 S1      
327m0616            PC6582-1          A01X+180101Y+160582X0400Y0500R180 S1      
327m0616            VIA   -           A01X+178522Y+160547X0300Y    R270 S1      
327m0616            VIA   -           A01X+177556Y+160462X0300Y    R270 S1      
327m0616            PC6559-1          A01X+176428Y+160495X0400Y0500     S1      
327m0616            PC6581-1          A01X+180101Y+159832X0400Y0500R180 S1      
327m0616            VIA   -           A01X+179348Y+159872X0300Y    R270 S1      
327m0616            PC6578-1          A01X+179498Y+158710X0198Y0197R180 S1      
327m0616            PC6558-1          A01X+176428Y+159755X0400Y0500     S1      
327m0616            VIA   -           A01X+180098Y+158338X0300Y    R270 S1      
327m0616            PU6504-30         A01X+179634Y+157538X0090Y0240     S1      
327m0616            PU6503-30         A01X+176060Y+157538X0090Y0240     S1      
327m0616            PC6555-1          A01X+176590Y+158240X0198Y0197     S1      
327m0616            PC6577-1          A01X+180235Y+156584X0198Y0197R270 S1      
327m0616            PC6554-1          A01X+176661Y+156614X0198Y0197R270 S1      
317m0616            VIA   -    MD0100PA00X+179712Y+159659X0200Y    R090 S0      
317m0616            VIA   -    MD0100PA00X+179704Y+159981X0200Y    R090 S0      
327m0616            PC6583-1          A18X+180101Y+160582X0400Y0500     S2      
327m0616            PC6817-1          A18X+180101Y+159832X0400Y0500     S2      
327m0616            PC6816-1          A18X+176428Y+160495X0400Y0500R180 S2      
327m0616            PC6560-1          A18X+176428Y+159755X0400Y0500R180 S2      
327m0616            PC6580-1          A18X+180058Y+156670X0400Y0500R270 S2      
327m0616            PC6579-1          A18X+179218Y+156670X0400Y0500R270 S2      
327m0616            PC6556-1          A18X+175690Y+156670X0400Y0500R270 S2      
327m0616            PC6557-1          A18X+176531Y+156670X0400Y0500R270 S2      
327m0616            PL6504-1   M      A01X+177998Y+161886X0420Y0990R090 S1      
317m0616            VIA   -    MD0100PA00X+179898Y+161655X0200Y    R270 S0      
317m0616            VIA   -    MD0100PA00X+178265Y+161773X0200Y    R090 S0      
317m0616            VIA   -    MD0100PA00X+178265Y+161503X0200Y    R090 S0      
317m0616            VIA   -    MD0100PA00X+179548Y+161655X0200Y    R270 S0      
317m0616            VIA   -    MD0100PA00X+179198Y+161655X0200Y    R270 S0      
317m0616            VIA   -    MD0100PA00X+177745Y+161773X0200Y    R090 S0      
317m0616            VIA   -    MD0100PA00X+178015Y+161773X0200Y    R090 S0      
317m0616            VIA   -    MD0100PA00X+177745Y+161503X0200Y    R090 S0      
317m0616            VIA   -    MD0100PA00X+178015Y+161503X0200Y    R090 S0      
317m0616            VIA   -    MD0100PA00X+176721Y+161645X0200Y    R090 S0      
317m0616            VIA   -    MD0100PA00X+176021Y+161645X0200Y    R090 S0      
317m0616            VIA   -    MD0100PA00X+176371Y+161645X0200Y    R090 S0      
317m0616            VIA   -    MD0100PA00X+176803Y+160315X0200Y    R090 S0      
317m0616            VIA   -    MD0100PA00X+176818Y+160655X0200Y    R090 S0      
317m0616            VIA   -    MD0100PA00X+179708Y+160366X0200Y    R090 S0      
317m0616            VIA   -    MD0100PA00X+179714Y+160701X0200Y    R090 S0      
317m0616            VIA   -    MD0100PA00X+176810Y+159592X0200Y    R090 S0      
317m0616            VIA   -    MD0100PA00X+176803Y+159925X0200Y    R090 S0      
317m0616            VIA   -    MD0100PA00X+180188Y+157890X0200Y    R090 S0      
317m0616            VIA   -    MD0100PA00X+180048Y+157230X0200Y    R090 S0      
317m0616            VIA   -    MD0100PA00X+180148Y+157560X0200Y    R090 S0      
317m0616            VIA   -    MD0100PA00X+179888Y+157890X0200Y    R090 S0      
317m0616            VIA   -    MD0100PA00X+179848Y+157560X0200Y    R090 S0      
317m0616            VIA   -    MD0100PA00X+179794Y+157198X0180Y    R180 S0      
317m0616            VIA   -    MD0100PA00X+179561Y+157198X0180Y    R180 S0      
317m0616            VIA   -    MD0100PA00X+179075Y+157198X0180Y    R180 S0      
317m0616            VIA   -    MD0100PA00X+179318Y+157198X0180Y    R180 S0      
327m0616            PU6504-25_2M      A01X+179433Y+156900X0810Y0910R270 S1      
317m0616            VIA   -    MD0100PA00X+176308Y+157870X0200Y    R090 S0      
317m0616            VIA   -    MD0100PA00X+176608Y+157870X0200Y    R090 S0      
317m0616            VIA   -    MD0100PA00X+176268Y+157540X0200Y    R090 S0      
317m0616            VIA   -    MD0100PA00X+176568Y+157540X0200Y    R090 S0      
317m0616            VIA   -    MD0100PA00X+176468Y+157210X0200Y    R090 S0      
317m0616            VIA   -    MD0100PA00X+175987Y+157198X0180Y    R180 S0      
317m0616            VIA   -    MD0100PA00X+176220Y+157198X0180Y    R180 S0      
317m0616            VIA   -    MD0100PA00X+175501Y+157198X0180Y    R180 S0      
317m0616            VIA   -    MD0100PA00X+175744Y+157198X0180Y    R180 S0      
327m0616            PU6503-25_2M      A01X+175859Y+156900X0810Y0910R270 S1      
327m0617            PC6641-1          A01X+008748Y+151934X0198Y0197R180 S1      
327m0617            PU6512-10_1       A01X+010095Y+151950X0240Y1700R090 S1      
327m0617            PL6512-1          A01X+009970Y+151176X0790Y1660R270 S1      
327m0618            PC6622-1          A01X+005174Y+151934X0198Y0197R180 S1      
327m0618            PU6511-10_1       A01X+006520Y+151950X0240Y1700R090 S1      
327m0618            PL6511-1          A01X+007112Y+151176X0790Y1660R270 S1      
327m0619            PC6640-2          A01X+010851Y+154692X0198Y0197R270 S1      
327m0619            PU6512-32         A01X+010552Y+154234X0090Y0240     S1      
327m0620            PC6621-2          A01X+007277Y+154722X0198Y0197R270 S1      
327m0620            PU6511-32         A01X+006977Y+154234X0090Y0240     S1      
327m0621            PC6640-1          A01X+010851Y+155007X0198Y0197R270 S1      
327m0621            PR6629-2          A01X+010451Y+155007X0198Y0197R090 S1      
327m0622            PR6629-1          A01X+010451Y+154692X0198Y0197R090 S1      
327m0622            PU6512-33         A01X+010374Y+154234X0090Y0240     S1      
327m0623            PC6621-1          A01X+007277Y+155037X0198Y0197R270 S1      
327m0623            PR6623-2          A01X+006877Y+155037X0198Y0197R090 S1      
327m0624            PR6623-1          A01X+006877Y+154722X0198Y0197R090 S1      
327m0624            PU6511-33         A01X+006800Y+154234X0090Y0240     S1      
327m0625            PC6585-2          A01X+177161Y+155237X0198Y0197R180 S1      
327m0625            PR6563-1          A01X+177169Y+155630X0198Y0197R090 S1      
327m0626            PC6585-1          A01X+177476Y+155237X0198Y0197R180 S1      
327m0626            PU6504-10_1       A01X+178823Y+155254X0240Y1700R090 S1      
327m0626            PL6506-1          A01X+178698Y+154479X0790Y1660R270 S1      
327m0627            PC6564-2          A01X+173587Y+155237X0198Y0197R180 S1      
327m0627            PR6555-1          A01X+173594Y+155630X0198Y0197R090 S1      
327m0628            PC6564-1          A01X+173902Y+155237X0198Y0197R180 S1      
327m0628            PU6503-10_1       A01X+175249Y+155254X0240Y1700R090 S1      
327m0628            PL6505-1          A01X+175840Y+154479X0790Y1660R270 S1      
327m0629            PC6584-2          A01X+179579Y+157996X0198Y0197R270 S1      
327m0629            PU6504-32         A01X+179280Y+157538X0090Y0240     S1      
327m0630            PC6563-2          A01X+176005Y+158026X0198Y0197R270 S1      
327m0630            PU6503-32         A01X+175706Y+157538X0090Y0240     S1      
327m0631            PC6584-1          A01X+179579Y+158311X0198Y0197R270 S1      
327m0631            PR6562-2          A01X+179179Y+158311X0198Y0197R090 S1      
327m0632            PR6562-1          A01X+179179Y+157996X0198Y0197R090 S1      
327m0632            PU6504-33         A01X+179103Y+157538X0090Y0240     S1      
327m0633            PC6563-1          A01X+176005Y+158341X0198Y0197R270 S1      
327m0633            PR6554-2          A01X+175605Y+158341X0198Y0197R090 S1      
327m0634            PR6554-1          A01X+175605Y+158026X0198Y0197R090 S1      
327m0634            PU6503-33         A01X+175528Y+157538X0090Y0240     S1      
327m0635            PR8012-2          A01X+009908Y+142150X0198Y0197     S1      
327m0635            PU34  -21         A01X+010868Y+142956X0070Y0260R270 S1      
327m0636            PR8011-2          A01X+009908Y+141700X0198Y0197     S1      
327m0636            PU34  -22         A01X+010868Y+142799X0070Y0260R270 S1      
327m0637            PR8008-2          A01X+120008Y+141000X0198Y0197     S1      
317m0637            VIA   -    M      A01X+120286Y+141245X0200Y         S2      
017m0637            VIA   -    M      A18X+120286Y+141245X0260Y         S2      
017m0637                  -    MD0100PA00X+120286Y+141245                       
327m0637            PU12  -21         A01X+120968Y+141606X0070Y0260R270 S1      
317m0638            VIA   -    M      A01X+120255Y+140745X0200Y         S2      
017m0638            VIA   -    M      A18X+120255Y+140745X0260Y         S2      
017m0638                  -    MD0100PA00X+120255Y+140745                       
327m0638            PR8007-2          A01X+120008Y+140550X0198Y0197     S1      
327m0638            PU12  -22         A01X+120968Y+141449X0070Y0260R270 S1      
327m0639            PR8010-2          A18X+034858Y+057850X0198Y0197R180 S2      
327m0639            PU25  -21         A18X+036534Y+057385X0070Y0260R270 S2      
327m0640            PR8009-2          A18X+034858Y+058250X0198Y0197R180 S2      
327m0640            PU25  -22         A18X+036534Y+057543X0070Y0260R270 S2      
327m0641            PR8006-2          A18X+146983Y+056898X0198Y0197R180 S2      
327m0641            VIA   -    M      A18X+147359Y+056745X0260Y    R180 S2      
327m0641            PU42  -21         A18X+147844Y+056441X0070Y0260R270 S2      
327m0642            PR8005-2          A18X+146983Y+057298X0198Y0197R180 S2      
327m0642            VIA   -    M      A18X+147323Y+057244X0260Y    R180 S2      
327m0642            PU42  -22         A18X+147844Y+056599X0070Y0260R270 S2      
327SPI_CPU0_R1_D3   R8005 -2          A01X+104242Y+053800X0198Y0197R180 S1      
327SPI_CPU0_R1_D3   VIA   -    M      A01X+103805Y+054426X0300Y         S1      
327SPI_CPU0_R1_D3   U54   -2          A01X+103008Y+054507X0070Y0280R270 S1      
327SPI_CPU0_R1_D2   VIA   -    M      A01X+103833Y+055110X0300Y         S1      
327SPI_CPU0_R1_D2   R8006 -2          A01X+104176Y+055364X0198Y0197R180 S1      
327SPI_CPU0_R1_D2   U54   -3          A01X+103008Y+054665X0070Y0280R270 S1      
327SPI_CPU0_R1_D1   R8008 -2          A01X+103000Y+055742X0198Y0197R270 S1      
317SPI_CPU0_R1_D1   VIA   -    M      A01X+103000Y+055450X0200Y         S2      
017SPI_CPU0_R1_D1   VIA   -    M      A18X+103000Y+055450X0260Y         S2      
017SPI_CPU0_R1_D1         -    MD0100PA00X+103000Y+055450                       
327SPI_CPU0_R1_D1   U54   -5          A01X+103008Y+054980X0070Y0280R270 S1      
327SPI_CPU0_R1_D0   R8007 -2          A01X+103550Y+055742X0198Y0197R270 S1      
327SPI_CPU0_R1_D0   VIA   -    M      A01X+103425Y+055398X0300Y         S1      
327SPI_CPU0_R1_D0   U54   -4          A01X+103008Y+054822X0070Y0280R270 S1      
327m0643            U41   -7          A18X+066219Y+167227X0100Y0210R180 S2      
317m0643            VIA   -    MD0100PA00X+066153Y+167486X0200Y         S0      
327m0643            R810  -2          A01X+066344Y+164250X0120Y0150R270 S1      
327m0643            R698  -1          A01X+066300Y+164915X0120Y0150R090 S1      
317m0643            VIA   -    M      A01X+066343Y+164578X0300Y         S1      
017m0643            VIA   -    M      A18X+066343Y+164578X0200Y         S1      
017m0643                  -    MD0100PA00X+066343Y+164578                       
327m0644            U41   -8          A18X+066416Y+167227X0100Y0210R180 S2      
317m0644            VIA   -    MD0100PA00X+066416Y+167484X0200Y         S0      
327m0644            R812  -2          A01X+066673Y+164250X0120Y0150R270 S1      
327m0644            R697  -1          A01X+066798Y+164901X0120Y0150R090 S1      
317m0644            VIA   -    M      A01X+066918Y+164663X0200Y         S2      
017m0644            VIA   -    M      A18X+066918Y+164663X0260Y         S2      
017m0644                  -    MD0100PA00X+066918Y+164663                       
327m0645            VIA   -    M      A18X+043998Y+159933X0260Y         S2      
317m0645            VIA   -    MD0100PA00X+044146Y+159602X0200Y         S0      
317m0645            VIA   -    MD0080PA00X+044171Y+153790X0160Y         S0      
327m0645            U6017 -FJ3        A01X+044363Y+153634X0100Y0130R090 S1      
327m0645            R696  -2          A18X+044234Y+160781X0120Y0150R270 S2      
327m0646            VIA   -    M      A18X+044587Y+159616X0260Y         S2      
317m0646            VIA   -    MD0100PA00X+044359Y+159388X0200Y         S0      
317m0646            VIA   -    MD0080PA00X+044171Y+153570X0160Y         S0      
327m0646            U6017 -FF5        A01X+044568Y+153516X0120Y         S1      
327m0646            R695  -2          A18X+044557Y+160768X0120Y0150R270 S2      
317m0647            VIA   -    M      A01X+066039Y+165448X0200Y         S2      
017m0647            VIA   -    M      A18X+066039Y+165448X0260Y         S2      
017m0647                  -    MD0100PA00X+066039Y+165448                       
327m0647            R698  -2          A01X+066300Y+165125X0120Y0150R270 S1      
327m0647            U21   -5          A01X+066297Y+165855X0350Y0500R180 S1      
317m0648            VIA   -    M      A01X+066797Y+165440X0200Y         S2      
017m0648            VIA   -    M      A18X+066797Y+165440X0260Y         S2      
017m0648                  -    MD0100PA00X+066797Y+165440                       
327m0648            R697  -2          A01X+066798Y+165111X0120Y0150R270 S1      
327m0648            U21   -6          A01X+066797Y+165855X0350Y0500R180 S1      
327m0649            R826  -2          A18X+064609Y+165322X0120Y0150R270 S2      
327m0649            U43   -7          A18X+063285Y+164470X0100Y0210R090 S2      
317m0649            VIA   -    M      A01X+063980Y+164665X0200Y         S2      
017m0649            VIA   -    M      A18X+063980Y+164665X0260Y         S2      
017m0649                  -    MD0100PA00X+063980Y+164665                       
327m0649            R694  -1          A01X+063980Y+164875X0120Y0150R090 S1      
327m0650            R827  -2          A18X+064922Y+165322X0120Y0150R270 S2      
327m0650            U43   -8          A18X+063285Y+164274X0100Y0210R090 S2      
317m0650            VIA   -    M      A01X+064490Y+164649X0200Y         S2      
017m0650            VIA   -    M      A18X+064490Y+164649X0260Y         S2      
017m0650                  -    MD0100PA00X+064490Y+164649                       
327m0650            R693  -1          A01X+064455Y+164875X0120Y0150R090 S1      
327m0651            R692  -2          A18X+064340Y+162174X0120Y0150R270 S2      
317m0651            VIA   -    MD0080PA00X+056977Y+153790X0160Y         S0      
317m0651            VIA   -    MD0100PA00X+064930Y+162318X0200Y         S0      
327m0651            VIA   -    M      A18X+064652Y+162182X0260Y         S2      
327m0651            U6016 -FJ3        A01X+057169Y+153634X0100Y0130R090 S1      
327m0652            R691  -2          A18X+064358Y+162705X0120Y0150R270 S2      
317m0652            VIA   -    MD0080PA00X+056977Y+153570X0160Y         S0      
327m0652            VIA   -    M      A18X+064663Y+162699X0260Y         S2      
317m0652            VIA   -    MD0100PA00X+064915Y+162573X0200Y         S0      
327m0652            U6016 -FF5        A01X+057374Y+153516X0120Y         S1      
327m0653            R694  -2          A01X+063980Y+165085X0120Y0150R270 S1      
317m0653            VIA   -    M      A01X+063722Y+165413X0200Y         S2      
017m0653            VIA   -    M      A18X+063722Y+165413X0260Y         S2      
017m0653                  -    MD0100PA00X+063722Y+165413                       
327m0653            U20   -5          A01X+063928Y+165833X0350Y0500R180 S1      
327m0654            R693  -2          A01X+064455Y+165085X0120Y0150R270 S1      
317m0654            VIA   -    M      A01X+064272Y+165394X0200Y         S2      
017m0654            VIA   -    M      A18X+064272Y+165394X0260Y         S2      
017m0654                  -    MD0100PA00X+064272Y+165394                       
327m0654            U20   -6          A01X+064428Y+165833X0350Y0500R180 S1      
327m0655            U42   -7          A01X+045177Y+158112X0100Y0210R270 S1      
317m0655            VIA   -    M      A01X+042708Y+158162X0200Y         S2      
017m0655            VIA   -    M      A18X+042708Y+158162X0260Y         S2      
017m0655                  -    MD0100PA00X+042708Y+158162                       
327m0655            R6735 -2          A01X+042685Y+155920X0120Y0150R270 S1      
327m0655            R690  -1          A01X+042660Y+156207X0120Y0150R090 S1      
317m0655            VIA   -    MD0100PA00X+042462Y+156009X0200Y         S0      
327m0656            R6734 -2          A01X+042996Y+155925X0120Y0150R270 S1      
327m0656            R689  -1          A01X+043000Y+156207X0120Y0150R090 S1      
317m0656            VIA   -    MD0100PA00X+043205Y+156064X0200Y    R180 S0      
327m0656            U42   -8          A01X+045177Y+157915X0100Y0210R270 S1      
317m0656            VIA   -    M      A01X+043344Y+158170X0200Y         S2      
017m0656            VIA   -    M      A18X+043344Y+158170X0260Y         S2      
017m0656                  -    MD0100PA00X+043344Y+158170                       
327m0657            R671  -2          A01X+041132Y+155315X0120Y0150R090 S1      
317m0657            VIA   -    MD0080PA00X+030560Y+153790X0160Y         S0      
317m0657            VIA   -    M      A01X+040890Y+155364X0200Y         S2      
017m0657            VIA   -    M      A18X+040890Y+155364X0260Y         S2      
017m0657                  -    MD0100PA00X+040890Y+155364                       
327m0657            U6015 -FJ3        A01X+030752Y+153634X0100Y0130R090 S1      
327m0658            R670  -2          A01X+041599Y+155731X0120Y0150     S1      
317m0658            VIA   -    MD0080PA00X+030560Y+153570X0160Y         S0      
317m0658            VIA   -    M      A01X+041354Y+155665X0200Y    R180 S2      
017m0658            VIA   -    M      A18X+041354Y+155665X0260Y    R180 S2      
017m0658                  -    MD0100PA00X+041354Y+155665                       
327m0658            U6015 -FF5        A01X+030956Y+153516X0120Y         S1      
317m0659            VIA   -    M      A01X+042449Y+156540X0200Y         S2      
017m0659            VIA   -    M      A18X+042449Y+156540X0260Y         S2      
017m0659                  -    MD0100PA00X+042449Y+156540                       
327m0659            U19   -5          A01X+042537Y+156980X0350Y0500R180 S1      
327m0659            R690  -2          A01X+042660Y+156417X0120Y0150R270 S1      
317m0660            VIA   -    M      A01X+043192Y+156579X0200Y         S2      
017m0660            VIA   -    M      A18X+043192Y+156579X0260Y         S2      
017m0660                  -    MD0100PA00X+043192Y+156579                       
327m0660            U19   -6          A01X+043037Y+156980X0350Y0500R180 S1      
327m0660            R689  -2          A01X+043000Y+156417X0120Y0150R270 S1      
327m0661            R6707 -2          A01X+040298Y+155498X0120Y0150R270 S1      
327m0661            U45   -7          A01X+038532Y+158324X0100Y0210R090 S1      
317m0661            VIA   -    M      A01X+038878Y+158180X0200Y         S2      
017m0661            VIA   -    M      A18X+038878Y+158180X0260Y         S2      
017m0661                  -    MD0100PA00X+038878Y+158180                       
327m0661            R673  -1          A01X+040420Y+156075X0120Y0150R090 S1      
317m0661            VIA   -    MD0100PA00X+040291Y+155801X0200Y         S0      
327m0662            R6706 -2          A01X+040609Y+155494X0120Y0150R270 S1      
327m0662            U45   -8          A01X+038532Y+158520X0100Y0210R090 S1      
317m0662            VIA   -    MD0100PA00X+038844Y+158590X0200Y         S0      
327m0662            R672  -1          A01X+040760Y+156075X0120Y0150R090 S1      
317m0662            VIA   -    M      A01X+040576Y+155790X0200Y         S2      
017m0662            VIA   -    M      A18X+040576Y+155790X0260Y         S2      
017m0662                  -    MD0100PA00X+040576Y+155790                       
327m0663            R675  -2          A01X+016774Y+149434X0120Y0150R180 S1      
317m0663            VIA   -    M      A01X+017207Y+149555X0200Y         S2      
017m0663            VIA   -    M      A18X+017207Y+149555X0260Y         S2      
017m0663                  -    MD0100PA00X+017207Y+149555                       
317m0663            VIA   -    MD0080PA00X+017753Y+153790X0160Y         S0      
327m0663            U6014 -FJ3        A01X+017946Y+153634X0100Y0130R090 S1      
327m0664            R674  -2          A01X+016785Y+149101X0120Y0150R180 S1      
327m0664            U6014 -FF5        A01X+018150Y+153516X0120Y         S1      
317m0664            VIA   -    MD0080PA00X+017753Y+153570X0160Y         S0      
317m0664            VIA   -    M      A01X+017218Y+149021X0200Y         S2      
017m0664            VIA   -    M      A18X+017218Y+149021X0260Y         S2      
017m0664                  -    MD0100PA00X+017218Y+149021                       
317m0665            VIA   -    M      A01X+040125Y+156442X0200Y         S2      
017m0665            VIA   -    M      A18X+040125Y+156442X0260Y         S2      
017m0665                  -    MD0100PA00X+040125Y+156442                       
327m0665            R673  -2          A01X+040420Y+156285X0120Y0150R270 S1      
327m0665            U12   -5          A01X+040038Y+156980X0350Y0500R180 S1      
317m0666            VIA   -    M      A01X+040720Y+156499X0200Y         S2      
017m0666            VIA   -    M      A18X+040720Y+156499X0260Y         S2      
017m0666                  -    MD0100PA00X+040720Y+156499                       
327m0666            U12   -6          A01X+040538Y+156980X0350Y0500R180 S1      
327m0666            R672  -2          A01X+040760Y+156285X0120Y0150R270 S1      
327m0667            R838  -2          A18X+144139Y+166544X0120Y0150     S2      
327m0667            R688  -1   M      A18X+144423Y+166762X0120Y0150R180 S2      
317m0667            VIA   -    M      A01X+143808Y+166999X0200Y         S2      
017m0667            VIA   -    M      A18X+143808Y+166999X0260Y         S2      
017m0667                  -    MD0100PA00X+143808Y+166999                       
327m0667            U46   -7          A01X+147198Y+167688X0100Y0210     S1      
317m0667            VIA   -    MD0100PA00X+146959Y+167334X0200Y         S0      
327m0668            R839  -2          A18X+145098Y+167523X0120Y0150R270 S2      
327m0668            R687  -1   M      A18X+144909Y+167076X0120Y0150R180 S2      
317m0668            VIA   -    M      A01X+143932Y+167508X0200Y         S2      
017m0668            VIA   -    M      A18X+143932Y+167508X0260Y         S2      
017m0668                  -    MD0100PA00X+143932Y+167508                       
327m0668            U46   -8          A01X+147394Y+167688X0100Y0210     S1      
317m0668            VIA   -    MD0100PA00X+146810Y+167082X0200Y         S0      
317m0669            VIA   -    MD0080PA00X+144958Y+157090X0160Y         S0      
327m0669            R686  -2          A01X+143909Y+168266X0120Y0150     S1      
317m0669            VIA   -    M      A01X+143316Y+165198X0200Y         S2      
017m0669            VIA   -    M      A18X+143316Y+165198X0260Y         S2      
017m0669                  -    MD0100PA00X+143316Y+165198                       
327m0669            U6013 -FJ3        A01X+145150Y+156934X0100Y0130R090 S1      
317m0670            VIA   -    MD0080PA00X+144958Y+156870X0160Y         S0      
327m0670            R684  -2          A01X+143909Y+168616X0120Y0150     S1      
317m0670            VIA   -    M      A01X+143362Y+165933X0200Y         S2      
017m0670            VIA   -    M      A18X+143362Y+165933X0260Y         S2      
017m0670                  -    MD0100PA00X+143362Y+165933                       
327m0670            U6013 -FF5        A01X+145355Y+156816X0120Y         S1      
327m0671            R688  -2          A18X+144633Y+166762X0120Y0150     S2      
327m0671            VIA   -    M      A18X+144955Y+166592X0260Y         S2      
327m0671            U17   -5          A18X+146211Y+166385X0350Y0500R090 S2      
327m0672            R687  -2          A18X+145119Y+167076X0120Y0150     S2      
327m0672            VIA   -    M      A18X+145470Y+167127X0260Y         S2      
327m0672            U17   -6          A18X+146211Y+166885X0350Y0500R090 S2      
327m0673            R683  -1          A01X+165115Y+166737X0120Y0150R090 S1      
317m0673            VIA   -    M      A01X+165170Y+166504X0200Y         S2      
017m0673            VIA   -    M      A18X+165170Y+166504X0260Y         S2      
017m0673                  -    MD0100PA00X+165170Y+166504                       
327m0673            U47   -7          A18X+165852Y+167920X0100Y0210R270 S2      
327m0673            R840  -2   M      A18X+165117Y+168031X0120Y0150     S2      
327m0674            VIA   -    M      A18X+164534Y+166772X0260Y         S2      
327m0674            R682  -1          A01X+165614Y+166724X0120Y0150R090 S1      
317m0674            VIA   -    MD0100PA00X+165685Y+166495X0200Y         S0      
327m0674            U47   -8          A18X+165852Y+168116X0100Y0210R270 S2      
327m0674            R841  -2   M      A18X+165121Y+168344X0120Y0150     S2      
327m0675            VIA   -    M      A18X+165712Y+166190X0260Y         S2      
327m0675            R681  -2          A18X+166020Y+166256X0120Y0150R180 S2      
317m0675            VIA   -    MD0100PA00X+165618Y+165922X0200Y         S0      
317m0675            VIA   -    MD0080PA00X+157764Y+157090X0160Y         S0      
327m0675            U6012 -FJ3        A01X+157957Y+156934X0100Y0130R090 S1      
327m0676            VIA   -    M      A18X+165338Y+165785X0260Y         S2      
327m0676            R680  -2          A18X+165631Y+165565X0120Y0150R180 S2      
317m0676            VIA   -    MD0100PA00X+165393Y+166064X0200Y         S0      
317m0676            VIA   -    MD0080PA00X+157764Y+156870X0160Y         S0      
327m0676            U6012 -FF5        A01X+158161Y+156816X0120Y         S1      
327m0677            R683  -2          A01X+165115Y+166947X0120Y0150R270 S1      
317m0677            VIA   -    M      A01X+165110Y+167183X0200Y         S2      
017m0677            VIA   -    M      A18X+165110Y+167183X0260Y         S2      
017m0677                  -    MD0100PA00X+165110Y+167183                       
327m0677            U16   -5          A01X+165110Y+167593X0350Y0500R180 S1      
327m0678            R682  -2          A01X+165614Y+166934X0120Y0150R270 S1      
317m0678            VIA   -    M      A01X+165610Y+167172X0200Y         S2      
017m0678            VIA   -    M      A18X+165610Y+167172X0260Y         S2      
017m0678                  -    MD0100PA00X+165610Y+167172                       
327m0678            U16   -6          A01X+165610Y+167593X0350Y0500R180 S1      
327m0679            R679  -1          A01X+114669Y+156828X0120Y0150R090 S1      
317m0679            VIA   -    M      A01X+114781Y+156282X0200Y         S2      
017m0679            VIA   -    M      A18X+114781Y+156282X0260Y         S2      
017m0679                  -    MD0100PA00X+114781Y+156282                       
327m0679            U48   -7          A01X+114622Y+155855X0100Y0210R180 S1      
327m0679            R836  -2   M      A01X+114663Y+156532X0120Y0150     S1      
317m0680            VIA   -    M      A01X+114264Y+156279X0200Y         S2      
017m0680            VIA   -    M      A18X+114264Y+156279X0260Y         S2      
017m0680                  -    MD0100PA00X+114264Y+156279                       
327m0680            R678  -1          A01X+114296Y+156829X0120Y0150R090 S1      
327m0680            U48   -8          A01X+114425Y+155855X0100Y0210R180 S1      
327m0680            R837  -2   M      A01X+114341Y+156531X0120Y0150R180 S1      
317m0681            VIA   -    M      A01X+130239Y+153043X0200Y         S2      
017m0681            VIA   -    M      A18X+130239Y+153043X0260Y         S2      
017m0681                  -    MD0100PA00X+130239Y+153043                       
327m0681            R677  -2          A01X+130393Y+152815X0120Y0150R180 S1      
327m0681            U6011 -FJ3        A01X+131539Y+156934X0100Y0130R090 S1      
317m0681            VIA   -    MD0080PA00X+131347Y+157090X0160Y         S0      
317m0682            VIA   -    M      A01X+130890Y+152551X0200Y         S2      
017m0682            VIA   -    M      A18X+130890Y+152551X0260Y         S2      
017m0682                  -    MD0100PA00X+130890Y+152551                       
327m0682            R676  -2          A01X+130393Y+152500X0120Y0150R180 S1      
327m0682            U6011 -FF5        A01X+131744Y+156816X0120Y         S1      
317m0682            VIA   -    MD0080PA00X+131347Y+156870X0160Y         S0      
327m0683            R679  -2          A01X+114669Y+157038X0120Y0150R270 S1      
327m0683            VIA   -    M      A01X+114809Y+157356X0300Y         S1      
327m0683            U15   -5          A01X+115354Y+157945X0350Y0500R270 S1      
327m0684            VIA   -    M      A01X+114192Y+157360X0300Y         S1      
327m0684            U15   -6          A01X+115354Y+158445X0350Y0500R270 S1      
327m0684            R678  -2          A01X+114296Y+157039X0120Y0150R270 S1      
327m0685            U49   -7          A18X+117293Y+167338X0100Y0210R270 S2      
327m0685            R834  -2   M      A18X+116405Y+167300X0120Y0150     S2      
317m0685            VIA   -    M      A01X+116581Y+165893X0200Y         S2      
017m0685            VIA   -    M      A18X+116581Y+165893X0260Y         S2      
017m0685                  -    MD0100PA00X+116581Y+165893                       
327m0685            R669  -1          A01X+116369Y+166105X0120Y0150R090 S1      
327m0686            R835  -2   M      A18X+116405Y+167850X0120Y0150     S2      
327m0686            U49   -8          A18X+117293Y+167535X0100Y0210R270 S2      
317m0686            VIA   -    M      A01X+115834Y+165851X0200Y         S2      
017m0686            VIA   -    M      A18X+115834Y+165851X0260Y         S2      
017m0686                  -    MD0100PA00X+115834Y+165851                       
327m0686            R668  -1          A01X+115969Y+166105X0120Y0150R090 S1      
317m0687            VIA   -    MD0080PA00X+118541Y+157090X0160Y         S0      
327m0687            R667  -2          A18X+118762Y+167519X0120Y0150     S2      
317m0687            VIA   -    M      A01X+119083Y+167571X0200Y         S2      
017m0687            VIA   -    M      A18X+119083Y+167571X0260Y         S2      
017m0687                  -    MD0100PA00X+119083Y+167571                       
327m0687            U6010 -FJ3        A01X+118733Y+156934X0100Y0130R090 S1      
317m0688            VIA   -    MD0080PA00X+118541Y+156870X0160Y         S0      
327m0688            R666  -2          A18X+118758Y+167913X0120Y0150     S2      
317m0688            VIA   -    M      A01X+118926Y+168255X0200Y         S2      
017m0688            VIA   -    M      A18X+118926Y+168255X0260Y         S2      
017m0688                  -    MD0100PA00X+118926Y+168255                       
327m0688            U6010 -FF5        A01X+118938Y+156816X0120Y         S1      
317m0689            VIA   -    M      A01X+116910Y+166628X0200Y         S2      
017m0689            VIA   -    M      A18X+116910Y+166628X0260Y         S2      
017m0689                  -    MD0100PA00X+116910Y+166628                       
327m0689            U11   -5          A01X+116919Y+166216X0350Y0500R180 S1      
327m0689            R669  -2          A01X+116369Y+166315X0120Y0150R270 S1      
317m0690            VIA   -    M      A01X+115969Y+166543X0200Y         S2      
017m0690            VIA   -    M      A18X+115969Y+166543X0260Y         S2      
017m0690                  -    MD0100PA00X+115969Y+166543                       
327m0690            R668  -2          A01X+115969Y+166315X0120Y0150R270 S1      
327m0690            U11   -6          A01X+117419Y+166216X0350Y0500R180 S1      
327m0691            VIA   -    M      A18X+089622Y+114064X0260Y         S2      
327m0691            R644  -2          A18X+089278Y+114506X0198Y0197R180 S2      
327m0691            R645  -1   M      A18X+089971Y+113963X0198Y0197R090 S2      
327m0691            PU6501-9          A01X+090562Y+114198X0120Y0320R090 S1      
317m0691            VIA   -    MD0100PA00X+090248Y+114056X0200Y         S0      
327m0692            C107  -1   M      A01X+007681Y+159948X0198Y0197R270 S1      
327m0692            R656  -2          A18X+006687Y+160436X0198Y0197R270 S2      
327m0692            R661  -2          A01X+007266Y+159347X0198Y0197R090 S1      
327m0692            R6861 -2          A01X+008101Y+159948X0198Y0197R090 S1      
317m0692            VIA   -    M      A01X+007238Y+160436X0200Y    R270 S2      
017m0692            VIA   -    M      A18X+007238Y+160436X0260Y    R270 S2      
017m0692                  -    MD0100PA00X+007238Y+160436                       
327m0692            PU6510-12         A01X+006922Y+160989X0070Y0240R090 S1      
327m0693            R661  -1          A01X+007266Y+159032X0198Y0197R090 S1      
317m0693            VIA   -    MD0100PA00X+007266Y+158736X0200Y    R270 S0      
327m0693            R6853 -1          A01X+069628Y+054386X0198Y0197R270 S1      
317m0693            VIA   -    MD0100PA00X+069628Y+054653X0200Y         S0      
317m0693            VIA   -    MD0100PA00X+028772Y+054850X0200Y         S0      
317m0693            VIA   -    M      A01X+014917Y+161676X0200Y         S2      
017m0693            VIA   -    M      A18X+014917Y+161676X0260Y         S2      
017m0693                  -    MD0100PA00X+014917Y+161676                       
327m0694            C101  -1   M      A01X+173004Y+168146X0198Y0197R180 S1      
327m0694            R643  -2          A18X+173000Y+168146X0198Y0197R180 S2      
327m0694            R650  -2   M      A01X+172944Y+168709X0198Y0197R270 S1      
327m0694            R6860 -2          A01X+172542Y+168708X0198Y0197R270 S1      
327m0694            PU6502-12         A01X+173988Y+167447X0070Y0240R270 S1      
317m0694            VIA   -    M      A01X+173476Y+168046X0200Y    R090 S2      
017m0694            VIA   -    M      A18X+173476Y+168046X0260Y    R090 S2      
017m0694                  -    MD0100PA00X+173476Y+168046                       
317m0695            VIA   -    MD0100PA00X+085230Y+033749X0200Y         S0      
327m0695            R650  -1          A01X+172944Y+169024X0198Y0197R270 S1      
317m0695            VIA   -    M      A01X+173194Y+169016X0200Y    R090 S2      
017m0695            VIA   -    M      A18X+173194Y+169016X0260Y    R090 S2      
017m0695                  -    MD0100PA00X+173194Y+169016                       
317m0695            VIA   -    MD0100PA00X+080534Y+057806X0200Y         S0      
327m0695            R6852 -1          A18X+068792Y+049700X0198Y0197R180 S2      
317m0695            VIA   -    MD0100PA00X+068957Y+057287X0200Y         S0      
327m0696            R8090 -2          A01X+077892Y+036750X0198Y0197R180 S1      
317m0696            VIA   -    M      A01X+075293Y+036102X0200Y         S2      
017m0696            VIA   -    M      A18X+075293Y+036102X0260Y         S2      
017m0696                  -    MD0100PA00X+075293Y+036102                       
317m0696            VIA   -    MD0100PA00X+074611Y+043411X0180Y    R090 S0      
327m0696            U18   -T6         A01X+074458Y+043564X0160Y    R090 S1      
327m0697            R8089 -2          A01X+078208Y+036400X0198Y0197     S1      
327m0697            R8091 -2          A01X+078208Y+037100X0198Y0197     S1      
327m0697            R8090 -1   M      A01X+078208Y+036750X0198Y0197R180 S1      
317m0697            VIA   -    M      A01X+078450Y+036750X0200Y         S2      
017m0697            VIA   -    M      A18X+078450Y+036750X0260Y         S2      
017m0697                  -    MD0100PA00X+078450Y+036750                       
327m0697            D8006 -1          A01X+078928Y+036600X0260Y0540R270 S1      
327m0698            R8084 -2          A01X+078942Y+040300X0198Y0197R180 S1      
317m0698            VIA   -    M      A01X+078657Y+040346X0200Y         S2      
017m0698            VIA   -    M      A18X+078657Y+040346X0260Y         S2      
017m0698                  -    MD0100PA00X+078657Y+040346                       
317m0698            VIA   -    MD0100PA00X+077016Y+041026X0200Y         S0      
327m0698            U18   -Y1         A01X+075717Y+041989X0160Y    R090 S1      
317m0698            VIA   -    MD0100PA00X+075871Y+041836X0180Y    R090 S0      
327m0699            R8083 -2   M      A01X+080542Y+039250X0198Y0197R180 S1      
327m0699            R8085 -2          A01X+080158Y+039250X0198Y0197     S1      
327m0699            R8084 -1          A01X+079258Y+040300X0198Y0197R180 S1      
317m0699            VIA   -    M      A01X+080542Y+039550X0200Y         S2      
017m0699            VIA   -    M      A18X+080542Y+039550X0260Y         S2      
017m0699                  -    MD0100PA00X+080542Y+039550                       
327m0699            D8004 -1   M      A01X+080178Y+039950X0260Y0540R270 S1      
327m0700            R8087 -2          A01X+059708Y+049350X0198Y0197     S1      
317m0700            VIA   -    M      A01X+059750Y+048350X0200Y         S2      
017m0700            VIA   -    M      A18X+059750Y+048350X0260Y         S2      
017m0700                  -    MD0100PA00X+059750Y+048350                       
327m0700            U18   -R6         A01X+074143Y+043564X0160Y    R090 S1      
317m0700            VIA   -    MD0100PA00X+074296Y+043411X0180Y    R090 S0      
317m0700            VIA   -    MD0100PA00X+066463Y+044995X0180Y    R090 S0      
327m0701            R8086 -2          A01X+058008Y+047550X0198Y0197     S1      
327m0701            R8088 -2   M      A01X+058008Y+047950X0198Y0197     S1      
327m0701            R8087 -1          A01X+059392Y+049350X0198Y0197     S1      
327m0701            VIA   -    M      A01X+058416Y+047966X0300Y         S1      
327m0701            D8005 -1   M      A01X+059372Y+048600X0260Y0540R090 S1      
327m0702            R8081 -2          A01X+078942Y+041150X0198Y0197R180 S1      
317m0702            VIA   -    M      A01X+078326Y+040934X0200Y         S2      
017m0702            VIA   -    M      A18X+078326Y+040934X0260Y         S2      
017m0702                  -    MD0100PA00X+078326Y+040934                       
317m0702            VIA   -    MD0100PA00X+075556Y+041836X0180Y    R090 S0      
327m0702            U18   -W1         A01X+075402Y+041989X0160Y    R090 S1      
327m0703            R8080 -2          A01X+081992Y+040950X0198Y0197R180 S1      
327m0703            R8081 -1          A01X+079258Y+041150X0198Y0197R180 S1      
327m0703            R8082 -2   M      A01X+079258Y+040750X0198Y0197     S1      
327m0703            VIA   -    M      A01X+081675Y+041237X0300Y         S1      
327m0703            D8003 -1   M      A01X+080078Y+040950X0260Y0540R270 S1      
327m0704            R8000 -2          A01X+078942Y+039900X0198Y0197R180 S1      
317m0704            VIA   -    M      A01X+078450Y+039635X0200Y         S2      
017m0704            VIA   -    M      A18X+078450Y+039635X0260Y         S2      
017m0704                  -    MD0100PA00X+078450Y+039635                       
327m0704            U18   -AB4        A01X+076347Y+042934X0160Y    R090 S1      
317m0704            VIA   -    MD0100PA00X+076501Y+042781X0180Y    R090 S0      
317m0704            VIA   -    MD0100PA00X+077323Y+040915X0200Y         S0      
327m0705            VIA   -    M      A01X+072776Y+163654X0300Y         S1      
327m0705            R8004 -2          A01X+072872Y+163010X0198Y0197R090 S1      
327m0705            U181  -8          A01X+072958Y+164333X0160Y0540     S1      
327m0706            R8000 -1          A01X+079258Y+039900X0198Y0197R180 S1      
317m0706            VIA   -    MD0100PA00X+069194Y+144163X0200Y         S0      
327m0706            VIA   -    M      A01X+085200Y+040800X0300Y         S1      
327m0706            C8000 -1          A18X+038579Y+167398X0198Y0197     S2      
327m0706            R8003 -2   M      A18X+038579Y+167787X0198Y0197R180 S2      
317m0706            VIA   -    MD0100PA00X+038507Y+168350X0200Y         S0      
327m0706            Q8000 -3          A18X+039419Y+167534X0170Y0200R090 S2      
317m0706            VIA   -    MD0100PA00X+070240Y+165047X0200Y         S0      
327m0706            R8004 -1          A01X+072872Y+162694X0198Y0197R090 S1      
317m0706            VIA   -    MD0100PA00X+072732Y+162370X0200Y         S0      
317m0706            VIA   -    MD0100PA00X+067373Y+155677X0200Y         S0      
327PRSNT_SWB        R8002 -2          A18X+040992Y+167250X0198Y0197     S2      
327PRSNT_SWB        VIA   -    M      A18X+040650Y+167250X0260Y         S2      
327PRSNT_SWB        Q8000 -6          A18X+040167Y+167022X0170Y0200R090 S2      
327PRSNT_SWB        Q8000 -5   M      A18X+040167Y+167278X0170Y0200R090 S2      
327m0707            R8099 -1   M      A01X+088058Y+032600X0198Y0197R180 S1      
327m0707            R8098 -2          A01X+087150Y+031958X0198Y0197R090 S1      
327m0707            R8100 -1          A01X+088492Y+032600X0198Y0197     S1      
317m0707            VIA   -    M      A01X+087110Y+032300X0200Y         S2      
017m0707            VIA   -    M      A18X+087110Y+032300X0260Y         S2      
017m0707                  -    MD0100PA00X+087110Y+032300                       
327m0707            U8003 -2   M      A01X+087726Y+032003X0260Y0380R180 S1      
327m0708            U10   -2          A01X+042321Y+162208X0100Y0220R180 S1      
327m0708            C84   -1          A01X+042258Y+163400X0198Y0197R180 S1      
327m0708            C83   -1          A01X+042258Y+163900X0198Y0197R180 S1      
327m0708            VIA   -    M      A01X+042500Y+162690X0300Y         S1      
327m0708            R555  -2          A01X+042410Y+164450X0280Y0320R090 S1      
327m0709            C68   -1          A01X+044192Y+161870X0198Y0197     S1      
327m0709            C82   -1          A01X+044192Y+162270X0198Y0197     S1      
327m0709            R586  -2          A01X+044190Y+162750X0280Y0320R270 S1      
327m0709            VIA   -           A01X+043650Y+161870X0300Y         S1      
327m0709            U10   -31         A01X+042764Y+161765X0100Y0220R090 S1      
327m0710            VIA   -           A18X+042517Y+160236X0260Y         S2      
327m0710            VIA   -           A18X+040167Y+160264X0260Y         S2      
327m0710            C58   -1          A18X+043005Y+160837X0198Y0197     S2      
327m0710            C90   -1          A01X+039718Y+160702X0198Y0197R180 S1      
327m0710            C98   -1          A18X+040993Y+161540X0198Y0197R180 S2      
327m0710            C99   -1          A18X+040990Y+161016X0198Y0197R180 S2      
327m0710            C75   -1          A18X+042740Y+161517X0198Y0197     S2      
327m0710            C28   -1          A01X+039718Y+161102X0198Y0197R180 S1      
317m0710            VIA   -    MD0100PA00X+043050Y+161371X0200Y         S0      
327m0710            U10   -29         A01X+042764Y+161371X0100Y0220R090 S1      
327m0710            U10   -12         A01X+040894Y+161371X0100Y0220R270 S1      
317m0710            VIA   -    MD0100PA00X+040634Y+161385X0200Y         S0      
327m0710            U10   -25         A01X+042764Y+160584X0100Y0220R090 S1      
317m0710            VIA   -    MD0100PA00X+043050Y+160584X0200Y         S0      
317m0710            VIA   -    MD0100PA00X+041928Y+160072X0200Y         S0      
327m0710            U10   -21         A01X+041928Y+160338X0100Y0220     S1      
317m0710            VIA   -    MD0100PA00X+040670Y+160421X0200Y         S0      
327m0710            U10   -16         A01X+040894Y+160584X0100Y0220R270 S1      
317m0710            VIA   -    MD0100PA00X+039980Y+160638X0200Y         S0      
317m0710            VIA   -    MD0100PA00X+039945Y+161261X0200Y         S0      
327m0710            L2    -2          A01X+039918Y+161682X0440Y0540R180 S1      
327m0711            VIA   -           A01X+043428Y+164481X0300Y         S1      
327m0711            R555  -1          A01X+042990Y+164450X0280Y0320R090 S1      
327m0711            L1    -2          A01X+043426Y+163400X0440Y0540     S1      
327m0711            R586  -1          A01X+043610Y+162750X0280Y0320R270 S1      
327m0712            C77   -1   M      A01X+110500Y+167642X0198Y0197R090 S1      
327m0712            VIA   -    M      A01X+111094Y+165442X0300Y         S1      
327m0712            C78   -1          A18X+111514Y+164951X0198Y0197R180 S2      
327m0712            U314  -2          A01X+111617Y+165186X0100Y0220R270 S1      
317m0712            VIA   -    MD0100PA00X+111349Y+165186X0200Y         S0      
327m0712            R4475 -2          A01X+111000Y+167510X0280Y0320R180 S1      
327m0713            C76   -1   M      A01X+112030Y+167636X0198Y0197R090 S1      
327m0713            VIA   -    M      A01X+112030Y+167011X0300Y         S1      
327m0713            C2334 -1          A18X+111840Y+165705X0198Y0197R090 S2      
327m0713            U314  -31         A01X+112060Y+165629X0100Y0220R180 S1      
317m0713            VIA   -    MD0100PA00X+112060Y+165897X0200Y         S0      
327m0713            R4493 -2          A01X+111522Y+167508X0280Y0320R180 S1      
317m0714            VIA   -    MD0100PA00X+112439Y+165897X0200Y         S0      
317m0714            VIA   -    M      A01X+113298Y+163453X0200Y    R180 S2      
017m0714            VIA   -    M      A18X+113298Y+163453X0260Y    R180 S2      
017m0714                  -    MD0100PA00X+113298Y+163453                       
317m0714            VIA   -    MD0100PA00X+111714Y+163044X0200Y    R270 S0      
317m0714            VIA   -    MD0100PA00X+111429Y+163051X0200Y    R270 S0      
327m0714            L20   -2          A01X+110889Y+162757X0440Y0540R270 S1      
327m0714            C2328 -1          A01X+111539Y+162590X0198Y0197R270 S1      
327m0714            C80   -1          A18X+112950Y+163542X0198Y0197R270 S2      
327m0714            C2329 -1          A18X+113465Y+165662X0198Y0197R090 S2      
327m0714            C79   -1          A18X+113538Y+164978X0198Y0197     S2      
327m0714            C81   -1          A18X+112296Y+163723X0198Y0197R270 S2      
327m0714            C2339 -1          A18X+112323Y+165650X0198Y0197R090 S2      
327m0714            U314  -25         A01X+113241Y+165629X0100Y0220R180 S1      
317m0714            VIA   -    MD0100PA00X+113241Y+165897X0200Y         S0      
327m0714            U314  -29         A01X+112453Y+165629X0100Y0220R180 S1      
327m0714            U314  -21         A01X+113487Y+164792X0100Y0220R090 S1      
317m0714            VIA   -    MD0100PA00X+113754Y+164792X0200Y    R270 S0      
327m0714            U314  -16         A01X+113241Y+163759X0100Y0220     S1      
327m0714            U314  -12         A01X+112453Y+163759X0100Y0220     S1      
317m0714            VIA   -    MD0100PA00X+112453Y+163492X0200Y    R180 S0      
327m0715            VIA   -           A01X+111545Y+168501X0300Y         S1      
327m0715            L19   -2          A01X+111000Y+168926X0440Y0540R090 S1      
327m0715            R4493 -1          A01X+111522Y+168088X0280Y0320R180 S1      
327m0715            R4475 -1          A01X+111000Y+168090X0280Y0320R180 S1      
327m0716            PC6525-1          A01X+092245Y+115565X0198Y0197R270 S1      
327m0716            PR6521-2          A18X+090549Y+114147X0198Y0197R270 S2      
327m0716            PU6501-19         A01X+091664Y+115536X0120Y0320R270 S1      
317m0716            VIA   -    M      A01X+091978Y+115566X0200Y    R270 S2      
017m0716            VIA   -    M      A18X+091978Y+115566X0260Y    R270 S2      
017m0716                  -    MD0100PA00X+091978Y+115566                       
327m0717            PC6537-1          A01X+089760Y+114907X0198Y0197R180 S1      
327m0717            PU6501-5          A01X+090562Y+114867X0070Y0320R090 S1      
327m0718            PR6520-2          A18X+089757Y+114395X0198Y0197     S2      
327m0718            PU6501-4          A01X+090562Y+115024X0070Y0320R090 S1      
317m0718            VIA   -    M      A01X+090028Y+115077X0200Y         S2      
017m0718            VIA   -    M      A18X+090028Y+115077X0260Y         S2      
017m0718                  -    MD0100PA00X+090028Y+115077                       
327m0719            VIA   -    M      A01X+090024Y+114346X0160Y0041R034 S1      
327m0719            PC6534-1          A01X+088937Y+114150X0198Y0197R090 S1      
327m0719            PR6526-1   M      A01X+089744Y+114150X0198Y0197R090 S1      
327m0719            PR6524-1   M      A01X+089337Y+114150X0198Y0197R090 S1      
327m0719            PU6501-7          A01X+090562Y+114552X0070Y0320R090 S1      
327m0720            VIA   -    M      A18X+072972Y+074280X0260Y         S2      
317m0720            VIA   -    MD0100PA00X+070255Y+073581X0200Y         S0      
327m0720            C105  -1   M      A01X+089720Y+113784X0198Y0197R180 S1      
327m0720            PU6501-8          A01X+090562Y+114394X0070Y0320R090 S1      
317m0720            VIA   -    MD0100PA00X+088927Y+113447X0200Y         S0      
317m0720            VIA   -    MD0100PA00X+069484Y+067641X0200Y         S0      
327m0720            R6851 -1          A01X+066671Y+050490X0198Y0197     S1      
317m0720            VIA   -    MD0100PA00X+066474Y+050686X0200Y         S0      
327m0721            PR6522-1          A01X+089760Y+115350X0198Y0197R180 S1      
327m0721            PU6501-3          A01X+090562Y+115182X0070Y0320R090 S1      
327m0722            R8031 -1          A01X+074550Y+019942X0198Y0197R090 S1      
317m0722            VIA   -    MD0100PA00X+073550Y+014300X0200Y         S0      
317m0722            VIA   -    MD0100PA00X+068700Y+011950X0200Y         S0      
327m0722            PU299 -9          A01X+069171Y+011944X0100Y0320R180 S1      
327m0722            PR4007-1          A01X+068353Y+011987X0198Y0197R180 S1      
327m0722            VIA   -           A01X+067386Y+012120X0300Y         S1      
327m0723            R8030 -2          A01X+076050Y+010942X0198Y0197R270 S1      
327m0723            R8031 -2   M      A01X+074550Y+020258X0198Y0197R090 S1      
327m0723            R4013 -2          A01X+076019Y+010380X0198Y0197R090 S1      
317m0723            VIA   -    MD0100PA00X+076019Y+010650X0200Y         S0      
317m0723            VIA   -    MD0100PA00X+075474Y+018547X0200Y         S0      
327m0723            VIA   -    M      A01X+074650Y+020750X0300Y         S1      
327m0723            Q8001 -2          A01X+075100Y+021276X0170Y0200R180 S1      
327m0724            R8030 -1          A01X+076050Y+011258X0198Y0197R270 S1      
317m0724            VIA   -    M      A01X+075758Y+011258X0200Y         S2      
017m0724            VIA   -    M      A18X+075758Y+011258X0260Y         S2      
017m0724                  -    MD0100PA00X+075758Y+011258                       
327m0724            PU300 -C7         A01X+075291Y+009997X0090Y         S1      
327m0725            R8121 -2          A01X+057192Y+045450X0198Y0197R180 S1      
327m0725            C8021 -1   M      A01X+057192Y+046600X0198Y0197     S1      
327m0725            R8122 -1   M      A01X+057192Y+046200X0198Y0197     S1      
327m0725            R8123 -1          A01X+056208Y+047350X0198Y0197R180 S1      
327m0725            VIA   -    M      A01X+057192Y+045844X0300Y         S1      
327m0725            U8010 -3   M      A01X+056582Y+046624X0240Y0420R090 S1      
327m0726            C8018 -1   M      A01X+051850Y+043258X0198Y0197R270 S1      
327m0726            R8115 -1   M      A01X+052250Y+043258X0198Y0197R270 S1      
327m0726            R8114 -2   M      A01X+051200Y+043258X0198Y0197R090 S1      
327m0726            R8117 -1          A01X+052642Y+043250X0198Y0197     S1      
327m0726            VIA   -    M      A01X+051319Y+043688X0300Y         S1      
327m0726            U8008 -3          A01X+051918Y+043826X0240Y0420R270 S1      
327m0727            PR6631-1          A01X+008627Y+154487X0198Y0197R180 S1      
327m0727            PU6512-1          A01X+009150Y+153988X0090Y0240R090 S1      
327m0728            PR6626-1          A01X+005070Y+154429X0198Y0197R090 S1      
327m0728            PU6511-1          A01X+005576Y+153988X0090Y0240R090 S1      
327m0729            PC514 -1          A01X+004121Y+161290X0198Y0197R180 S1      
327m0729            PR6808-2          A18X+004817Y+162983X0198Y0197R090 S2      
327m0729            PR6821-1   M      A18X+005056Y+161270X0198Y0197R180 S2      
327m0729            PR885 -2   M      A18X+004824Y+162540X0198Y0197R180 S2      
327m0729            PU6510-37         A01X+005032Y+161304X0070Y0240R090 S1      
317m0729            VIA   -    MD0100PA00X+004683Y+161260X0200Y    R270 S0      
327m0730            PC819 -1   M      A01X+004121Y+160790X0198Y0197R180 S1      
327m0730            PR6813-1   M      A18X+004121Y+160340X0198Y0197     S2      
327m0730            PR6809-2          A18X+004121Y+159890X0198Y0197R180 S2      
327m0730            PU6510-38         A01X+005032Y+161147X0070Y0240R090 S1      
317m0730            VIA   -    M      A01X+004363Y+160690X0200Y    R270 S2      
017m0730            VIA   -    M      A18X+004363Y+160690X0260Y    R270 S2      
017m0730                  -    MD0100PA00X+004363Y+160690                       
327m0731            R665  -2          A01X+007906Y+161190X0198Y0197R180 S1      
327m0731            VIA   -    M      A01X+007423Y+161440X0300Y    R090 S1      
327m0731            PU6510-15         A01X+006922Y+161462X0070Y0240R090 S1      
327m0732            VIA   -    M      A18X+009332Y+154214X0260Y         S2      
327m0732            PC6645-1   M      A01X+008637Y+153760X0198Y0197R090 S1      
327m0732            PR6627-2   M      A18X+008700Y+153514X0198Y0197R270 S2      
327m0732            PU6512-35         A01X+010020Y+154234X0090Y0240     S1      
327m0732            PU6512-3          A01X+009150Y+153634X0090Y0240R090 S1      
317m0732            VIA   -    MD0100PA00X+008381Y+153730X0200Y         S0      
317m0732            VIA   -    MD0100PA00X+009982Y+154630X0200Y         S0      
327m0733            VIA   -    M      A18X+005785Y+154214X0260Y         S2      
327m0733            PC6610-1   M      A01X+005063Y+153710X0198Y0197R090 S1      
327m0733            PR6621-2   M      A18X+005125Y+153514X0198Y0197R270 S2      
327m0733            PU6511-35         A01X+006446Y+154234X0090Y0240     S1      
317m0733            VIA   -    MD0100PA00X+006428Y+154630X0200Y    R090 S0      
327m0733            PU6511-3          A01X+005576Y+153634X0090Y0240R090 S1      
317m0733            VIA   -    MD0100PA00X+004816Y+153630X0200Y         S0      
327m0734            PC6543-1   M      A01X+004121Y+160340X0198Y0197R180 S1      
327m0734            PC6544-1   M      A01X+004121Y+159890X0198Y0197R180 S1      
327m0734            PR6538-1          A01X+004121Y+159440X0198Y0197R180 S1      
327m0734            VIA   -    M      A01X+004512Y+160340X0300Y         S1      
327m0734            PU6510-39         A01X+005032Y+160989X0070Y0240R090 S1      
317m0735            VIA   -    M      A01X+004121Y+161990X0200Y    R180 S2      
017m0735            VIA   -    M      A18X+004121Y+161990X0260Y    R180 S2      
017m0735                  -    MD0100PA00X+004121Y+161990                       
327m0735            PU6510-35         A01X+005032Y+161619X0070Y0240R090 S1      
327m0735            PR6815-1          A18X+004121Y+162320X0198Y0197     S2      
327m0735            PC523 -1   M      A01X+004121Y+161740X0198Y0197R180 S1      
317m0735            VIA   -    MD0100PA00X+006160Y+154683X0200Y         S0      
317m0735            VIA   -    MD0100PA00X+009702Y+154633X0200Y         S0      
327m0735            PU6512-36         A01X+009843Y+154234X0090Y0240     S1      
327m0735            PU6511-36         A01X+006268Y+154234X0090Y0240     S1      
317m0736            VIA   -    M      A01X+005781Y+159806X0200Y    R180 S2      
017m0736            VIA   -    M      A18X+005781Y+159806X0260Y    R180 S2      
017m0736                  -    MD0100PA00X+005781Y+159806                       
317m0736            VIA   -    MD0100PA00X+010201Y+155024X0200Y         S0      
327m0736            PU6512-34         A01X+010197Y+154234X0090Y0240     S1      
327m0736            PU6510-7          A01X+006213Y+160596X0070Y0240     S1      
327m0737            PU6510-8          A01X+006370Y+160596X0070Y0240     S1      
317m0737            VIA   -    MD0100PA00X+006111Y+159815X0200Y    R180 S0      
317m0737            VIA   -    M      A01X+006623Y+154954X0200Y         S2      
017m0737            VIA   -    M      A18X+006623Y+154954X0260Y         S2      
017m0737                  -    MD0100PA00X+006623Y+154954                       
327m0737            PU6511-34         A01X+006623Y+154234X0090Y0240     S1      
327m0738            VIA   -    M      A01X+004215Y+154679X0300Y         S1      
327m0738            PC6644-1   M      A01X+008637Y+153375X0198Y0197R270 S1      
327m0738            PC6609-1   M      A01X+005063Y+153325X0198Y0197R270 S1      
327m0738            PR6627-1          A18X+008700Y+153199X0198Y0197R270 S2      
327m0738            PR6621-1          A18X+005125Y+153199X0198Y0197R270 S2      
327m0738            PU6511-4          A01X+005576Y+153456X0090Y0240R090 S1      
317m0738            VIA   -    MD0100PA00X+004838Y+153240X0200Y         S0      
317m0738            VIA   -    MD0100PA00X+008380Y+153375X0200Y         S0      
327m0738            PU6512-4          A01X+009150Y+153456X0090Y0240R090 S1      
327m0738            PR6619-2          A01X+004615Y+155050X0198Y0197R270 S1      
327m0738            PR6620-2   M      A01X+004215Y+155050X0198Y0197R270 S1      
327m0739            R658  -2          A01X+005863Y+159347X0198Y0197R090 S1      
327m0739            PU6510-9          A01X+006528Y+160596X0070Y0240     S1      
327m0740            R657  -2          A01X+006363Y+159347X0198Y0197R090 S1      
327m0740            PU6510-10         A01X+006685Y+160596X0070Y0240     S1      
327m0740            VIA   -    M      A01X+006685Y+159716X0300Y         S1      
327m0741            R660  -2          A01X+006813Y+159347X0198Y0197R090 S1      
327m0741            PU6510-11         A01X+006922Y+160832X0070Y0240R090 S1      
327m0741            VIA   -    M      A01X+007046Y+160066X0300Y         S1      
317m0742            VIA   -    M      A01X+009330Y+154914X0200Y         S2      
017m0742            VIA   -    M      A18X+009330Y+154914X0260Y         S2      
017m0742                  -    MD0100PA00X+009330Y+154914                       
327m0742            PR6628-1          A01X+009544Y+155280X0198Y0197     S1      
327m0742            PU6512-37         A01X+009666Y+154234X0090Y0240     S1      
327m0743            VIA   -    M      A01X+005904Y+154964X0300Y         S1      
327m0743            PR6622-1          A01X+006162Y+155287X0198Y0197     S1      
327m0743            PU6511-37         A01X+006091Y+154234X0090Y0240     S1      
317m0744            VIA   -    MD0100PA00X+009151Y+155230X0200Y         S0      
327m0744            PU6512-38         A01X+009488Y+154234X0090Y0240     S1      
317m0744            VIA   -    M      A01X+006463Y+163290X0200Y    R180 S2      
017m0744            VIA   -    M      A18X+006463Y+163290X0260Y    R180 S2      
017m0744                  -    MD0100PA00X+006463Y+163290                       
327m0744            PU6510-24         A01X+006213Y+162485X0070Y0240     S1      
317m0745            VIA   -    M      A01X+006413Y+162790X0200Y    R180 S2      
017m0745            VIA   -    M      A18X+006413Y+162790X0260Y    R180 S2      
017m0745                  -    MD0100PA00X+006413Y+162790                       
327m0745            PU6510-23         A01X+006370Y+162485X0070Y0240     S1      
317m0745            VIA   -    MD0100PA00X+005537Y+155135X0200Y         S0      
327m0745            PU6511-38         A01X+005914Y+154234X0090Y0240     S1      
327m0746            R662  -1          A01X+008261Y+160463X0198Y0197R090 S1      
317m0746            VIA   -    MD0100PA00X+014645Y+161488X0200Y         S0      
327m0746            R6855 -2          A01X+076870Y+054358X0198Y0197R090 S1      
317m0746            VIA   -    M      A01X+077346Y+056346X0200Y         S2      
017m0746            VIA   -    M      A18X+077346Y+056346X0260Y         S2      
017m0746                  -    MD0100PA00X+077346Y+056346                       
327m0747            PR6564-1          A01X+177355Y+157790X0198Y0197R180 S1      
327m0747            PU6504-1          A01X+177878Y+157292X0090Y0240R090 S1      
327m0748            PR6556-1          A01X+173798Y+157733X0198Y0197R090 S1      
327m0748            PU6503-1          A01X+174304Y+157292X0090Y0240R090 S1      
327m0749            PR6605-1          A01X+176831Y+167051X0198Y0197     S1      
327m0749            PC6601-1   M      A01X+176823Y+167406X0198Y0197     S1      
327m0749            PR6807-2          A18X+176093Y+165453X0198Y0197R270 S2      
327m0749            PR6604-2   M      A18X+176085Y+165896X0198Y0197     S2      
317m0749            VIA   -    MD0100PA00X+176226Y+167176X0200Y    R090 S0      
327m0749            PU6502-37         A01X+175878Y+167132X0070Y0240R270 S1      
327m0750            PC6602-1   M      A01X+176789Y+167817X0198Y0197     S1      
317m0750            VIA   -    M      A01X+176546Y+167746X0200Y    R090 S2      
017m0750            VIA   -    M      A18X+176546Y+167746X0260Y    R090 S2      
017m0750                  -    MD0100PA00X+176546Y+167746                       
327m0750            PU6502-38         A01X+175878Y+167289X0070Y0240R270 S1      
327m0750            PR6606-2   M      A18X+176869Y+167686X0198Y0197     S2      
327m0750            PR6607-1          A18X+176809Y+167296X0198Y0197R180 S2      
327m0751            R655  -2          A01X+173004Y+167246X0198Y0197     S1      
327m0751            PU6502-15         A01X+173988Y+166974X0070Y0240R270 S1      
327m0752            VIA   -    M      A18X+177678Y+157388X0260Y         S2      
317m0752            VIA   -    MD0100PA00X+178724Y+157941X0200Y         S0      
327m0752            PC6575-1   M      A01X+177366Y+157063X0198Y0197R090 S1      
327m0752            PR6560-2   M      A18X+177428Y+156818X0198Y0197R270 S2      
327m0752            PU6504-35         A01X+178748Y+157538X0090Y0240     S1      
327m0752            PU6504-3          A01X+177878Y+156937X0090Y0240R090 S1      
317m0752            VIA   -    MD0100PA00X+177109Y+157033X0200Y         S0      
317m0753            VIA   -    M      A01X+175156Y+157933X0200Y    R090 S2      
017m0753            VIA   -    M      A18X+175156Y+157933X0260Y    R090 S2      
017m0753                  -    MD0100PA00X+175156Y+157933                       
327m0753            PC6552-1   M      A01X+173791Y+157013X0198Y0197R090 S1      
327m0753            PR6552-2   M      A18X+174152Y+157466X0198Y0197R270 S2      
327m0753            PU6503-3          A01X+174304Y+156937X0090Y0240R090 S1      
317m0753            VIA   -    MD0100PA00X+173535Y+156983X0200Y         S0      
327m0753            PU6503-35         A01X+175174Y+157538X0090Y0240     S1      
327m0754            PC6603-1   M      A01X+176789Y+168170X0198Y0197     S1      
327m0754            PC6604-1   M      A01X+176789Y+168546X0198Y0197     S1      
327m0754            PR6608-1          A01X+176789Y+168996X0198Y0197     S1      
327m0754            PU6502-39         A01X+175878Y+167447X0070Y0240R270 S1      
327m0754            VIA   -    M      A01X+176316Y+167996X0300Y    R180 S1      
327m0755            PC6607-1   M      A01X+176835Y+166698X0198Y0197     S1      
317m0755            VIA   -    M      A01X+174678Y+158338X0200Y         S2      
017m0755            VIA   -    M      A18X+174678Y+158338X0260Y         S2      
017m0755                  -    MD0100PA00X+174678Y+158338                       
327m0755            PU6503-36         A01X+174997Y+157538X0090Y0240     S1      
327m0755            PU6504-36         A01X+178571Y+157538X0090Y0240     S1      
317m0755            VIA   -    MD0100PA00X+178460Y+157897X0200Y         S0      
327m0755            PR6814-1          A18X+176789Y+166146X0198Y0197R180 S2      
317m0755            VIA   -    M      A01X+176789Y+166446X0200Y    R090 S2      
017m0755            VIA   -    M      A18X+176789Y+166446X0260Y    R090 S2      
017m0755                  -    MD0100PA00X+176789Y+166446                       
327m0755            PU6502-35         A01X+175878Y+166817X0070Y0240R270 S1      
317m0756            VIA   -    M      A01X+175134Y+168614X0200Y         S2      
017m0756            VIA   -    M      A18X+175134Y+168614X0260Y         S2      
017m0756                  -    MD0100PA00X+175134Y+168614                       
327m0756            PU6502-7          A01X+174697Y+167840X0070Y0240R180 S1      
317m0756            VIA   -    MD0100PA00X+178929Y+158328X0200Y         S0      
327m0756            PU6504-34         A01X+178926Y+157538X0090Y0240     S1      
327m0757            PU6502-8          A01X+174539Y+167840X0070Y0240R180 S1      
317m0757            VIA   -    MD0100PA00X+174799Y+168622X0200Y         S0      
317m0757            VIA   -    MD0100PA00X+175351Y+158348X0200Y         S0      
327m0757            PU6503-34         A01X+175351Y+157538X0090Y0240     S1      
327m0758            VIA   -    M      A01X+173020Y+157928X0300Y         S1      
327m0758            PC6550-1   M      A01X+173791Y+156628X0198Y0197R270 S1      
327m0758            PC6551-1   M      A01X+177366Y+156678X0198Y0197R270 S1      
327m0758            PR6552-1          A18X+174152Y+157151X0198Y0197R270 S2      
327m0758            PR6551-2          A01X+172620Y+159602X0198Y0197R270 S1      
327m0758            PR6550-2   M      A01X+173020Y+159602X0198Y0197R270 S1      
327m0758            PR6560-1          A18X+177428Y+156503X0198Y0197R270 S2      
327m0758            PU6503-4          A01X+174304Y+156760X0090Y0240R090 S1      
317m0758            VIA   -    MD0100PA00X+173538Y+156628X0200Y         S0      
327m0758            PU6504-4          A01X+177878Y+156760X0090Y0240R090 S1      
317m0758            VIA   -    MD0100PA00X+177108Y+156678X0200Y         S0      
327m0759            R647  -2          A01X+174546Y+168889X0198Y0197R270 S1      
327m0759            PU6502-9          A01X+174382Y+167840X0070Y0240R180 S1      
327m0759            VIA   -    M      A01X+174546Y+168416X0300Y    R180 S1      
327m0760            R646  -2          A01X+174046Y+168889X0198Y0197R270 S1      
327m0760            PU6502-10         A01X+174224Y+167840X0070Y0240R180 S1      
327m0760            VIA   -    M      A01X+174046Y+168416X0300Y    R180 S1      
327m0761            R649  -2          A01X+173546Y+168889X0198Y0197R270 S1      
327m0761            PU6502-11         A01X+173988Y+167604X0070Y0240R270 S1      
327m0761            VIA   -    M      A01X+173546Y+168416X0300Y    R180 S1      
317m0762            VIA   -    M      A01X+178058Y+158218X0200Y         S2      
017m0762            VIA   -    M      A18X+178058Y+158218X0260Y         S2      
017m0762                  -    MD0100PA00X+178058Y+158218                       
327m0762            PR6561-1          A01X+178272Y+158583X0198Y0197     S1      
327m0762            PU6504-37         A01X+178394Y+157538X0090Y0240     S1      
327m0763            PR6553-1          A01X+174890Y+158590X0198Y0197     S1      
327m0763            PU6503-37         A01X+174820Y+157538X0090Y0240     S1      
327m0764            PU6502-24         A01X+174697Y+165951X0070Y0240R180 S1      
317m0764            VIA   -    M      A01X+174446Y+165123X0200Y    R090 S2      
017m0764            VIA   -    M      A18X+174446Y+165123X0260Y    R090 S2      
017m0764                  -    MD0100PA00X+174446Y+165123                       
327m0764            PU6504-38         A01X+178217Y+157538X0090Y0240     S1      
317m0764            VIA   -    MD0100PA00X+177879Y+158533X0200Y         S0      
327m0765            PU6503-38         A01X+174642Y+157538X0090Y0240     S1      
317m0765            VIA   -    MD0100PA00X+174608Y+158770X0200Y    R090 S0      
317m0765            VIA   -    M      A01X+174496Y+165646X0200Y    R090 S2      
017m0765            VIA   -    M      A18X+174496Y+165646X0260Y    R090 S2      
017m0765                  -    MD0100PA00X+174496Y+165646                       
327m0765            PU6502-23         A01X+174539Y+165951X0070Y0240R180 S1      
327m0766            R6854 -1          A18X+077708Y+044250X0198Y0197     S2      
317m0766            VIA   -    M      A01X+086054Y+044609X0200Y         S2      
017m0766            VIA   -    M      A18X+086054Y+044609X0260Y         S2      
017m0766                  -    MD0100PA00X+086054Y+044609                       
317m0766            VIA   -    MD0100PA00X+085016Y+033504X0200Y         S0      
327m0766            R651  -1          A01X+172084Y+167376X0198Y0197R090 S1      
317m0766            VIA   -    MD0100PA00X+172084Y+166850X0200Y         S0      
327m0767            C7032 -1          A01X+122295Y+161065X0950Y1110     S1      
327m0767            C7034 -1          A01X+121261Y+161227X0400Y0500R270 S1      
327m0767            C7033 -1          A01X+120576Y+161227X0400Y0500R270 S1      
327m0767            C7035 -1          A01X+130291Y+161166X0400Y0500R270 S1      
327m0767            C7036 -1          A01X+156698Y+161136X0400Y0500R270 S1      
327m0767            C7002 -1          A01X+156007Y+161124X0400Y0500R270 S1      
327m0767            C7001 -1          A01X+154990Y+161083X0950Y1110R180 S1      
327m0767            C7003 -1          A01X+129596Y+161165X0400Y0500R270 S1      
327m0767            C7000 -1          A01X+128573Y+161083X0950Y1110R180 S1      
327m0767            C1032 -1          A18X+150115Y+157221X0198Y0197R090 S2      
327m0767            C805  -1          A18X+162921Y+157221X0198Y0197R090 S2      
327m0767            C636  -1          A18X+136504Y+157221X0198Y0197R090 S2      
327m0767            C563  -1          A18X+123697Y+157221X0198Y0197R090 S2      
327m0767            C980  -1          A18X+163393Y+157306X0120Y0150R090 S2      
327m0767            VIA   -           A18X+162381Y+157974X0260Y         S2      
327m0767            C971  -1          A18X+161504Y+157221X0198Y0197R090 S2      
327m0767            C976  -1          A18X+161031Y+157221X0198Y0197R090 S2      
327m0767            C1016 -1          A18X+150587Y+157306X0120Y0150R090 S2      
327m0767            VIA   -           A18X+149575Y+157974X0260Y         S2      
327m0767            C1044 -1          A18X+148697Y+157221X0198Y0197R090 S2      
327m0767            C1038 -1          A18X+148225Y+157221X0198Y0197R090 S2      
327m0767            VIA   -           A18X+136912Y+157978X0260Y         S2      
327m0767            C655  -1          A18X+136976Y+157306X0120Y0150R090 S2      
327m0767            C646  -1          A18X+135086Y+157221X0198Y0197R090 S2      
327m0767            VIA   -           A18X+135019Y+157974X0260Y         S2      
327m0767            C651  -1          A18X+134614Y+157221X0198Y0197R090 S2      
327m0767            C528  -1          A18X+124170Y+157306X0120Y0150R090 S2      
327m0767            VIA   -           A18X+123158Y+157974X0260Y         S2      
327m0767            C569  -1          A18X+121808Y+157221X0198Y0197R090 S2      
327m0767            C574  -1          A18X+122280Y+157221X0198Y0197R090 S2      
317m0767            VIA   -    MD0100PA00X+119017Y+161542X0200Y    R090 S0      
327m0767            U6012 -BL17       A01X+163188Y+155914X0120Y         S1      
327m0767            U6012 -BL20       A01X+163188Y+155717X0120Y         S1      
327m0767            U6012 -CW17       A01X+161298Y+155914X0120Y         S1      
327m0767            U6012 -CW20       A01X+161298Y+155717X0120Y         S1      
327m0767            U6013 -BL17       A01X+150382Y+155914X0120Y         S1      
327m0767            U6013 -BL20       A01X+150382Y+155717X0120Y         S1      
327m0767            U6013 -CW17       A01X+148492Y+155914X0120Y         S1      
327m0767            U6013 -CW20       A01X+148492Y+155717X0120Y         S1      
327m0767            U6011 -BL17       A01X+136771Y+155914X0120Y         S1      
327m0767            U6011 -BL20       A01X+136771Y+155717X0120Y         S1      
327m0767            U6011 -CW17       A01X+134881Y+155914X0120Y         S1      
327m0767            U6011 -CW20       A01X+134881Y+155717X0120Y         S1      
327m0767            U6010 -BL17       A01X+123965Y+155914X0120Y         S1      
327m0767            U6010 -BL20       A01X+123965Y+155717X0120Y         S1      
327m0767            U6010 -CW17       A01X+122075Y+155914X0120Y         S1      
327m0767            U6010 -CW20       A01X+122075Y+155717X0120Y         S1      
317m0767            VIA   -    MD0100PA00X+174836Y+152925X0200Y         S0      
317m0767            VIA   -    MD0100PA00X+174836Y+152425X0200Y         S0      
317m0767            VIA   -    MD0100PA00X+174836Y+152675X0200Y         S0      
317m0767            VIA   -    MD0100PA00X+174831Y+151870X0200Y         S0      
317m0767            VIA   -    MD0100PA00X+174835Y+152122X0200Y         S0      
317m0767            VIA   -    MD0100PA00X+142462Y+156941X0200Y         S0      
317m0767            VIA   -    MD0100PA00X+142462Y+157191X0200Y         S0      
317m0767            VIA   -    MD0100PA00X+177078Y+151590X0200Y         S0      
317m0767            VIA   -    MD0100PA00X+177089Y+151847X0200Y         S0      
317m0767            VIA   -    MD0100PA00X+177089Y+152110X0200Y         S0      
317m0767            VIA   -    MD0100PA00X+177085Y+152660X0200Y         S0      
317m0767            VIA   -    MD0100PA00X+177085Y+152400X0200Y         S0      
317m0767            VIA   -    MD0100PA00X+176829Y+152110X0200Y         S0      
317m0767            VIA   -    MD0100PA00X+176829Y+151847X0200Y         S0      
317m0767            VIA   -    MD0100PA00X+176818Y+151590X0200Y         S0      
317m0767            VIA   -    MD0100PA00X+176833Y+152934X0200Y         S0      
317m0767            VIA   -    MD0100PA00X+176825Y+152400X0200Y         S0      
317m0767            VIA   -    MD0100PA00X+176825Y+152660X0200Y         S0      
317m0767            VIA   -    MD0100PA00X+177455Y+151863X0200Y         S0      
317m0767            VIA   -    MD0100PA00X+177455Y+151603X0200Y         S0      
317m0767            VIA   -    MD0100PA00X+177455Y+152123X0200Y         S0      
317m0767            VIA   -    MD0100PA00X+177458Y+152636X0200Y         S0      
317m0767            VIA   -    MD0100PA00X+177458Y+152386X0200Y         S0      
317m0767            VIA   -    MD0100PA00X+177715Y+152123X0200Y         S0      
317m0767            VIA   -    MD0100PA00X+177715Y+151603X0200Y         S0      
317m0767            VIA   -    MD0100PA00X+177715Y+151863X0200Y         S0      
317m0767            VIA   -    MD0100PA00X+177718Y+152386X0200Y         S0      
317m0767            VIA   -    MD0100PA00X+177718Y+152636X0200Y         S0      
317m0767            VIA   -    MD0100PA00X+176529Y+152110X0200Y         S0      
317m0767            VIA   -    MD0100PA00X+182365Y+152514X0200Y         S0      
317m0767            VIA   -    MD0100PA00X+174541Y+152453X0200Y    R090 S0      
317m0767            VIA   -    MD0100PA00X+174281Y+152453X0200Y    R090 S0      
327m0767            PC6587-1          A18X+174415Y+152858X0400Y0500R090 S2      
317m0767            VIA   -    MD0100PA00X+155606Y+157168X0200Y         S0      
317m0767            VIA   -    MD0100PA00X+155856Y+157168X0200Y         S0      
317m0767            VIA   -    MD0100PA00X+129189Y+157168X0200Y         S0      
317m0767            VIA   -    MD0100PA00X+129439Y+157168X0200Y         S0      
327m0767            C559  -1          A01X+119891Y+161295X0400Y0500R090 S1      
327m0767            R961  -1          A01X+118066Y+160549X0280Y0320R270 S1      
317m0767            VIA   -    MD0100PA00X+117784Y+160312X0200Y    R090 S0      
317m0767            VIA   -    MD0100PA00X+117284Y+160312X0200Y    R090 S0      
317m0767            VIA   -    MD0100PA00X+117534Y+160312X0200Y    R090 S0      
317m0767            VIA   -    MD0100PA00X+117034Y+160312X0200Y    R090 S0      
317m0767            VIA   -    MD0100PA00X+117304Y+159562X0200Y    R090 S0      
317m0767            VIA   -    MD0100PA00X+117554Y+159562X0200Y    R090 S0      
317m0767            VIA   -    MD0100PA00X+117804Y+159562X0200Y    R090 S0      
317m0767            VIA   -    MD0100PA00X+117054Y+159562X0200Y    R090 S0      
317m0767            VIA   -    MD0100PA00X+117054Y+159812X0200Y    R090 S0      
317m0767            VIA   -    MD0100PA00X+117304Y+159812X0200Y    R090 S0      
317m0767            VIA   -    MD0100PA00X+117554Y+159812X0200Y    R090 S0      
317m0767            VIA   -    MD0100PA00X+117804Y+159812X0200Y    R090 S0      
317m0767            VIA   -    MD0100PA00X+117054Y+160062X0200Y    R090 S0      
317m0767            VIA   -    MD0100PA00X+117304Y+160062X0200Y    R090 S0      
317m0767            VIA   -    MD0100PA00X+117554Y+160062X0200Y    R090 S0      
317m0767            VIA   -    MD0100PA00X+117804Y+160062X0200Y    R090 S0      
327m0767            L12   -1   M      A01X+117447Y+159938X0420Y0990R270 S1      
317m0767            VIA   -    MD0100PA00X+154659Y+157980X0200Y         S0      
317m0767            VIA   -    MD0100PA00X+154659Y+158230X0200Y         S0      
317m0767            VIA   -    MD0100PA00X+154909Y+158230X0200Y         S0      
317m0767            VIA   -    MD0100PA00X+154909Y+157980X0200Y         S0      
317m0767            VIA   -    MD0100PA00X+155909Y+157480X0200Y         S0      
317m0767            VIA   -    MD0100PA00X+155909Y+157730X0200Y         S0      
317m0767            VIA   -    MD0100PA00X+155659Y+157730X0200Y         S0      
317m0767            VIA   -    MD0100PA00X+155659Y+157480X0200Y         S0      
317m0767            VIA   -    MD0100PA00X+155659Y+157980X0200Y         S0      
317m0767            VIA   -    MD0100PA00X+155659Y+158230X0200Y         S0      
317m0767            VIA   -    MD0100PA00X+155159Y+157980X0200Y         S0      
317m0767            VIA   -    MD0100PA00X+155159Y+158230X0200Y         S0      
317m0767            VIA   -    MD0100PA00X+155409Y+157730X0200Y         S0      
317m0767            VIA   -    MD0100PA00X+155409Y+157980X0200Y         S0      
317m0767            VIA   -    MD0100PA00X+155409Y+157480X0200Y         S0      
327m0767            C801  -1   M      A18X+155733Y+157065X0400Y0500R270 S2      
327m0767            R1051 -1   M      A18X+155425Y+158120X0280Y0320R270 S2      
317m0767            VIA   -    MD0100PA00X+155409Y+158230X0200Y         S0      
327m0767            L21   -1   M      A01X+155286Y+157836X0420Y0990     S1      
317m0767            VIA   -    MD0100PA00X+142793Y+157060X0200Y         S0      
317m0767            VIA   -    MD0100PA00X+143043Y+157060X0200Y         S0      
317m0767            VIA   -    MD0100PA00X+142853Y+158230X0200Y         S0      
317m0767            VIA   -    MD0100PA00X+142853Y+157980X0200Y         S0      
317m0767            VIA   -    MD0100PA00X+142853Y+157730X0200Y         S0      
317m0767            VIA   -    MD0100PA00X+142853Y+157480X0200Y         S0      
317m0767            VIA   -    MD0100PA00X+142353Y+157730X0200Y         S0      
317m0767            VIA   -    MD0100PA00X+142353Y+157980X0200Y         S0      
317m0767            VIA   -    MD0100PA00X+142353Y+158230X0200Y         S0      
317m0767            VIA   -    MD0100PA00X+142603Y+157480X0200Y         S0      
317m0767            VIA   -    MD0100PA00X+142603Y+157730X0200Y         S0      
317m0767            VIA   -    MD0100PA00X+142603Y+157980X0200Y         S0      
317m0767            VIA   -    MD0100PA00X+142353Y+157480X0200Y         S0      
317m0767            VIA   -    MD0100PA00X+143103Y+157730X0200Y         S0      
317m0767            VIA   -    MD0100PA00X+143103Y+157480X0200Y         S0      
327m0767            C1028 -1   M      A18X+142927Y+157065X0400Y0500R270 S2      
327m0767            R1094 -1   M      A18X+142619Y+158120X0280Y0320R270 S2      
317m0767            VIA   -    MD0100PA00X+142603Y+158230X0200Y         S0      
327m0767            L23   -1   M      A01X+142480Y+157836X0420Y0990     S1      
317m0767            VIA   -    MD0100PA00X+128242Y+157980X0200Y         S0      
317m0767            VIA   -    MD0100PA00X+128242Y+158230X0200Y         S0      
317m0767            VIA   -    MD0100PA00X+128492Y+158230X0200Y         S0      
317m0767            VIA   -    MD0100PA00X+128492Y+157980X0200Y         S0      
317m0767            VIA   -    MD0100PA00X+129492Y+157480X0200Y         S0      
317m0767            VIA   -    MD0100PA00X+129492Y+157730X0200Y         S0      
317m0767            VIA   -    MD0100PA00X+129242Y+157730X0200Y         S0      
317m0767            VIA   -    MD0100PA00X+129242Y+157480X0200Y         S0      
317m0767            VIA   -    MD0100PA00X+129242Y+157980X0200Y         S0      
317m0767            VIA   -    MD0100PA00X+129242Y+158230X0200Y         S0      
317m0767            VIA   -    MD0100PA00X+128742Y+157980X0200Y         S0      
317m0767            VIA   -    MD0100PA00X+128742Y+158230X0200Y         S0      
317m0767            VIA   -    MD0100PA00X+128992Y+157730X0200Y         S0      
317m0767            VIA   -    MD0100PA00X+128992Y+157980X0200Y         S0      
317m0767            VIA   -    MD0100PA00X+128992Y+157480X0200Y         S0      
327m0767            C632  -1   M      A18X+129316Y+157065X0400Y0500R270 S2      
327m0767            R1010 -1   M      A18X+129008Y+158120X0280Y0320R270 S2      
317m0767            VIA   -    MD0100PA00X+128992Y+158230X0200Y         S0      
327m0767            L14   -1   M      A01X+128868Y+157836X0420Y0990     S1      
317m0767            VIA   -    MD0080PA00X+161081Y+155935X0160Y         S0      
317m0767            VIA   -    MD0080PA00X+161026Y+155695X0160Y         S0      
317m0767            VIA   -    MD0080PA00X+163443Y+155935X0160Y         S0      
317m0767            VIA   -    MD0080PA00X+163388Y+155695X0160Y         S0      
327m0767            C789  -1   M      A18X+163388Y+155675X0120Y0150R090 S2      
327m0767            C785  -1   M      A18X+163443Y+155955X0120Y0150R270 S2      
327m0767            C780  -1   M      A18X+161026Y+155675X0120Y0150R090 S2      
327m0767            C782  -1   M      A18X+161081Y+155955X0120Y0150R270 S2      
317m0767            VIA   -    MD0080PA00X+148275Y+155935X0160Y         S0      
317m0767            VIA   -    MD0080PA00X+148220Y+155695X0160Y         S0      
317m0767            VIA   -    MD0080PA00X+150637Y+155935X0160Y         S0      
317m0767            VIA   -    MD0080PA00X+150582Y+155695X0160Y         S0      
327m0767            C1048 -1   M      A18X+150582Y+155675X0120Y0150R090 S2      
327m0767            C1012 -1   M      A18X+150637Y+155955X0120Y0150R270 S2      
327m0767            C1007 -1   M      A18X+148220Y+155675X0120Y0150R090 S2      
327m0767            C1009 -1   M      A18X+148275Y+155955X0120Y0150R270 S2      
317m0767            VIA   -    MD0080PA00X+134664Y+155935X0160Y         S0      
317m0767            VIA   -    MD0080PA00X+134609Y+155695X0160Y         S0      
317m0767            VIA   -    MD0080PA00X+137026Y+155935X0160Y         S0      
317m0767            VIA   -    MD0080PA00X+136971Y+155695X0160Y         S0      
327m0767            C619  -1   M      A18X+136971Y+155675X0120Y0150R090 S2      
327m0767            C615  -1   M      A18X+137026Y+155955X0120Y0150R270 S2      
327m0767            C610  -1   M      A18X+134609Y+155675X0120Y0150R090 S2      
327m0767            C608  -1   M      A18X+134664Y+155955X0120Y0150R270 S2      
317m0767            VIA   -    MD0080PA00X+121858Y+155935X0160Y         S0      
317m0767            VIA   -    MD0080PA00X+121802Y+155695X0160Y         S0      
317m0767            VIA   -    MD0080PA00X+124220Y+155935X0160Y         S0      
317m0767            VIA   -    MD0080PA00X+124165Y+155695X0160Y         S0      
327m0767            C578  -1   M      A18X+124165Y+155675X0120Y0150R090 S2      
327m0767            C524  -1   M      A18X+124220Y+155955X0120Y0150R270 S2      
327m0767            C540  -1   M      A18X+121802Y+155675X0120Y0150R090 S2      
327m0767            C522  -1   M      A18X+121858Y+155955X0120Y0150R270 S2      
327m0767            PC6565-1          A01X+174069Y+153103X0198Y0197R090 S1      
327m0767            PC6806-1          A18X+180198Y+153083X0198Y0197R270 S2      
327m0767            PR6530-2   M      A01X+173315Y+153095X0198Y0197     S1      
317m0767            VIA   -    MD0100PA00X+181588Y+152468X0200Y         S0      
317m0767            VIA   -    MD0100PA00X+181848Y+152468X0200Y         S0      
317m0767            VIA   -    MD0100PA00X+180729Y+152453X0200Y         S0      
317m0767            VIA   -    MD0100PA00X+180989Y+152453X0200Y         S0      
327m0767            PC6572-1          A01X+181948Y+150527X0630Y1190     S1      
317m0767            VIA   -    MD0100PA00X+182703Y+151240X0200Y    R090 S0      
317m0767            VIA   -    MD0100PA00X+182703Y+150940X0200Y    R090 S0      
317m0767            VIA   -    MD0100PA00X+182703Y+150340X0200Y    R090 S0      
317m0767            VIA   -    MD0100PA00X+182703Y+150640X0200Y    R090 S0      
327m0767            PC6586-1          A18X+177335Y+153036X0400Y0500R090 S2      
327m0767            PC6812-1          A18X+178709Y+152448X0950Y1110R270 S2      
327m0767            PC6811-1          A18X+175819Y+152443X0950Y1110R270 S2      
327m0767            PC6567-1          A18X+181692Y+152852X0400Y0500R090 S2      
327m0767            PC6566-1          A18X+180842Y+152852X0400Y0500R090 S2      
327m0767            PR6557-1          A18X+182351Y+152909X0280Y0320     S2      
327m0767            PC534 -1          A18X+181939Y+150877X0950Y1110R090 S2      
327m0767            PC6569-1          A18X+179539Y+150877X0950Y1110R090 S2      
327m0767            PC6570-1          A18X+177139Y+150877X0950Y1110R090 S2      
327m0767            PC6568-1          A18X+174869Y+150877X0950Y1110R090 S2      
317m0767            VIA   -    MD0100PA00X+179427Y+152872X0200Y         S0      
317m0767            VIA   -    MD0100PA00X+179745Y+152877X0200Y         S0      
317m0767            VIA   -    MD0100PA00X+179999Y+152867X0200Y         S0      
317m0767            VIA   -    MD0100PA00X+179736Y+152610X0200Y         S0      
317m0767            VIA   -    MD0100PA00X+179988Y+152611X0200Y         S0      
317m0767            VIA   -    MD0100PA00X+179736Y+152350X0200Y         S0      
317m0767            VIA   -    MD0100PA00X+179988Y+152351X0200Y         S0      
317m0767            VIA   -    MD0100PA00X+179736Y+152090X0200Y         S0      
317m0767            VIA   -    MD0100PA00X+178000Y+152889X0200Y         S0      
317m0767            VIA   -    MD0100PA00X+179426Y+152606X0200Y         S0      
317m0767            VIA   -    MD0100PA00X+179426Y+152086X0200Y         S0      
317m0767            VIA   -    MD0100PA00X+179426Y+152346X0200Y         S0      
317m0767            VIA   -    MD0100PA00X+178004Y+152636X0200Y         S0      
317m0767            VIA   -    MD0100PA00X+178004Y+152386X0200Y         S0      
317m0767            VIA   -    MD0100PA00X+178001Y+152123X0200Y         S0      
327m0767            PL6506-2   M      A01X+178698Y+152668X0790Y1660R270 S1      
317m0767            VIA   -    MD0100PA00X+176533Y+152934X0200Y         S0      
317m0767            VIA   -    MD0100PA00X+176525Y+152660X0200Y         S0      
317m0767            VIA   -    MD0100PA00X+176525Y+152400X0200Y         S0      
317m0767            VIA   -    MD0100PA00X+175113Y+152925X0200Y         S0      
317m0767            VIA   -    MD0100PA00X+175113Y+152425X0200Y         S0      
317m0767            VIA   -    MD0100PA00X+175113Y+152675X0200Y         S0      
327m0767            PL6505-2   M      A01X+175840Y+152668X0790Y1660R270 S1      
317m0767            VIA   -    MD0100PA00X+180405Y+152803X0200Y         S0      
317m0767            VIA   -    MD0100PA00X+179426Y+151826X0200Y         S0      
317m0767            VIA   -    MD0100PA00X+179988Y+151831X0200Y         S0      
317m0767            VIA   -    MD0100PA00X+179988Y+152091X0200Y         S0      
317m0767            VIA   -    MD0100PA00X+179736Y+151830X0200Y         S0      
317m0767            VIA   -    MD0100PA00X+181203Y+151240X0200Y    R090 S0      
317m0767            VIA   -    MD0100PA00X+181203Y+150940X0200Y    R090 S0      
317m0767            VIA   -    MD0100PA00X+180303Y+151240X0200Y    R090 S0      
317m0767            VIA   -    MD0100PA00X+178001Y+151603X0200Y         S0      
317m0767            VIA   -    MD0100PA00X+178001Y+151863X0200Y         S0      
317m0767            VIA   -    MD0100PA00X+180303Y+150940X0200Y    R090 S0      
317m0767            VIA   -    MD0100PA00X+178803Y+151240X0200Y    R090 S0      
317m0767            VIA   -    MD0100PA00X+176518Y+151590X0200Y         S0      
317m0767            VIA   -    MD0100PA00X+176529Y+151847X0200Y         S0      
317m0767            VIA   -    MD0100PA00X+177903Y+151240X0200Y    R090 S0      
317m0767            VIA   -    MD0100PA00X+178803Y+150940X0200Y    R090 S0      
317m0767            VIA   -    MD0100PA00X+177903Y+150940X0200Y    R090 S0      
317m0767            VIA   -    MD0100PA00X+175109Y+151870X0200Y         S0      
317m0767            VIA   -    MD0100PA00X+175112Y+152122X0200Y         S0      
317m0767            VIA   -    MD0100PA00X+176403Y+151240X0200Y    R090 S0      
317m0767            VIA   -    MD0100PA00X+174575Y+152124X0200Y    R090 S0      
317m0767            VIA   -    MD0100PA00X+176403Y+150940X0200Y    R090 S0      
317m0767            VIA   -    MD0100PA00X+174276Y+152124X0200Y    R090 S0      
317m0767            VIA   -    MD0100PA00X+174554Y+151868X0200Y    R090 S0      
317m0767            VIA   -    MD0100PA00X+175633Y+151240X0200Y    R090 S0      
317m0767            VIA   -    MD0100PA00X+173956Y+152810X0200Y    R090 S0      
317m0767            VIA   -    MD0100PA00X+175633Y+150940X0200Y    R090 S0      
317m0767            VIA   -    MD0100PA00X+174133Y+151240X0200Y    R090 S0      
317m0767            VIA   -    MD0100PA00X+174133Y+150940X0200Y    R090 S0      
317m0767            VIA   -    MD0100PA00X+181203Y+150340X0200Y    R090 S0      
317m0767            VIA   -    MD0100PA00X+181203Y+150640X0200Y    R090 S0      
317m0767            VIA   -    MD0100PA00X+180303Y+150340X0200Y    R090 S0      
317m0767            VIA   -    MD0100PA00X+180303Y+150640X0200Y    R090 S0      
327m0767            PC6573-1          A01X+179548Y+150527X0630Y1190     S1      
317m0767            VIA   -    MD0100PA00X+178803Y+150340X0200Y    R090 S0      
317m0767            VIA   -    MD0100PA00X+178803Y+150640X0200Y    R090 S0      
317m0767            VIA   -    MD0100PA00X+177903Y+150340X0200Y    R090 S0      
317m0767            VIA   -    MD0100PA00X+177903Y+150640X0200Y    R090 S0      
317m0767            VIA   -    MD0100PA00X+176403Y+150340X0200Y    R090 S0      
317m0767            VIA   -    MD0100PA00X+176403Y+150640X0200Y    R090 S0      
327m0767            PC6574-1          A01X+177148Y+150527X0630Y1190     S1      
317m0767            VIA   -    MD0100PA00X+175633Y+150340X0200Y    R090 S0      
317m0767            VIA   -    MD0100PA00X+175633Y+150640X0200Y    R090 S0      
327m0767            PC6571-1          A01X+174748Y+150527X0630Y1190     S1      
317m0767            VIA   -    MD0100PA00X+174133Y+150340X0200Y    R090 S0      
317m0767            VIA   -    MD0100PA00X+174133Y+150640X0200Y    R090 S0      
327m0767            PR6564-2          A01X+177040Y+157790X0198Y0197R180 S1      
317m0767            VIA   -    MD0100PA00X+177040Y+157533X0200Y         S0      
327m0767            PR6556-2          A01X+173798Y+158048X0198Y0197R090 S1      
317m0767            VIA   -    MD0100PA00X+173535Y+158048X0200Y    R090 S0      
327OC_P2V5_COMP     C8014 -1   M      A18X+073808Y+166300X0198Y0197     S2      
327OC_P2V5_COMP     R8107 -2   M      A18X+074192Y+166300X0198Y0197     S2      
327OC_P2V5_COMP     VIA   -    M      A18X+074192Y+166633X0260Y         S2      
327OC_P2V5_COMP     U8005 -1          A18X+073626Y+165366X0240Y0420R180 S2      
327OC_P2V5_COMP     U8006 -1          A18X+074124Y+167268X0240Y0420     S2      
327m0768            C8004 -1   M      A01X+005092Y+030350X0198Y0197     S1      
327m0768            R8016 -2          A01X+004708Y+030350X0198Y0197     S1      
317m0768            VIA   -    M      A01X+005525Y+029289X0200Y         S2      
017m0768            VIA   -    M      A18X+005525Y+029289X0260Y         S2      
017m0768                  -    MD0100PA00X+005525Y+029289                       
327m0768            U242  -6          A01X+005867Y+029289X0160Y0340R270 S1      
327m0769            C8003 -1   M      A01X+006442Y+029000X0198Y0197     S1      
327m0769            R8015 -2          A01X+003808Y+028850X0198Y0197     S1      
317m0769            VIA   -    M      A01X+004050Y+028850X0200Y         S2      
017m0769            VIA   -    M      A18X+004050Y+028850X0260Y         S2      
017m0769                  -    MD0100PA00X+004050Y+028850                       
327m0769            U242  -5          A01X+005867Y+029014X0200Y0340R270 S1      
327m0770            R8096 -1   M      A01X+031208Y+026300X0198Y0197R180 S1      
327m0770            R8097 -1          A01X+031592Y+026300X0198Y0197     S1      
327m0770            R8095 -2          A01X+030250Y+025358X0198Y0197R090 S1      
317m0770            VIA   -    M      A01X+030653Y+025653X0200Y         S2      
017m0770            VIA   -    M      A18X+030653Y+025653X0260Y         S2      
017m0770                  -    MD0100PA00X+030653Y+025653                       
327m0770            U8002 -2   M      A01X+030976Y+025653X0260Y0380R180 S1      
327m0771            R8094 -1          A01X+162500Y+038908X0198Y0197R270 S1      
327m0771            R8092 -2   M      A01X+162900Y+038908X0198Y0197R090 S1      
327m0771            R8093 -1   M      A01X+162900Y+039292X0198Y0197R090 S1      
317m0771            VIA   -    M      A01X+163166Y+039292X0200Y         S2      
017m0771            VIA   -    M      A18X+163166Y+039292X0260Y         S2      
017m0771                  -    MD0100PA00X+163166Y+039292                       
327m0771            U8001 -2          A01X+163476Y+039603X0260Y0380R180 S1      
327m0772            C8002 -1   M      A18X+003650Y+031792X0198Y0197R270 S2      
327m0772            R8014 -2          A18X+003300Y+031792X0198Y0197R090 S2      
317m0772            VIA   -    M      A01X+004789Y+029545X0200Y    R090 S2      
017m0772            VIA   -    M      A18X+004789Y+029545X0260Y    R090 S2      
017m0772                  -    MD0100PA00X+004789Y+029545                       
327m0772            U242  -2          A01X+004469Y+029545X0160Y0340R270 S1      
327m0773            C8001 -1   M      A18X+004000Y+031792X0198Y0197R270 S2      
327m0773            R8013 -2          A18X+004350Y+031792X0198Y0197R090 S2      
317m0773            VIA   -    M      A01X+004149Y+029821X0200Y    R270 S2      
017m0773            VIA   -    M      A18X+004149Y+029821X0260Y    R270 S2      
017m0773                  -    MD0100PA00X+004149Y+029821                       
327m0773            U242  -1          A01X+004469Y+029821X0200Y0340R270 S1      
327NC_U8004_2Y      U8004 -4          A18X+079406Y+054926X0170Y0240R180 S2      
327NC_U8004_2Y      VIA   -           A18X+079929Y+054926X0260Y         S2      
327NC_U314_NC3      U314  -30         A01X+112256Y+165629X0100Y0220R180 S1      
327NC_U314_NC2      U314  -17         A01X+113487Y+164005X0100Y0220R090 S1      
327NC_U314_NC1      U314  -11         A01X+112256Y+163759X0100Y0220     S1      
327NC_U314_NC0      U314  -10         A01X+112060Y+163759X0100Y0220     S1      
327m0774            U314  -8          A01X+111617Y+164005X0100Y0220R270 S1      
327NC_U314_FBOUT    U314  -9          A01X+111863Y+163759X0100Y0220     S1      
327NC_U10_NC3       U10   -30         A01X+042764Y+161568X0100Y0220R090 S1      
327NC_U10_NC2       U10   -17         A01X+041140Y+160338X0100Y0220     S1      
327NC_U10_NC1       U10   -11         A01X+040894Y+161568X0100Y0220R270 S1      
327NC_U10_NC0       U10   -10         A01X+040894Y+161765X0100Y0220R270 S1      
327NC_U10_FBOUT_N   U10   -8          A01X+041140Y+162208X0100Y0220R180 S1      
327NC_U10_FBOUT     U10   -9          A01X+040894Y+161962X0100Y0220R270 S1      
327m0775            PU6510-1          A01X+005268Y+160596X0070Y0240     S1      
327m0776            PU6510-2          A01X+005426Y+160596X0070Y0240     S1      
327m0777            PU6510-3          A01X+005583Y+160596X0070Y0240     S1      
327m0778            PU6510-4          A01X+005740Y+160596X0070Y0240     S1      
327m0779            PU6510-5          A01X+005898Y+160596X0070Y0240     S1      
327m0780            PU6510-6          A01X+006055Y+160596X0070Y0240     S1      
327m0781            PU6510-16         A01X+006922Y+161619X0070Y0240R090 S1      
327m0782            PR6544-1          A01X+004613Y+163332X0198Y0197R090 S1      
327m0782            PU6510-30         A01X+005268Y+162485X0070Y0240     S1      
327m0783            PR6543-1          A01X+005113Y+163332X0198Y0197R090 S1      
327m0783            PU6510-29         A01X+005426Y+162485X0070Y0240     S1      
327m0784            PR6542-1          A18X+005363Y+163482X0198Y0197R270 S2      
327m0784            PU6510-28         A01X+005583Y+162485X0070Y0240     S1      
317m0784            VIA   -    M      A01X+005363Y+162990X0200Y    R270 S2      
017m0784            VIA   -    M      A18X+005363Y+162990X0260Y    R270 S2      
017m0784                  -    MD0100PA00X+005363Y+162990                       
327m0785            PR6541-1          A01X+005613Y+163642X0198Y0197R090 S1      
327m0785            VIA   -    M      A01X+005613Y+163170X0300Y         S1      
327m0785            PU6510-27         A01X+005740Y+162485X0070Y0240     S1      
327m0786            PR6540-1          A18X+005863Y+163482X0198Y0197R270 S2      
327m0786            PU6510-26         A01X+005898Y+162485X0070Y0240     S1      
317m0786            VIA   -    M      A01X+005863Y+162990X0200Y    R270 S2      
017m0786            VIA   -    M      A18X+005863Y+162990X0260Y    R270 S2      
017m0786                  -    MD0100PA00X+005863Y+162990                       
327m0787            PR6539-1          A01X+006113Y+163642X0198Y0197R090 S1      
327m0787            VIA   -    M      A01X+006113Y+163180X0300Y         S1      
327m0787            PU6510-25         A01X+006055Y+162485X0070Y0240     S1      
327m0788            PU6512-41         A01X+009494Y+152994X0120Y0180R270 S1      
327m0789            PU6511-41         A01X+005920Y+152994X0120Y0180R270 S1      
327m0790            PU6512-6          A01X+009150Y+153102X0090Y0240R090 S1      
327m0791            PU6511-6          A01X+005576Y+153102X0090Y0240R090 S1      
327m0792            PU6512-31         A01X+010729Y+154234X0090Y0240     S1      
327m0793            PU6511-31         A01X+007154Y+154234X0090Y0240     S1      
327m0794            PU6502-1          A01X+175642Y+167840X0070Y0240R180 S1      
327m0795            PU6502-2          A01X+175484Y+167840X0070Y0240R180 S1      
327m0796            PU6502-3          A01X+175327Y+167840X0070Y0240R180 S1      
327m0797            PU6502-4          A01X+175169Y+167840X0070Y0240R180 S1      
327m0798            PU6502-5          A01X+175012Y+167840X0070Y0240R180 S1      
327m0799            PU6502-6          A01X+174854Y+167840X0070Y0240R180 S1      
327m0800            PU6502-16         A01X+173988Y+166817X0070Y0240R270 S1      
327m0801            PR6614-1          A01X+176296Y+165104X0198Y0197R270 S1      
327m0801            PU6502-30         A01X+175642Y+165951X0070Y0240R180 S1      
327m0802            PR6613-1          A01X+175796Y+165104X0198Y0197R270 S1      
327m0802            PU6502-29         A01X+175484Y+165951X0070Y0240R180 S1      
327m0803            PR6612-1          A18X+175546Y+164954X0198Y0197R090 S2      
317m0803            VIA   -    M      A01X+175546Y+165446X0200Y    R090 S2      
017m0803            VIA   -    M      A18X+175546Y+165446X0260Y    R090 S2      
017m0803                  -    MD0100PA00X+175546Y+165446                       
327m0803            PU6502-28         A01X+175327Y+165951X0070Y0240R180 S1      
327m0804            PR6611-1          A01X+175296Y+164794X0198Y0197R270 S1      
327m0804            VIA   -    M      A01X+175296Y+165266X0300Y    R180 S1      
327m0804            PU6502-27         A01X+175169Y+165951X0070Y0240R180 S1      
327m0805            PR6610-1          A18X+175046Y+164954X0198Y0197R090 S2      
327m0805            PU6502-26         A01X+175012Y+165951X0070Y0240R180 S1      
317m0805            VIA   -    M      A01X+175046Y+165446X0200Y    R090 S2      
017m0805            VIA   -    M      A18X+175046Y+165446X0260Y    R090 S2      
017m0805                  -    MD0100PA00X+175046Y+165446                       
327m0806            PR6609-1          A01X+174796Y+164794X0198Y0197R270 S1      
327m0806            VIA   -    M      A01X+174796Y+165256X0300Y    R180 S1      
327m0806            PU6502-25         A01X+174854Y+165951X0070Y0240R180 S1      
327m0807            PU6504-41         A01X+178223Y+156297X0120Y0180R270 S1      
327m0808            PU6503-41         A01X+174648Y+156297X0120Y0180R270 S1      
327m0809            PU6504-6          A01X+177878Y+156406X0090Y0240R090 S1      
327m0810            PU6503-6          A01X+174304Y+156406X0090Y0240R090 S1      
327m0811            PU6504-31         A01X+179457Y+157538X0090Y0240     S1      
327m0812            PU6503-31         A01X+175883Y+157538X0090Y0240     S1      
327m0813            VIA   -    M      A01X+075350Y+020800X0300Y         S1      
327m0813            D8002 -C          A01X+075350Y+020245X0320Y0320R090 S1      
327m0813            Q8001 -3          A01X+075356Y+021276X0170Y0200R180 S1      
327m0814            R8028 -2          A01X+075448Y+022820X0198Y0197R180 S1      
327m0814            VIA   -    M      A01X+075100Y+022500X0300Y         S1      
327m0814            Q8001 -5          A01X+075100Y+022024X0170Y0200R180 S1      
327m0814            Q8001 -6          A01X+074844Y+022024X0170Y0200R180 S1      
327m0815            R8029 -1          A01X+076100Y+021242X0198Y0197R090 S1      
327m0815            VIA   -    M      A01X+076100Y+019900X0300Y         S1      
327m0815            D8002 -A          A01X+075350Y+019655X0320Y0320R090 S1      
327m0816            R8026 -2          A01X+015032Y+021038X0198Y0197R270 S1      
327m0816            R8027 -1          A01X+072529Y+161474X0198Y0197     S1      
317m0816            VIA   -    M      A01X+016315Y+147450X0200Y         S2      
017m0816            VIA   -    M      A18X+016315Y+147450X0260Y         S2      
017m0816                  -    MD0100PA00X+016315Y+147450                       
317m0816            VIA   -    MD0100PA00X+075097Y+148235X0200Y         S0      
317m0816            VIA   -    MD0100PA00X+071723Y+161238X0200Y         S0      
327m0817            R8025 -2          A01X+015032Y+021838X0198Y0197R270 S1      
327m0817            R8026 -1          A01X+015032Y+021353X0198Y0197R270 S1      
317m0817            VIA   -    M      A01X+014823Y+021612X0200Y         S2      
017m0817            VIA   -    M      A18X+014823Y+021612X0260Y         S2      
017m0817                  -    MD0100PA00X+014823Y+021612                       
327m0818            D8001 -A          A01X+015032Y+022709X0240Y0280R090 S1      
327m0818            R8025 -1          A01X+015032Y+022153X0198Y0197R270 S1      
317m0818            VIA   -    M      A01X+014923Y+022420X0200Y         S2      
017m0818            VIA   -    M      A18X+014923Y+022420X0260Y         S2      
017m0818                  -    MD0100PA00X+014923Y+022420                       
327m0819            R8023 -2          A01X+144819Y+024445X0198Y0197     S1      
317m0819            VIA   -    M      A01X+075158Y+018425X0200Y         S2      
017m0819            VIA   -    M      A18X+075158Y+018425X0260Y         S2      
017m0819                  -    MD0100PA00X+075158Y+018425                       
327m0819            R8024 -1          A01X+075158Y+017550X0198Y0197R180 S1      
317m0819            VIA   -    MD0100PA00X+141075Y+024458X0200Y         S0      
327m0820            R8022 -2          A01X+143519Y+024445X0198Y0197     S1      
327m0820            R8023 -1          A01X+144504Y+024445X0198Y0197     S1      
327m0820            VIA   -    M      A01X+144012Y+024445X0300Y    R090 S1      
327m0821            D8000 -A          A01X+142199Y+024445X0240Y0280R180 S1      
327m0821            R8022 -1          A01X+143204Y+024445X0198Y0197     S1      
327m0821            VIA   -    M      A01X+142712Y+024445X0300Y    R090 S1      
327m0822            R8123 -2   M      A01X+055892Y+047350X0198Y0197R180 S1      
327m0822            R8124 -1          A01X+055892Y+047750X0198Y0197     S1      
327m0822            VIA   -    M      A01X+055306Y+047233X0300Y         S1      
327m0822            U8010 -4          A01X+055518Y+046624X0240Y0420R090 S1      
327HSC_OC_VOL       R8112 -1          A18X+072724Y+167349X0198Y0197R270 S2      
327HSC_OC_VOL       VIA   -    M      A18X+073376Y+166691X0260Y         S2      
327HSC_OC_VOL       R8108 -2          A18X+072263Y+166382X0198Y0197R090 S2      
327HSC_OC_VOL       C8015 -1   M      A18X+072630Y+166381X0198Y0197R090 S2      
327HSC_OC_VOL       R8109 -1   M      A18X+073030Y+166381X0198Y0197R090 S2      
327HSC_OC_VOL       U8006 -3   M      A18X+073376Y+167268X0240Y0420     S2      
327HSC_D_OC_R2      R8110 -1          A18X+072869Y+168566X0198Y0197     S2      
327HSC_D_OC_R2      VIA   -    M      A18X+072724Y+167991X0260Y         S2      
327HSC_D_OC_R2      U8006 -4          A18X+073376Y+168332X0240Y0420     S2      
327HSC_D_OC_R2      R8112 -2   M      A18X+072724Y+167664X0198Y0197R270 S2      
327m0823            R8012 -1          A18X+068150Y+011692X0198Y0197R270 S2      
327m0823            PU299 -10         A01X+069013Y+011590X0100Y0320R270 S1      
327m0823            R3836 -2          A01X+068353Y+011587X0198Y0197     S1      
317m0823            VIA   -    M      A01X+068689Y+011587X0200Y         S2      
017m0823            VIA   -    M      A18X+068689Y+011587X0260Y         S2      
017m0823                  -    MD0100PA00X+068689Y+011587                       
327m0824            R8117 -2   M      A01X+052958Y+043250X0198Y0197     S1      
327m0824            R8118 -1          A01X+058363Y+045424X0198Y0197     S1      
327m0824            VIA   -    M      A01X+053740Y+043078X0300Y         S1      
327m0824            U8008 -4          A01X+052982Y+043826X0240Y0420R270 S1      
317m0825            VIA   -    MD0100PA00X+074926Y+044356X0180Y    R090 S0      
317m0825            VIA   -    M      A01X+075348Y+064875X0200Y         S2      
017m0825            VIA   -    M      A18X+075348Y+064875X0260Y         S2      
017m0825                  -    MD0100PA00X+075348Y+064875                       
317m0825            VIA   -    MD0100PA00X+079313Y+073431X0200Y         S0      
327m0825            C109  -1          A18X+089278Y+114106X0198Y0197     S2      
327m0825            R645  -2   M      A18X+089971Y+113648X0198Y0197R090 S2      
327m0825            U18   -U9         A01X+074772Y+044509X0160Y    R090 S1      
327m0826            R8021 -2          A01X+079308Y+050700X0198Y0197     S1      
327m0826            R8019 -2          A01X+166200Y+022108X0198Y0197R090 S1      
317m0826            VIA   -    M      A01X+079945Y+051180X0200Y         S2      
017m0826            VIA   -    M      A18X+079945Y+051180X0260Y         S2      
017m0826                  -    MD0100PA00X+079945Y+051180                       
317m0826            VIA   -    MD0100PA00X+165942Y+022460X0200Y         S0      
327m0826            U124  -2          A01X+166861Y+022460X0220Y0530R270 S1      
327m0826            R733  -2   M      A01X+166193Y+022460X0198Y0197R270 S1      
317m0826            VIA   -    MD0100PA00X+098102Y+034939X0200Y         S0      
317m0826            VIA   -    MD0100PA00X+099553Y+050003X0200Y         S0      
327m0827            R8032 -1          A01X+073250Y+054042X0198Y0197R090 S1      
317m0827            VIA   -    M      A01X+073665Y+052977X0200Y         S2      
017m0827            VIA   -    M      A18X+073665Y+052977X0260Y         S2      
017m0827                  -    MD0100PA00X+073665Y+052977                       
327m0827            U18   -N17        A01X+073513Y+047029X0160Y    R090 S1      
317m0827            VIA   -    MD0100PA00X+073666Y+047182X0180Y         S0      
327m0828            R8032 -2          A01X+073250Y+054358X0198Y0197R090 S1      
327m0828            R8033 -1   M      A18X+073892Y+056400X0198Y0197R180 S2      
317m0828            VIA   -    M      A01X+072871Y+055419X0200Y         S2      
017m0828            VIA   -    M      A18X+072871Y+055419X0260Y         S2      
017m0828                  -    MD0100PA00X+072871Y+055419                       
327m0828            U8000 -6          A18X+073124Y+056594X0160Y0200R270 S2      
317m0829            VIA   -    MD0100PA00X+074279Y+164798X0200Y         S0      
327m0829            R8102 -1          A01X+076737Y+166249X0198Y0197R090 S1      
317m0829            VIA   -    MD0100PA00X+065075Y+161591X0200Y         S0      
327m0829            R8101 -1          A01X+057845Y+008621X0198Y0197R270 S1      
317m0829            VIA   -    M      A01X+079278Y+056532X0200Y         S2      
017m0829            VIA   -    M      A18X+079278Y+056532X0260Y         S2      
017m0829                  -    MD0100PA00X+079278Y+056532                       
317m0829            VIA   -    MD0100PA00X+074355Y+014770X0200Y         S0      
317m0829            VIA   -    MD0100PA00X+057845Y+008893X0200Y         S0      
317m0829            VIA   -    MD0100PA00X+069516Y+144135X0200Y         S0      
327m0829            R8103 -2          A18X+078100Y+056958X0198Y0197R270 S2      
327m0829            R8104 -1   M      A18X+078900Y+056958X0198Y0197R090 S2      
327m0829            C8012 -1   M      A18X+078500Y+056958X0198Y0197R090 S2      
317m0829            VIA   -    MD0100PA00X+063913Y+157313X0200Y         S0      
327m0830            R8104 -2          A18X+078900Y+056642X0198Y0197R090 S2      
327m0830            U8004 -1          A18X+078894Y+055674X0170Y0240R180 S2      
327m0830            VIA   -    M      A18X+078894Y+056194X0260Y         S2      
327m0831            R8105 -1          A18X+078550Y+053958X0198Y0197R090 S2      
327m0831            VIA   -    M      A18X+078550Y+054400X0260Y    R090 S2      
327m0831            U8004 -6          A18X+078894Y+054926X0170Y0240R180 S2      
317m0832            VIA   -    MD0100PA00X+075556Y+047497X0180Y    R090 S0      
327m0832            R8105 -2   M      A18X+078550Y+053642X0198Y0197R090 S2      
327m0832            R8106 -2          A18X+078550Y+053258X0198Y0197R270 S2      
317m0832            VIA   -    M      A01X+078170Y+053642X0200Y         S2      
017m0832            VIA   -    M      A18X+078170Y+053642X0260Y         S2      
017m0832                  -    MD0100PA00X+078170Y+053642                       
327m0832            U18   -W18        A01X+075402Y+047344X0160Y    R090 S1      
327m0833            C8011 -1   M      A01X+076738Y+167017X0198Y0197R090 S1      
327m0833            R8102 -2          A01X+076737Y+166564X0198Y0197R090 S1      
317m0833            VIA   -    M      A01X+076873Y+169448X0200Y         S2      
017m0833            VIA   -    M      A18X+076873Y+169448X0260Y         S2      
017m0833                  -    MD0100PA00X+076873Y+169448                       
317m0833            J45   -A2   D0402PA00X+092878Y+171489X0657Y    R270 S3      
327m0834            J41   -B42        A01X+059392Y+006516X0150Y0570R180 S1      
327m0834            R8101 -2          A01X+057845Y+008306X0198Y0197R270 S1      
327m0834            VIA   -    M      A01X+057906Y+007797X0300Y         S1      
327m0835            R560  -2          A01X+042850Y+163392X0198Y0197R270 S1      
327m0835            U10   -1          A01X+042518Y+162208X0100Y0220R180 S1      
327m0835            VIA   -    M      A01X+042850Y+163050X0300Y         S1      
327m0836            R6803 -1          A01X+043842Y+160420X0198Y0197     S1      
327m0836            U10   -26         A01X+042764Y+160780X0100Y0220R090 S1      
327m0836            VIA   -    M      A01X+043380Y+160655X0300Y         S1      
327m0837            R592  -1          A01X+043842Y+160020X0198Y0197     S1      
327m0837            VIA   -    M      A01X+043168Y+160167X0300Y         S1      
327m0837            U10   -24         A01X+042518Y+160338X0100Y0220     S1      
327m0838            R593  -1          A01X+039718Y+159902X0198Y0197R180 S1      
327m0838            VIA   -    M      A01X+040761Y+159902X0300Y         S1      
327m0838            U10   -18         A01X+041337Y+160338X0100Y0220     S1      
327m0839            R594  -1          A01X+039718Y+160302X0198Y0197R180 S1      
327m0839            VIA   -    M      A01X+040155Y+160302X0300Y         S1      
327m0839            U10   -15         A01X+040894Y+160780X0100Y0220R270 S1      
327m0840            VIA   -    M      A01X+110952Y+166092X0300Y         S1      
327m0840            R4476 -2          A01X+110900Y+166542X0198Y0197R270 S1      
327m0840            U314  -1          A01X+111617Y+165383X0100Y0220R270 S1      
327m0841            VIA   -    M      A01X+113540Y+166376X0300Y         S1      
327m0841            R6802 -1          A01X+114012Y+166558X0198Y0197R090 S1      
327m0841            U314  -26         A01X+113044Y+165629X0100Y0220R180 S1      
327m0842            VIA   -    M      A01X+114235Y+165956X0300Y         S1      
327m0842            R4518 -1          A01X+114411Y+166549X0198Y0197R090 S1      
327m0842            U314  -24         A01X+113487Y+165383X0100Y0220R090 S1      
327m0843            VIA   -    M      A01X+113846Y+163228X0300Y         S1      
327m0843            U314  -18         A01X+113487Y+164202X0100Y0220R090 S1      
327m0843            R4519 -1          A01X+113610Y+162654X0198Y0197R270 S1      
327m0844            VIA   -    M      A01X+113217Y+163056X0300Y         S1      
327m0844            U314  -15         A01X+113044Y+163759X0100Y0220     S1      
327m0844            R4520 -1          A01X+113217Y+162654X0198Y0197R270 S1      
327m0845            VIA   -    M      A18X+072945Y+057648X0260Y         S2      
327m0845            R8034 -1          A18X+072945Y+058204X0198Y0197R180 S2      
327m0845            U8000 -1          A18X+072376Y+056594X0160Y0200R270 S2      
327m0846            R8036 -2   M      A18X+071850Y+057142X0198Y0197R090 S2      
327m0846            VIA   -    M      A18X+071850Y+056674X0260Y         S2      
317m0846            VIA   -    MD0100PA00X+072428Y+055344X0200Y         S0      
327m0846            R1557 -2          A01X+072850Y+054344X0198Y0197R090 S1      
327m0846            U8000 -3          A18X+072376Y+057106X0160Y0200R270 S2      
327m0847            R472  -1          A18X+158943Y+127517X0180Y0200R180 S2      
327m0847            R1593 -1   M      A18X+158943Y+127517X0180Y0200     S2      
327m0847            R1197 -1   M      A18X+073898Y+057317X0198Y0197R180 S2      
317m0847            VIA   -    M      A01X+073653Y+057962X0200Y         S2      
017m0847            VIA   -    M      A18X+073653Y+057962X0260Y         S2      
017m0847                  -    MD0100PA00X+073653Y+057962                       
327m0847            U8000 -4          A18X+073124Y+057106X0160Y0200R270 S2      
317m0847            VIA   -    MD0100PA00X+087942Y+142500X0200Y         S0      
317m0847            VIA   -    MD0100PA00X+159627Y+127147X0200Y         S0      
327m0847            R458  -2   M      A18X+159960Y+127499X0198Y0197     S2      
317m0847            VIA   -    MD0100PA00X+090947Y+144878X0200Y         S0      
327m0848            R579  -1          A01X+041208Y+164100X0198Y0197R180 S1      
327m0848            R578  -2   M      A01X+041208Y+163700X0198Y0197     S1      
327m0848            U10   -5          A01X+041731Y+162208X0100Y0220R180 S1      
327m0848            VIA   -    M      A01X+041330Y+163342X0300Y         S1      
327m0849            R585  -1   M      A18X+043908Y+162600X0198Y0197     S2      
327m0849            R580  -2          A18X+043892Y+163000X0198Y0197     S2      
317m0849            VIA   -    M      A01X+043301Y+162161X0200Y         S2      
017m0849            VIA   -    M      A18X+043301Y+162161X0260Y         S2      
017m0849                  -    MD0100PA00X+043301Y+162161                       
327m0849            U10   -32         A01X+042764Y+161962X0100Y0220R090 S1      
327m0850            VIA   -    M      A01X+110550Y+164350X0300Y         S1      
327m0850            R4490 -1   M      A01X+110208Y+164250X0198Y0197R180 S1      
327m0850            R4489 -2          A01X+110208Y+163900X0198Y0197     S1      
327m0850            U314  -5          A01X+111617Y+164596X0100Y0220R270 S1      
327m0851            VIA   -    M      A01X+111648Y+166163X0300Y         S1      
327m0851            R4492 -1   M      A01X+111600Y+166542X0198Y0197R090 S1      
327m0851            R4491 -2          A01X+111250Y+166542X0198Y0197R270 S1      
327m0851            U314  -32         A01X+111863Y+165629X0100Y0220R180 S1      
327m0852            U10   -27         A01X+042764Y+160977X0100Y0220R090 S1      
317m0852            VIA   -    MD0100PA00X+043678Y+161039X0200Y         S0      
327m0852            R621  -1          A01X+043056Y+152663X0120Y0150     S1      
317m0852            VIA   -    MD0100PA00X+042670Y+152673X0200Y         S0      
327m0853            U10   -28         A01X+042764Y+161174X0100Y0220R090 S1      
317m0853            VIA   -    MD0100PA00X+043678Y+161379X0200Y         S0      
327m0853            R622  -1          A01X+043056Y+152343X0120Y0150     S1      
317m0853            VIA   -    MD0100PA00X+042670Y+152333X0200Y         S0      
327m0854            U6017 -FJ16       A01X+044363Y+152689X0100Y0130R090 S1      
327m0854            R621  -2          A01X+043266Y+152663X0120Y0150R180 S1      
327m0854            R642  -1   M      A01X+043561Y+152663X0120Y0150R090 S1      
327m0855            U6017 -FF18       A01X+044568Y+152571X0120Y         S1      
327m0855            R622  -2          A01X+043266Y+152343X0120Y0150R180 S1      
327m0855            R641  -1   M      A01X+043561Y+152343X0120Y0150R270 S1      
317m0856            VIA   -    MD0100PA00X+055477Y+152673X0200Y         S0      
327m0856            R619  -1          A01X+055862Y+152663X0120Y0150     S1      
317m0856            VIA   -    MD0100PA00X+042207Y+159543X0200Y         S0      
327m0856            U10   -22         A01X+042125Y+160338X0100Y0220     S1      
317m0857            VIA   -    MD0100PA00X+042547Y+159543X0200Y         S0      
327m0857            U10   -23         A01X+042321Y+160338X0100Y0220     S1      
317m0857            VIA   -    MD0100PA00X+055477Y+152333X0200Y         S0      
327m0857            R620  -1          A01X+055862Y+152343X0120Y0150     S1      
327m0858            U6016 -FJ16       A01X+057169Y+152689X0100Y0130R090 S1      
327m0858            R619  -2          A01X+056072Y+152663X0120Y0150R180 S1      
327m0858            R640  -1   M      A01X+056367Y+152663X0120Y0150R090 S1      
327m0859            U6016 -FF18       A01X+057374Y+152571X0120Y         S1      
327m0859            R620  -2          A01X+056072Y+152343X0120Y0150R180 S1      
327m0859            R637  -1   M      A01X+056367Y+152343X0120Y0150R270 S1      
327m0860            U10   -19         A01X+041534Y+160338X0100Y0220     S1      
317m0860            VIA   -    MD0100PA00X+041099Y+159700X0200Y         S0      
327m0860            R597  -1          A01X+029444Y+152663X0120Y0150     S1      
317m0860            VIA   -    MD0100PA00X+029059Y+152673X0200Y         S0      
327m0861            U10   -20         A01X+041731Y+160338X0100Y0220     S1      
317m0861            VIA   -    MD0100PA00X+041340Y+159460X0200Y         S0      
327m0861            R598  -1          A01X+029444Y+152343X0120Y0150     S1      
317m0861            VIA   -    MD0100PA00X+029059Y+152333X0200Y         S0      
327m0862            U6015 -FJ16       A01X+030752Y+152689X0100Y0130R090 S1      
327m0862            R597  -2          A01X+029654Y+152663X0120Y0150R180 S1      
327m0862            R626  -1   M      A01X+029950Y+152663X0120Y0150R090 S1      
327m0863            U6015 -FF18       A01X+030956Y+152571X0120Y         S1      
327m0863            R598  -2          A01X+029654Y+152343X0120Y0150R180 S1      
327m0863            R625  -1   M      A01X+029950Y+152343X0120Y0150R270 S1      
317m0864            VIA   -    MD0100PA00X+016253Y+152673X0200Y         S0      
327m0864            R599  -1          A01X+016638Y+152663X0120Y0150     S1      
327m0864            U10   -13         A01X+040894Y+161174X0100Y0220R270 S1      
317m0864            VIA   -    MD0100PA00X+040384Y+161246X0200Y         S0      
317m0865            VIA   -    MD0100PA00X+016253Y+152333X0200Y         S0      
327m0865            R609  -1          A01X+016638Y+152343X0120Y0150     S1      
327m0865            U10   -14         A01X+040894Y+160977X0100Y0220R270 S1      
317m0865            VIA   -    MD0100PA00X+040384Y+160906X0200Y         S0      
327m0866            U6014 -FJ16       A01X+017946Y+152689X0100Y0130R090 S1      
327m0866            R599  -2          A01X+016848Y+152663X0120Y0150R180 S1      
327m0866            R628  -1   M      A01X+017143Y+152663X0120Y0150R090 S1      
327m0867            U6014 -FF18       A01X+018150Y+152571X0120Y         S1      
327m0867            R609  -2          A01X+016848Y+152343X0120Y0150R180 S1      
327m0867            R627  -1   M      A01X+017143Y+152343X0120Y0150R270 S1      
327m0868            R615  -1          A01X+143843Y+155963X0120Y0150     S1      
317m0868            VIA   -    MD0100PA00X+143458Y+155973X0200Y         S0      
317m0868            VIA   -    MD0100PA00X+111813Y+159140X0200Y         S0      
327m0868            U314  -27         A01X+112847Y+165629X0100Y0220R180 S1      
317m0868            VIA   -    MD0100PA00X+112918Y+166270X0200Y         S0      
327m0869            R616  -1          A01X+143843Y+155643X0120Y0150     S1      
317m0869            VIA   -    MD0100PA00X+143458Y+155633X0200Y         S0      
317m0869            VIA   -    MD0100PA00X+111813Y+158800X0200Y         S0      
327m0869            U314  -28         A01X+112650Y+165629X0100Y0220R180 S1      
317m0869            VIA   -    MD0100PA00X+112578Y+166270X0200Y         S0      
327m0870            U6013 -FJ16       A01X+145150Y+155989X0100Y0130R090 S1      
327m0870            R615  -2          A01X+144053Y+155963X0120Y0150R180 S1      
327m0870            R636  -1   M      A01X+144348Y+155963X0120Y0150R090 S1      
327m0871            U6013 -FF18       A01X+145355Y+155871X0120Y         S1      
327m0871            R616  -2          A01X+144053Y+155643X0120Y0150R180 S1      
327m0871            R635  -1   M      A01X+144348Y+155643X0120Y0150R270 S1      
327m0872            U314  -22         A01X+113487Y+164989X0100Y0220R090 S1      
317m0872            VIA   -    MD0100PA00X+114650Y+165221X0200Y         S0      
317m0872            VIA   -    MD0100PA00X+113182Y+160399X0200Y         S0      
327m0872            R613  -1          A01X+156649Y+155963X0120Y0150     S1      
317m0872            VIA   -    MD0100PA00X+156264Y+155973X0200Y         S0      
327m0873            R614  -1          A01X+156649Y+155643X0120Y0150     S1      
317m0873            VIA   -    MD0100PA00X+156264Y+155633X0200Y         S0      
327m0873            U314  -23         A01X+113487Y+165186X0100Y0220R090 S1      
317m0873            VIA   -    MD0100PA00X+114650Y+165561X0200Y         S0      
317m0873            VIA   -    MD0100PA00X+113182Y+160059X0200Y         S0      
327m0874            U6012 -FJ16       A01X+157957Y+155989X0100Y0130R090 S1      
327m0874            R613  -2          A01X+156859Y+155963X0120Y0150R180 S1      
327m0874            R634  -1   M      A01X+157154Y+155963X0120Y0150R090 S1      
327m0875            U6012 -FF18       A01X+158161Y+155871X0120Y         S1      
327m0875            R614  -2          A01X+156859Y+155643X0120Y0150R180 S1      
327m0875            R631  -1   M      A01X+157154Y+155643X0120Y0150R270 S1      
327m0876            R611  -1          A01X+130232Y+155963X0120Y0150     S1      
317m0876            VIA   -    MD0100PA00X+129847Y+155973X0200Y         S0      
327m0876            U314  -19         A01X+113487Y+164399X0100Y0220R090 S1      
317m0876            VIA   -    MD0100PA00X+114108Y+164327X0200Y         S0      
317m0876            VIA   -    MD0100PA00X+114292Y+158671X0200Y         S0      
327m0877            R612  -1          A01X+130232Y+155643X0120Y0150     S1      
317m0877            VIA   -    MD0100PA00X+129847Y+155633X0200Y         S0      
327m0877            U314  -20         A01X+113487Y+164596X0100Y0220R090 S1      
317m0877            VIA   -    MD0100PA00X+114108Y+164667X0200Y         S0      
317m0877            VIA   -    MD0100PA00X+114292Y+158331X0200Y         S0      
327m0878            U6011 -FJ16       A01X+131539Y+155989X0100Y0130R090 S1      
327m0878            R611  -2          A01X+130442Y+155963X0120Y0150R180 S1      
327m0878            R630  -1   M      A01X+130737Y+155963X0120Y0150R090 S1      
327m0879            U6011 -FF18       A01X+131744Y+155871X0120Y         S1      
327m0879            R612  -2          A01X+130442Y+155643X0120Y0150R180 S1      
327m0879            R629  -1   M      A01X+130737Y+155643X0120Y0150R270 S1      
317m0880            VIA   -    MD0100PA00X+111385Y+160455X0200Y         S0      
327m0880            U314  -13         A01X+112650Y+163759X0100Y0220     S1      
327m0880            R595  -1          A01X+117426Y+155963X0120Y0150     S1      
317m0880            VIA   -    MD0100PA00X+117040Y+155973X0200Y         S0      
327m0881            R596  -1          A01X+117426Y+155643X0120Y0150     S1      
317m0881            VIA   -    MD0100PA00X+117040Y+155633X0200Y         S0      
317m0881            VIA   -    MD0100PA00X+111725Y+160455X0200Y         S0      
327m0881            U314  -14         A01X+112847Y+163759X0100Y0220     S1      
327m0882            U6010 -FJ16       A01X+118733Y+155989X0100Y0130R090 S1      
327m0882            R595  -2          A01X+117636Y+155963X0120Y0150R180 S1      
327m0882            R624  -1   M      A01X+117931Y+155963X0120Y0150R090 S1      
327m0883            U6010 -FF18       A01X+118938Y+155871X0120Y         S1      
327m0883            R596  -2          A01X+117636Y+155643X0120Y0150R180 S1      
327m0883            R623  -1   M      A01X+117931Y+155643X0120Y0150R270 S1      
327m0884            R8350 -1          A01X+047850Y+126492X0198Y0197R090 S1      
327m0884            U26   -DJ53       A01X+038759Y+116414X0177Y    R180 S1      
327m0885            R8351 -1          A01X+047450Y+126492X0198Y0197R090 S1      
327m0885            U26   -DJ54       A01X+038389Y+116414X0177Y    R180 S1      
327m0886            VIA   -    M      A01X+047714Y+137168X0160Y0041R090 S1      
327m0886            R8350 -2          A01X+047850Y+126808X0198Y0197R090 S1      
327m0886            U10   -3          A01X+042125Y+162208X0100Y0220R180 S1      
317m0886            VIA   -    MD0100PA00X+042076Y+162770X0200Y         S0      
317m0886            VIA   -    MD0100PA00X+054625Y+145751X0200Y         S0      
327m0887            VIA   -    M      A01X+047586Y+136118X0160Y0041R090 S1      
327m0887            R8351 -2          A01X+047450Y+126808X0198Y0197R090 S1      
327m0887            U10   -4          A01X+041928Y+162208X0100Y0220R180 S1      
317m0887            VIA   -    MD0100PA00X+041736Y+162770X0200Y         S0      
317m0887            VIA   -    MD0100PA00X+054625Y+145411X0200Y         S0      
327m0888            R8305 -1          A01X+142121Y+125879X0198Y0197R090 S1      
327m0888            U25   -DJ53       A01X+136373Y+116413X0177Y    R180 S1      
327m0889            R8306 -1          A01X+141771Y+125879X0198Y0197R090 S1      
327m0889            U25   -DJ54       A01X+136003Y+116413X0177Y    R180 S1      
327m0890            R8305 -2          A01X+142121Y+126194X0198Y0197R090 S1      
327m0890            VIA   -    M      A01X+117874Y+146640X0160Y0041R180 S1      
317m0890            VIA   -    MD0100PA00X+109096Y+164993X0200Y         S0      
317m0890            VIA   -    MD0100PA00X+111510Y+147227X0200Y         S0      
327m0890            U314  -3          A01X+111617Y+164989X0100Y0220R270 S1      
327m0891            R8306 -2          A01X+141771Y+126194X0198Y0197R090 S1      
327m0891            VIA   -    M      A01X+118924Y+146513X0160Y0041R180 S1      
317m0891            VIA   -    MD0100PA00X+109096Y+164653X0200Y         S0      
317m0891            VIA   -    MD0100PA00X+111510Y+146887X0200Y         S0      
327m0891            U314  -4          A01X+111617Y+164792X0100Y0220R270 S1      
327m0892            PC6507-2          A01X+094242Y+116291X0198Y0197R090 S1      
327m0892            PL6501-1          A01X+095650Y+117524X1300Y1692R090 S1      
327m0892            PU6500-20         A01X+095934Y+115379X0120Y0790     S1      
327m0893            PR6800-1          A01X+094949Y+115983X0198Y0197R180 S1      
327m0893            PU6500-1          A01X+095284Y+115536X0354Y0118     S1      
327m0894            PC6902-1          A01X+095150Y+113020X0400Y0500     S1      
327m0894            PC6901-1          A01X+095830Y+113140X0400Y0500R180 S1      
327m0894            PC6900-1          A01X+095150Y+112320X0400Y0500     S1      
327m0894            PC6505-1          A01X+095665Y+116117X0198Y0197R180 S1      
327m0894            PU6500-21         A01X+095697Y+115379X0120Y0790     S1      
327m0894            PU6500-10         A01X+095697Y+114355X0120Y0790     S1      
327m0894            PC6501-1          A01X+095842Y+112453X0400Y0500R180 S1      
327m0894            PC6802-1          A01X+095842Y+111053X0400Y0500R180 S1      
327m0894            PC6504-1          A01X+095150Y+110920X0400Y0500     S1      
327m0894            PC6503-1          A01X+095150Y+111620X0400Y0500     S1      
327m0894            PC6502-1          A01X+095842Y+111753X0400Y0500R180 S1      
327m0894            PC6800-1          A01X+096658Y+109226X0630Y1380R270 S1      
327m0894            PL6500-2          A01X+097104Y+106798X0420Y0990R180 S1      
327m0895            VIA   -    M      A18X+094343Y+114070X0260Y         S2      
327m0895            R6505 -2          A18X+093981Y+114506X0198Y0197R180 S2      
327m0895            R6506 -1   M      A18X+094673Y+113963X0198Y0197R090 S2      
327m0895            PU6500-9          A01X+095264Y+114198X0120Y0320R090 S1      
317m0895            VIA   -    MD0100PA00X+094951Y+114056X0200Y         S0      
327m0896            VIA   -    M      A18X+095576Y+114472X0260Y         S2      
327m0896            PC6506-1          A01X+096947Y+115565X0198Y0197R270 S1      
327m0896            PR6501-2          A18X+095251Y+114147X0198Y0197R270 S2      
327m0896            PU6500-19         A01X+096367Y+115536X0120Y0320R270 S1      
317m0896            VIA   -    MD0100PA00X+096680Y+115566X0200Y    R270 S0      
327m0897            PC6518-1          A01X+094463Y+114907X0198Y0197R180 S1      
327m0897            PU6500-5          A01X+095264Y+114867X0070Y0320R090 S1      
327m0898            PR6500-2          A18X+094460Y+114395X0198Y0197     S2      
327m0898            PU6500-4          A01X+095264Y+115024X0070Y0320R090 S1      
317m0898            VIA   -    M      A01X+094730Y+115077X0200Y         S2      
017m0898            VIA   -    M      A18X+094730Y+115077X0260Y         S2      
017m0898                  -    MD0100PA00X+094730Y+115077                       
327m0899            VIA   -    M      A01X+094726Y+114346X0160Y0041R034 S1      
327m0899            PC6515-1          A01X+093639Y+114150X0198Y0197R090 S1      
327m0899            PR6507-1   M      A01X+094446Y+114150X0198Y0197R090 S1      
327m0899            PR6505-1   M      A01X+094039Y+114150X0198Y0197R090 S1      
327m0899            PU6500-7          A01X+095264Y+114552X0070Y0320R090 S1      
317m0900            VIA   -    MD0100PA00X+070460Y+073229X0200Y         S0      
317m0900            VIA   -    MD0100PA00X+069876Y+067639X0200Y         S0      
327m0900            R6850 -1          A01X+067471Y+050490X0198Y0197     S1      
317m0900            VIA   -    MD0100PA00X+067270Y+050691X0200Y         S0      
327m0900            C6757 -1   M      A01X+094422Y+113784X0198Y0197R180 S1      
327m0900            PU6500-8          A01X+095264Y+114394X0070Y0320R090 S1      
317m0900            VIA   -    M      A01X+093715Y+113434X0200Y         S2      
017m0900            VIA   -    M      A18X+093715Y+113434X0260Y         S2      
017m0900                  -    MD0100PA00X+093715Y+113434                       
327m0901            PR6502-1          A01X+094463Y+115350X0198Y0197R180 S1      
327m0901            PU6500-3          A01X+095264Y+115182X0070Y0320R090 S1      
327m0902            R6808 -1          A01X+126915Y+158641X0120Y0150R090 S1      
317m0902            VIA   -    MD0100PA00X+126931Y+158317X0200Y         S0      
327m0902            R1024 -1          A01X+131935Y+159504X0120Y0150R270 S1      
327m0902            R1040 -1          A01X+139796Y+159165X0120Y0150R270 S1      
327m0902            R1039 -1          A01X+131507Y+159089X0120Y0150R270 S1      
327m0902            R1023 -1          A01X+131187Y+159089X0120Y0150R270 S1      
327m0902            R1473 -1          A01X+139340Y+160475X0120Y0150R090 S1      
327m0902            R1471 -1          A01X+138700Y+160475X0120Y0150R090 S1      
327m0902            R1472 -1          A01X+139020Y+160475X0120Y0150R090 S1      
327m0902            R1470 -1          A01X+138380Y+160475X0120Y0150R090 S1      
317m0902            VIA   -    MD0100PA00X+139703Y+159406X0200Y         S0      
327m0902            R1050 -1          A01X+168374Y+155963X0180Y0200     S1      
327m0902            R1093 -1   M      A01X+155182Y+154522X0180Y0200     S1      
327m0902            R1008 -1   M      A01X+141571Y+154522X0180Y0200     S1      
327m0902            R960  -1   M      A01X+128765Y+154522X0180Y0200     S1      
327m0902            C992  -1   M      A01X+155155Y+155284X0198Y0197R090 S1      
327m0902            C667  -1          A01X+169553Y+154834X0198Y0197R270 S1      
327m0902            C589  -1   M      A01X+141543Y+155284X0198Y0197R090 S1      
327m0902            C504  -1   M      A01X+128737Y+155284X0198Y0197R090 S1      
327m0902            PR6505-2          A01X+094039Y+114465X0198Y0197R090 S1      
327m0902            PC6515-2   M      A01X+093639Y+114465X0198Y0197R090 S1      
317m0902            VIA   -    MD0100PA00X+093639Y+114809X0200Y         S0      
317m0902            VIA   -    MD0100PA00X+097909Y+124192X0200Y         S0      
317m0902            VIA   -    MD0100PA00X+097909Y+123892X0200Y         S0      
317m0902            VIA   -    MD0100PA00X+097909Y+123292X0200Y         S0      
317m0902            VIA   -    MD0100PA00X+097909Y+123592X0200Y         S0      
317m0902            VIA   -    MD0100PA00X+096399Y+124192X0200Y         S0      
317m0902            VIA   -    M      A01X+097909Y+122992X0200Y         S2      
017m0902            VIA   -    M      A18X+097909Y+122992X0260Y         S2      
017m0902                  -    MD0100PA00X+097909Y+122992                       
317m0902            VIA   -    MD0100PA00X+096399Y+123594X0200Y         S0      
317m0902            VIA   -    MD0100PA00X+096399Y+123294X0200Y         S0      
317m0902            VIA   -    MD0100PA00X+096399Y+122994X0200Y         S0      
317m0902            VIA   -    M      A01X+096969Y+123592X0200Y         S2      
017m0902            VIA   -    M      A18X+096969Y+123592X0260Y         S2      
017m0902                  -    MD0100PA00X+096969Y+123592                       
317m0902            VIA   -    MD0100PA00X+096399Y+123892X0200Y         S0      
317m0902            VIA   -    MD0100PA00X+096969Y+123292X0200Y         S0      
317m0902            VIA   -    MD0100PA00X+096969Y+122992X0200Y         S0      
317m0902            VIA   -    MD0100PA00X+096991Y+122552X0200Y         S0      
317m0902            VIA   -    M      A01X+096691Y+122552X0200Y         S2      
017m0902            VIA   -    M      A18X+096691Y+122552X0260Y         S2      
017m0902                  -    MD0100PA00X+096691Y+122552                       
317m0902            VIA   -    MD0100PA00X+096691Y+121952X0200Y         S0      
317m0902            VIA   -    MD0100PA00X+096691Y+122252X0200Y         S0      
317m0902            VIA   -    MD0100PA00X+096991Y+122252X0200Y         S0      
317m0902            VIA   -    MD0100PA00X+096991Y+121952X0200Y         S0      
317m0902            VIA   -    MD0100PA00X+095589Y+124192X0200Y         S0      
317m0902            VIA   -    M      A01X+095596Y+122987X0200Y         S2      
017m0902            VIA   -    M      A18X+095596Y+122987X0260Y         S2      
017m0902                  -    MD0100PA00X+095596Y+122987                       
317m0902            VIA   -    MD0100PA00X+095589Y+123892X0200Y         S0      
317m0902            VIA   -    MD0100PA00X+095596Y+123587X0200Y         S0      
317m0902            VIA   -    MD0100PA00X+095596Y+123287X0200Y         S0      
317m0902            VIA   -    MD0100PA00X+094079Y+124192X0200Y         S0      
317m0902            VIA   -    MD0100PA00X+093589Y+122959X0200Y         S0      
317m0902            VIA   -    MD0100PA00X+093589Y+123259X0200Y         S0      
317m0902            VIA   -    MD0100PA00X+093589Y+123559X0200Y         S0      
317m0902            VIA   -    MD0100PA00X+094068Y+123576X0200Y         S0      
317m0902            VIA   -    MD0100PA00X+094068Y+123276X0200Y         S0      
317m0902            VIA   -    MD0100PA00X+094068Y+122976X0200Y         S0      
317m0902            VIA   -    M      A01X+094569Y+123592X0200Y         S2      
017m0902            VIA   -    M      A18X+094569Y+123592X0260Y         S2      
017m0902                  -    MD0100PA00X+094569Y+123592                       
317m0902            VIA   -    M      A01X+093591Y+123952X0200Y         S2      
017m0902            VIA   -    M      A18X+093591Y+123952X0260Y         S2      
017m0902                  -    MD0100PA00X+093591Y+123952                       
317m0902            VIA   -    MD0100PA00X+094079Y+123892X0200Y         S0      
317m0902            VIA   -    MD0100PA00X+094569Y+123292X0200Y         S0      
317m0902            VIA   -    MD0100PA00X+094569Y+122992X0200Y         S0      
317m0902            VIA   -    MD0100PA00X+094610Y+122552X0200Y         S0      
317m0902            VIA   -    MD0100PA00X+094310Y+122552X0200Y         S0      
317m0902            VIA   -    M      A01X+094610Y+121952X0200Y         S2      
017m0902            VIA   -    M      A18X+094610Y+121952X0260Y         S2      
017m0902                  -    MD0100PA00X+094610Y+121952                       
317m0902            VIA   -    MD0100PA00X+094610Y+122252X0200Y         S0      
317m0902            VIA   -    MD0100PA00X+094310Y+122252X0200Y         S0      
327m0902            PC6512-1          A18X+096801Y+124042X0400Y0500R090 S2      
327m0902            PC6509-1          A18X+097501Y+124042X0400Y0500R090 S2      
327m0902            PC6511-1          A18X+095181Y+124042X0400Y0500R090 S2      
327m0902            PC6508-1          A18X+095991Y+124042X0400Y0500R090 S2      
327m0902            PC6510-1          A18X+094481Y+124042X0400Y0500R090 S2      
327m0902            PC6514-1          A01X+093591Y+124234X0198Y0197R090 S1      
327m0902            PC6805-1          A01X+097441Y+123476X0630Y1190R180 S1      
327m0902            PC6513-1          A01X+095041Y+123476X0630Y1190R180 S1      
327m0902            PL6501-2          A01X+095650Y+121974X1300Y1692R090 S1      
317m0902            VIA   -    MD0100PA00X+094310Y+121952X0200Y         S0      
327m0902            L28   -1   M      A01X+141571Y+154912X0180Y0200     S1      
327m0902            L26   -1   M      A01X+128765Y+154912X0180Y0200     S1      
327m0902            L30   -1   M      A01X+155182Y+154912X0180Y0200     S1      
327m0902            L29   -1          A01X+168374Y+156353X0180Y0200     S1      
317m0902            VIA   -    MD0100PA00X+167077Y+168883X0200Y         S0      
327m0902            R1432 -1          A18X+167191Y+168656X0120Y0150R090 S2      
317m0902            VIA   -    MD0100PA00X+167434Y+167783X0200Y         S0      
327m0902            R1431 -1          A18X+167199Y+167894X0120Y0150R270 S2      
327m0902            R840  -1          A18X+164907Y+168031X0120Y0150R180 S2      
327m0902            R841  -1          A18X+164911Y+168344X0120Y0150R180 S2      
317m0902            VIA   -    MD0100PA00X+164688Y+168174X0200Y         S0      
327m0902            R1446 -1          A18X+120140Y+168540X0120Y0150R180 S2      
327m0902            R1445 -1          A18X+120140Y+167900X0120Y0150R180 S2      
327m0902            R1439 -1          A18X+120140Y+167580X0120Y0150R180 S2      
327m0902            R1438 -1          A18X+120140Y+168220X0120Y0150R180 S2      
317m0902            VIA   -    MD0100PA00X+119927Y+168302X0200Y         S0      
317m0902            VIA   -    MD0100PA00X+119775Y+168091X0200Y         S0      
317m0902            VIA   -    MD0100PA00X+119930Y+167552X0200Y         S0      
327m0902            R1411 -1          A18X+118536Y+168478X0120Y0150R090 S2      
327m0902            R835  -1          A18X+116195Y+167850X0120Y0150R180 S2      
317m0902            VIA   -    MD0100PA00X+115950Y+167900X0200Y         S0      
317m0902            VIA   -    MD0100PA00X+115970Y+167300X0200Y         S0      
327m0902            R834  -1          A18X+116195Y+167300X0120Y0150R180 S2      
317m0902            VIA   -    MD0100PA00X+166617Y+166769X0200Y         S0      
327m0902            C989  -1   M      A01X+166617Y+167015X0120Y0150     S1      
327m0902            U16   -8          A01X+166610Y+167593X0350Y0500R180 S1      
317m0902            VIA   -    MD0100PA00X+119031Y+166163X0200Y         S0      
327m0902            C7510 -1          A01X+119033Y+166418X0120Y0150R090 S1      
327m0902            U11   -8          A01X+118419Y+166216X0350Y0500R180 S1      
327m0902            R1410 -1          A18X+118715Y+167001X0120Y0150R270 S2      
327m0902            R1485 -1          A01X+167140Y+165895X0120Y0150R090 S1      
317m0902            VIA   -    MD0100PA00X+167116Y+165640X0200Y         S0      
317m0902            VIA   -    MD0100PA00X+167436Y+165640X0200Y         S0      
317m0902            VIA   -    MD0100PA00X+167756Y+165640X0200Y         S0      
317m0902            VIA   -    MD0100PA00X+168070Y+165631X0200Y         S0      
327m0902            R1483 -1          A01X+168100Y+165895X0120Y0150R090 S1      
327m0902            R1484 -1          A01X+167780Y+165895X0120Y0150R090 S1      
327m0902            R1482 -1          A01X+167460Y+165895X0120Y0150R090 S1      
317m0902            VIA   -    MD0100PA00X+091428Y+134755X0200Y         S0      
327m0902            R6762 -1          A18X+091200Y+134755X0120Y0150R090 S2      
317m0902            VIA   -    MD0100PA00X+091436Y+134073X0200Y         S0      
327m0902            R6763 -1          A18X+091200Y+134045X0120Y0150R270 S2      
327m0902            R6764 -1   M      A18X+091550Y+133855X0120Y0150R090 S2      
317m0902            VIA   -    MD0100PA00X+091800Y+133950X0200Y         S0      
327m0902            R6766 -1          A18X+091200Y+132955X0120Y0150R090 S2      
327m0902            R6765 -1   M      A18X+091550Y+133145X0120Y0150R270 S2      
317m0902            VIA   -    MD0100PA00X+091800Y+133050X0200Y         S0      
317m0902            VIA   -    MD0100PA00X+091446Y+132935X0200Y         S0      
317m0902            VIA   -    MD0100PA00X+091433Y+132270X0200Y         S0      
327m0902            R6767 -1          A18X+091200Y+132245X0120Y0150R270 S2      
327m0902            R6768 -1   M      A18X+091550Y+132055X0120Y0150R090 S2      
317m0902            VIA   -    MD0100PA00X+091800Y+132150X0200Y         S0      
327m0902            R6769 -1          A18X+091550Y+131345X0120Y0150R270 S2      
317m0902            VIA   -    MD0100PA00X+091800Y+131250X0200Y         S0      
327m0902            R1415 -1          A01X+116082Y+155402X0120Y0150R180 S1      
327m0902            R1418 -1          A01X+116152Y+154458X0120Y0150R180 S1      
327m0902            R1371 -1          A18X+100145Y+133716X0120Y0150R180 S2      
327m0902            R1375 -1          A18X+100145Y+132826X0120Y0150R180 S2      
327m0902            R1379 -1          A18X+100145Y+132384X0120Y0150R180 S2      
327m0902            R1382 -1          A18X+100145Y+131942X0120Y0150R180 S2      
327m0902            R1383 -1          A18X+100145Y+131500X0120Y0150R180 S2      
327m0902            R1367 -1          A18X+100145Y+134158X0120Y0150R180 S2      
327m0902            R1366 -1          A18X+100145Y+134600X0120Y0150R180 S2      
317m0902            VIA   -    MD0100PA00X+099935Y+133716X0200Y         S0      
317m0902            VIA   -    MD0100PA00X+099935Y+132826X0200Y         S0      
317m0902            VIA   -    MD0100PA00X+099935Y+132384X0200Y         S0      
317m0902            VIA   -    MD0100PA00X+099935Y+131942X0200Y         S0      
317m0902            VIA   -    MD0100PA00X+099935Y+131500X0200Y         S0      
317m0902            VIA   -    MD0100PA00X+099935Y+134158X0200Y         S0      
317m0902            VIA   -    MD0100PA00X+099935Y+134600X0200Y         S0      
327m0902            R1374 -1          A18X+100145Y+133274X0120Y0150R180 S2      
317m0902            VIA   -    MD0100PA00X+099935Y+133274X0200Y         S0      
327m0902            R838  -1          A18X+143929Y+166544X0120Y0150R180 S2      
327m0902            R839  -1   M      A18X+145098Y+167733X0120Y0150R090 S2      
327m0902            R1428 -1          A01X+143907Y+168927X0120Y0150     S1      
317m0902            VIA   -    MD0100PA00X+143590Y+169434X0200Y         S0      
327m0902            R1420 -1          A01X+143905Y+167954X0120Y0150     S1      
327m0902            R1476 -1          A01X+170095Y+160430X0120Y0150     S1      
327m0902            R1479 -1          A01X+170095Y+160740X0120Y0150     S1      
327m0902            R1478 -1          A01X+170095Y+160120X0120Y0150     S1      
327m0902            R1405 -1          A01X+170095Y+159810X0120Y0150     S1      
327m0902            R1477 -1          A01X+170095Y+159500X0120Y0150     S1      
317m0902            VIA   -    MD0100PA00X+114096Y+149193X0200Y    R180 S0      
317m0902            VIA   -    MD0100PA00X+114346Y+149193X0200Y    R180 S0      
317m0902            VIA   -    MD0100PA00X+114096Y+148943X0200Y    R180 S0      
317m0902            VIA   -    MD0100PA00X+114346Y+148943X0200Y    R180 S0      
317m0902            VIA   -    MD0100PA00X+115846Y+148943X0200Y    R180 S0      
317m0902            VIA   -    MD0100PA00X+115596Y+148943X0200Y    R180 S0      
317m0902            VIA   -    MD0100PA00X+115346Y+148943X0200Y    R180 S0      
317m0902            VIA   -    MD0100PA00X+115096Y+148943X0200Y    R180 S0      
317m0902            VIA   -    MD0100PA00X+114846Y+148943X0200Y    R180 S0      
317m0902            VIA   -    MD0100PA00X+114596Y+148943X0200Y    R180 S0      
317m0902            VIA   -    MD0100PA00X+115846Y+149193X0200Y    R180 S0      
317m0902            VIA   -    MD0100PA00X+115596Y+149193X0200Y    R180 S0      
317m0902            VIA   -    MD0100PA00X+115346Y+149193X0200Y    R180 S0      
317m0902            VIA   -    MD0100PA00X+115096Y+149193X0200Y    R180 S0      
317m0902            VIA   -    MD0100PA00X+114846Y+149193X0200Y    R180 S0      
317m0902            VIA   -    MD0100PA00X+114596Y+149193X0200Y    R180 S0      
327m0902            R1055 -1          A01X+169385Y+157974X0120Y0150R270 S1      
327m0902            R1057 -1          A01X+169065Y+157974X0120Y0150R270 S1      
317m0902            VIA   -    MD0100PA00X+141798Y+156868X0200Y         S0      
327m0902            R1397 -1          A01X+141702Y+157100X0120Y0150     S1      
317m0902            VIA   -    MD0100PA00X+156709Y+156360X0200Y         S0      
327m0902            R1413 -1          A01X+156825Y+156585X0120Y0150R180 S1      
317m0902            VIA   -    MD0100PA00X+130292Y+156360X0200Y         S0      
327m0902            R1369 -1          A01X+130408Y+156585X0120Y0150R180 S1      
327m0902            R1059 -1          A01X+168207Y+154134X0120Y0150R180 S1      
327m0902            R1101 -1          A01X+155250Y+153960X0120Y0150R180 S1      
327m0902            R968  -1          A01X+128832Y+153960X0120Y0150R180 S1      
327m0902            R1017 -1          A01X+141638Y+153960X0120Y0150R180 S1      
327m0902            C664  -1          A01X+116262Y+159326X0120Y0150R270 S1      
327m0902            U15   -8          A01X+115354Y+159445X0350Y0500R270 S1      
327m0902            R974  -1          A01X+116687Y+156565X0120Y0150R270 S1      
327m0902            R1065 -1          A01X+157605Y+159089X0120Y0150R270 S1      
327m0902            R1107 -1          A01X+144798Y+159089X0120Y0150R270 S1      
327m0902            R1122 -1          A01X+145118Y+159089X0120Y0150R270 S1      
317m0902            VIA   -    MD0100PA00X+144806Y+159306X0200Y         S0      
327m0902            C1057 -1   M      A18X+145605Y+167900X0120Y0150     S2      
327m0902            U17   -8          A18X+146211Y+167885X0350Y0500R090 S2      
317m0902            VIA   -    MD0100PA00X+144800Y+167600X0200Y         S0      
317m0902            VIA   -    MD0100PA00X+143631Y+166595X0200Y         S0      
327m0902            R1108 -1          A01X+145546Y+159504X0120Y0150R270 S1      
327m0902            R1123 -1          A01X+153407Y+159165X0120Y0150R270 S1      
327m0902            R1066 -1          A01X+158352Y+159504X0120Y0150R270 S1      
327m0902            R1081 -1          A01X+166213Y+159165X0120Y0150R270 S1      
317m0902            VIA   -    MD0100PA00X+165998Y+159293X0200Y         S0      
327m0902            R1080 -1          A01X+157925Y+159089X0120Y0150R270 S1      
317m0902            VIA   -    MD0100PA00X+168622Y+154999X0200Y    R180 S0      
317m0902            VIA   -    MD0100PA00X+168574Y+155258X0200Y    R180 S0      
327m0902            C665  -1          A01X+169007Y+154730X0400Y0500R270 S1      
327m0902            L18   -1          A01X+168221Y+154720X0440Y0540     S1      
317m0902            VIA   -    MD0100PA00X+168600Y+156152X0200Y    R180 S0      
317m0902            VIA   -    MD0100PA00X+168574Y+155758X0200Y    R180 S0      
317m0902            VIA   -    MD0100PA00X+168574Y+155508X0200Y    R180 S0      
327m0902            C672  -1          A01X+168808Y+155953X0198Y0197     S1      
327m0902            C669  -1          A01X+168808Y+156353X0198Y0197     S1      
327m0902            VIA   -           A18X+156135Y+154722X0260Y         S2      
327m0902            VIA   -           A18X+155769Y+154266X0260Y         S2      
327m0902            VIA   -           A18X+155756Y+155057X0260Y         S2      
327m0902            C994  -1          A18X+155972Y+155405X0198Y0197R270 S2      
327m0902            C997  -1          A18X+155572Y+155405X0198Y0197R270 S2      
317m0902            VIA   -    MD0100PA00X+155607Y+154508X0200Y    R180 S0      
317m0902            VIA   -    MD0100PA00X+155214Y+154247X0200Y    R180 S0      
317m0902            VIA   -    MD0100PA00X+155464Y+154247X0200Y    R180 S0      
317m0902            VIA   -    MD0100PA00X+155607Y+154758X0200Y    R180 S0      
317m0902            VIA   -    MD0100PA00X+154868Y+155444X0200Y         S0      
317m0902            VIA   -    MD0100PA00X+155155Y+155284X0200Y         S0      
327m0902            R1097 -1          A01X+155505Y+154975X0120Y0150R090 S1      
327m0902            R1099 -1          A01X+155825Y+154975X0120Y0150R090 S1      
327m0902            R1069 -1          A01X+156440Y+155064X0120Y0150     S1      
327m0902            R1077 -1          A01X+156340Y+154380X0120Y0150     S1      
317m0902            VIA   -    MD0100PA00X+155182Y+154522X0200Y    R180 S0      
327m0902            R1073 -1          A18X+156440Y+155104X0120Y0150R180 S2      
327m0902            R1075 -1          A18X+156440Y+154742X0120Y0150R180 S2      
327m0902            C990  -1   M      A18X+155018Y+155345X0400Y0500R090 S2      
327m0902            R1063 -1          A18X+156440Y+154380X0120Y0150R180 S2      
327m0902            L22   -1   M      A18X+155237Y+154708X0440Y0540R180 S2      
317m0902            VIA   -    MD0100PA00X+155182Y+154912X0200Y    R180 S0      
327m0902            R1111 -1          A01X+143634Y+155064X0120Y0150     S1      
327m0902            R1119 -1          A01X+143534Y+154380X0120Y0150     S1      
317m0902            VIA   -    MD0100PA00X+143174Y+155024X0200Y    R180 S0      
317m0902            VIA   -    MD0100PA00X+143074Y+154380X0200Y    R180 S0      
317m0902            VIA   -    MD0100PA00X+143324Y+154380X0200Y    R180 S0      
317m0902            VIA   -    MD0100PA00X+143424Y+155024X0200Y    R180 S0      
327m0902            R1105 -1          A18X+143634Y+154380X0120Y0150R180 S2      
327m0902            R1116 -1          A18X+143634Y+154742X0120Y0150R180 S2      
327m0902            R1114 -1          A18X+143634Y+155104X0120Y0150R180 S2      
327m0902            R1015 -1          A01X+142214Y+154975X0120Y0150R090 S1      
327m0902            R1013 -1          A01X+141894Y+154975X0120Y0150R090 S1      
317m0902            VIA   -    MD0100PA00X+141602Y+154247X0200Y    R180 S0      
317m0902            VIA   -    MD0100PA00X+141996Y+154758X0200Y    R180 S0      
317m0902            VIA   -    MD0100PA00X+141996Y+154508X0200Y    R180 S0      
317m0902            VIA   -    MD0100PA00X+141852Y+154247X0200Y    R180 S0      
327m0902            C591  -1          A18X+141961Y+155405X0198Y0197R270 S2      
327m0902            C596  -1          A18X+142361Y+155405X0198Y0197R270 S2      
327m0902            L13   -1   M      A18X+141626Y+154708X0440Y0540R180 S2      
317m0902            VIA   -    MD0100PA00X+141571Y+154912X0200Y    R180 S0      
317m0902            VIA   -    MD0100PA00X+141571Y+154522X0200Y    R180 S0      
327m0902            C587  -1   M      A18X+141407Y+155345X0400Y0500R090 S2      
317m0902            VIA   -    MD0100PA00X+141543Y+155284X0200Y         S0      
317m0902            VIA   -    MD0100PA00X+141257Y+155444X0200Y         S0      
317m0902            VIA   -    MD0100PA00X+128765Y+154912X0200Y    R180 S0      
327m0902            L11   -1   M      A18X+128820Y+154708X0440Y0540R180 S2      
327m0902            R1021 -1          A18X+130022Y+154380X0120Y0150R180 S2      
327m0902            C502  -1   M      A18X+128600Y+155345X0400Y0500R090 S2      
327m0902            R1032 -1          A18X+130022Y+154742X0120Y0150R180 S2      
327m0902            R1030 -1          A18X+130022Y+155104X0120Y0150R180 S2      
317m0902            VIA   -    MD0100PA00X+128765Y+154522X0200Y    R180 S0      
327m0902            R1034 -1          A01X+129922Y+154380X0120Y0150     S1      
327m0902            R1027 -1          A01X+130022Y+155064X0120Y0150     S1      
327m0902            R966  -1          A01X+129407Y+154975X0120Y0150R090 S1      
327m0902            R964  -1          A01X+129087Y+154975X0120Y0150R090 S1      
317m0902            VIA   -    MD0100PA00X+128737Y+155284X0200Y         S0      
317m0902            VIA   -    MD0100PA00X+128451Y+155444X0200Y         S0      
317m0902            VIA   -    MD0100PA00X+129190Y+154758X0200Y    R180 S0      
317m0902            VIA   -    MD0100PA00X+129046Y+154247X0200Y    R180 S0      
317m0902            VIA   -    MD0100PA00X+128796Y+154247X0200Y    R180 S0      
317m0902            VIA   -    MD0100PA00X+129190Y+154508X0200Y    R180 S0      
327m0902            C511  -1          A18X+129154Y+155405X0198Y0197R270 S2      
327m0902            C506  -1          A18X+129554Y+155405X0198Y0197R270 S2      
317m0902            VIA   -    MD0100PA00X+114104Y+153995X0200Y    R180 S0      
317m0902            VIA   -    MD0100PA00X+114354Y+153995X0200Y    R180 S0      
317m0902            VIA   -    MD0100PA00X+114604Y+153995X0200Y    R180 S0      
317m0902            VIA   -    MD0100PA00X+114854Y+153995X0200Y    R180 S0      
317m0902            VIA   -    MD0100PA00X+115104Y+153995X0200Y    R180 S0      
317m0902            VIA   -    MD0100PA00X+115354Y+153995X0200Y    R180 S0      
317m0902            VIA   -    MD0100PA00X+114104Y+153745X0200Y    R180 S0      
317m0902            VIA   -    MD0100PA00X+114354Y+153745X0200Y    R180 S0      
317m0902            VIA   -    MD0100PA00X+114604Y+153745X0200Y    R180 S0      
317m0902            VIA   -    MD0100PA00X+114854Y+153745X0200Y    R180 S0      
317m0902            VIA   -    MD0100PA00X+115104Y+153745X0200Y    R180 S0      
317m0902            VIA   -    MD0100PA00X+115354Y+153745X0200Y    R180 S0      
317m0902            VIA   -    MD0100PA00X+114104Y+153495X0200Y    R180 S0      
317m0902            VIA   -    MD0100PA00X+114354Y+153495X0200Y    R180 S0      
317m0902            VIA   -    MD0100PA00X+114604Y+153495X0200Y    R180 S0      
317m0902            VIA   -    MD0100PA00X+114854Y+153495X0200Y    R180 S0      
317m0902            VIA   -    MD0100PA00X+115104Y+153495X0200Y    R180 S0      
317m0902            VIA   -    MD0100PA00X+115354Y+153495X0200Y    R180 S0      
317m0902            VIA   -    MD0100PA00X+115354Y+154245X0200Y    R180 S0      
317m0902            VIA   -    MD0100PA00X+115104Y+154245X0200Y    R180 S0      
317m0902            VIA   -    MD0100PA00X+114854Y+154245X0200Y    R180 S0      
317m0902            VIA   -    MD0100PA00X+114604Y+154245X0200Y    R180 S0      
317m0902            VIA   -    MD0100PA00X+114354Y+154245X0200Y    R180 S0      
317m0902            VIA   -    MD0100PA00X+114104Y+154245X0200Y    R180 S0      
317m0902            VIA   -    MD0100PA00X+115354Y+154495X0200Y    R180 S0      
317m0902            VIA   -    MD0100PA00X+114104Y+154495X0200Y    R180 S0      
317m0902            VIA   -    MD0100PA00X+114354Y+154495X0200Y    R180 S0      
317m0902            VIA   -    MD0100PA00X+114604Y+154495X0200Y    R180 S0      
317m0902            VIA   -    MD0100PA00X+114854Y+154495X0200Y    R180 S0      
317m0902            VIA   -    MD0100PA00X+115104Y+154495X0200Y    R180 S0      
317m0902            VIA   -    MD0100PA00X+094150Y+127806X0200Y         S0      
327m0902            R1231 -1          A18X+093826Y+127806X0198Y0197     S2      
317m0902            VIA   -    MD0100PA00X+117006Y+155104X0200Y    R180 S0      
317m0902            VIA   -    MD0100PA00X+116906Y+154380X0200Y    R180 S0      
327m0902            R972  -1          A18X+117716Y+153964X0120Y0150R180 S2      
327m0902            R983  -1          A18X+117716Y+154914X0120Y0150R180 S2      
327m0902            R981  -1          A18X+117716Y+155554X0120Y0150R180 S2      
327m0902            R985  -1          A01X+117116Y+154380X0120Y0150     S1      
327m0902            R978  -1          A01X+117216Y+155104X0120Y0150     S1      
317m0902            VIA   -    MD0100PA00X+116453Y+156558X0200Y         S0      
327m0902            R975  -1          A01X+116687Y+157645X0120Y0150R270 S1      
327m0902            R998  -1          A01X+116687Y+156895X0120Y0150R090 S1      
327m0902            R836  -1          A01X+114873Y+156532X0120Y0150R180 S1      
317m0902            VIA   -    MD0100PA00X+114947Y+156899X0200Y         S0      
327m0902            R837  -1          A01X+114131Y+156531X0120Y0150     S1      
317m0902            VIA   -    MD0100PA00X+114066Y+156926X0200Y         S0      
327m0903            VIA   -    M      A18X+093066Y+110304X0260Y         S2      
327m0903            C6758 -1          A18X+093981Y+114106X0198Y0197     S2      
327m0903            R6506 -2   M      A18X+094673Y+113648X0198Y0197R090 S2      
317m0903            VIA   -    MD0100PA00X+078854Y+073441X0200Y         S0      
317m0903            VIA   -    MD0100PA00X+074611Y+044356X0180Y    R090 S0      
327m0903            U18   -T9         A01X+074458Y+044509X0160Y    R090 S1      
317m0903            VIA   -    MD0100PA00X+075007Y+064874X0200Y         S0      
327m0904            VIA   -    M      A01X+040600Y+013948X0300Y         S1      
327m0904            R6323 -1          A01X+041257Y+014430X0198Y0197     S1      
327m0904            R6325 -1          A01X+040063Y+014115X0198Y0197R090 S1      
327SW_P3V3_EN_R     R490  -2   M      A01X+080958Y+051600X0198Y0197     S1      
327SW_P3V3_EN_R     R487  -2          A01X+080958Y+051200X0198Y0197     S1      
327SW_P3V3_EN_R     VIA   -    M      A01X+081119Y+052400X0300Y         S1      
327SW_P3V3_EN_R     Q3    -2          A01X+082000Y+052076X0170Y0200R180 S1      
327SW_P3V3_EN_N     R554  -2          A01X+081158Y+053450X0198Y0197     S1      
327SW_P3V3_EN_N     Q3    -5          A01X+082000Y+052824X0170Y0200R180 S1      
327SW_P3V3_EN_N     VIA   -    M      A01X+081744Y+053300X0300Y         S1      
327SW_P3V3_EN_N     Q3    -6          A01X+081744Y+052824X0170Y0200R180 S1      
327m0905            C29   -1   M      A01X+082450Y+050842X0198Y0197R090 S1      
327m0905            R569  -1          A01X+082050Y+050842X0198Y0197R090 S1      
327m0905            R568  -2   M      A01X+083100Y+050842X0198Y0197R270 S1      
317m0905            VIA   -    M      A01X+083834Y+051461X0200Y         S2      
017m0905            VIA   -    M      A18X+083834Y+051461X0260Y         S2      
017m0905                  -    MD0100PA00X+083834Y+051461                       
317m0905            VIA   -    MD0100PA00X+098281Y+049861X0200Y         S0      
327m0905            Q56   -4          A01X+173057Y+028686X0280Y0460R180 S1      
317m0905            VIA   -    MD0100PA00X+172349Y+029307X0200Y         S0      
317m0905            VIA   -    MD0100PA00X+098035Y+035353X0200Y         S0      
327SW_P3V3_EN_ISO   R569  -2          A01X+082050Y+051158X0198Y0197R090 S1      
327SW_P3V3_EN_ISO   VIA   -    M      A01X+082050Y+051532X0300Y         S1      
327SW_P3V3_EN_ISO   Q3    -3          A01X+082256Y+052076X0170Y0200R180 S1      
327PWRGD_P5V_R_N    R494  -1   M      A01X+065600Y+051308X0198Y0197R270 S1      
327PWRGD_P5V_R_N    R492  -2          A01X+065600Y+051792X0198Y0197R270 S1      
327PWRGD_P5V_R_N    VIA   -    M      A01X+065191Y+051409X0300Y         S1      
327PWRGD_P5V_R_N    Q1    -6          A01X+064698Y+051260X0170Y0200R090 S1      
327PWRGD_P5V_R2     R439  -2          A01X+064292Y+048800X0198Y0197R180 S1      
327PWRGD_P5V_R2     R552  -2   M      A01X+063424Y+050746X0198Y0197R270 S1      
327PWRGD_P5V_R2     Q1    -3          A01X+063950Y+050748X0170Y0200R090 S1      
327PWRGD_P5V_R2     VIA   -    M      A01X+063752Y+050198X0300Y         S1      
327PWRGD_P5V_R1     R482  -2          A01X+064692Y+051950X0198Y0197R180 S1      
327PWRGD_P5V_R1     Q1    -2          A01X+063950Y+051004X0170Y0200R090 S1      
327PWRGD_P5V_R1     VIA   -    M      A01X+064331Y+051875X0300Y         S1      
327PWRGD_P5V_R      R479  -2   M      A01X+066542Y+053350X0198Y0197R180 S1      
327PWRGD_P5V_R      R480  -1   M      A01X+066542Y+052950X0198Y0197     S1      
327PWRGD_P5V_R      R490  -1          A01X+080642Y+051600X0198Y0197     S1      
327PWRGD_P5V_R      R482  -1          A01X+065008Y+051950X0198Y0197R180 S1      
317PWRGD_P5V_R      VIA   -    M      A01X+080050Y+054050X0200Y         S2      
017PWRGD_P5V_R      VIA   -    M      A18X+080050Y+054050X0260Y         S2      
017PWRGD_P5V_R            -    MD0100PA00X+080050Y+054050                       
317PWRGD_P5V_R      VIA   -    MD0100PA00X+066542Y+053700X0200Y         S0      
327PWRGD_P5V_R      U100  -1   M      A01X+066338Y+052374X0320Y0400R270 S1      
327PWRGD_P5V_N      R494  -2          A01X+065600Y+050992X0198Y0197R270 S1      
327PWRGD_P5V_N      Q1    -5          A01X+064698Y+051004X0170Y0200R090 S1      
327PWRGD_P5V_N      VIA   -    M      A01X+065191Y+050793X0300Y         S1      
327PWRGD_P5V        R439  -1          A01X+064608Y+048800X0198Y0197R180 S1      
327PWRGD_P5V        U18   -A16        A01X+069733Y+046714X0160Y    R090 S1      
317PWRGD_P5V        VIA   -    MD0100PA00X+069580Y+046867X0180Y    R090 S2      
317PWRGD_P5V        VIA   -    MD0100PA00X+064950Y+049026X0200Y         S0      
327m0906            R6500 -1          A01X+043950Y+049342X0198Y0197R090 S1      
327m0906            R6501 -1   M      A01X+043950Y+048958X0198Y0197R270 S1      
327m0906            VIA   -    M      A01X+044769Y+048977X0300Y         S1      
327m0906            U6006 -2          A01X+045347Y+048976X0260Y0380R270 S1      
327m0906            R1491 -2   M      A01X+044350Y+048958X0198Y0197R090 S1      
327PU_U38_6         R6504 -2          A01X+039338Y+047227X0198Y0197R090 S1      
327PU_U38_6         U38   -6          A01X+038974Y+048240X0160Y0360     S1      
327PU_U38_6         VIA   -    M      A01X+039418Y+047673X0300Y         S1      
317m0907            VIA   -    MD0080PA01X+049642Y+153334X0160Y         S0      
317m0907            VIA   -    MD0100PA18X+057031Y+160238X0180Y         S0      
327m0907            C6743 -2          A18X+057041Y+160729X0120Y0150R090 S2      
327m0907            U6017 -BP7        A01X+049437Y+153334X0150Y         S1      
317m0908            VIA   -    MD0080PA01X+049170Y+153334X0160Y         S0      
317m0908            VIA   -    MD0100PA18X+055825Y+160238X0180Y         S0      
327m0908            C6741 -2          A18X+055835Y+160729X0120Y0150R090 S2      
327m0908            U6017 -CA7        A01X+048965Y+153334X0150Y         S1      
317m0909            VIA   -    MD0080PA01X+048697Y+153334X0160Y         S0      
317m0909            VIA   -    MD0100PA18X+054619Y+160238X0180Y         S0      
327m0909            C6739 -2          A18X+054629Y+160729X0120Y0150R090 S2      
327m0909            U6017 -CH7        A01X+048492Y+153334X0150Y         S1      
317m0910            VIA   -    MD0080PA01X+048225Y+153334X0160Y         S0      
317m0910            VIA   -    MD0100PA18X+053413Y+160238X0180Y         S0      
327m0910            C6737 -2          A18X+053423Y+160729X0120Y0150R090 S2      
327m0910            U6017 -CR7        A01X+048020Y+153334X0150Y         S1      
317m0911            VIA   -    MD0080PA01X+047752Y+153334X0160Y         S0      
317m0911            VIA   -    MD0100PA18X+052207Y+160238X0180Y         S0      
327m0911            C6735 -2          A18X+052217Y+160729X0120Y0150R090 S2      
327m0911            U6017 -DB7        A01X+047548Y+153334X0150Y         S1      
317m0912            VIA   -    MD0080PA01X+047280Y+153334X0160Y         S0      
317m0912            VIA   -    MD0100PA18X+051001Y+160238X0180Y         S0      
327m0912            C6733 -2          A18X+051011Y+160729X0120Y0150R090 S2      
327m0912            U6017 -DJ7        A01X+047075Y+153334X0150Y         S1      
317m0913            VIA   -    MD0080PA01X+046808Y+153334X0160Y         S0      
317m0913            VIA   -    MD0100PA18X+049795Y+160238X0180Y         S0      
327m0913            C6731 -2          A18X+049805Y+160729X0120Y0150R090 S2      
327m0913            U6017 -DT7        A01X+046603Y+153334X0150Y         S1      
317m0914            VIA   -    MD0080PA01X+046335Y+153334X0160Y         S0      
317m0914            VIA   -    MD0100PA18X+048589Y+160238X0180Y         S0      
327m0914            C6729 -2          A18X+048599Y+160729X0120Y0150R090 S2      
327m0914            U6017 -EC7        A01X+046130Y+153334X0150Y         S1      
317m0915            VIA   -    MD0080PA01X+045863Y+153334X0160Y         S0      
317m0915            VIA   -    MD0100PA18X+047383Y+160238X0180Y         S0      
327m0915            C6727 -2          A18X+047393Y+160729X0120Y0150R090 S2      
327m0915            U6017 -EK7        A01X+045658Y+153334X0150Y         S1      
317m0916            VIA   -    MD0100PA18X+064267Y+160238X0180Y         S0      
327m0916            C6755 -2          A18X+064277Y+160729X0120Y0150R090 S2      
327m0916            U6017 -M7         A01X+052272Y+153334X0150Y         S1      
317m0916            VIA   -    MD0080PA01X+052477Y+153334X0160Y         S0      
317m0917            VIA   -    MD0080PA01X+052004Y+153334X0160Y         S0      
317m0917            VIA   -    MD0100PA18X+063061Y+160238X0180Y         S0      
327m0917            C6753 -2          A18X+063071Y+160729X0120Y0150R090 S2      
327m0917            U6017 -W7         A01X+051799Y+153334X0150Y         S1      
317m0918            VIA   -    MD0080PA01X+051532Y+153334X0160Y         S0      
317m0918            VIA   -    MD0100PA18X+061855Y+160238X0180Y         S0      
327m0918            C6751 -2          A18X+061865Y+160729X0120Y0150R090 S2      
327m0918            U6017 -AF7        A01X+051327Y+153334X0150Y         S1      
317m0919            VIA   -    MD0080PA01X+051060Y+153334X0160Y         S0      
317m0919            VIA   -    MD0100PA18X+060649Y+160238X0180Y         S0      
327m0919            C6749 -2          A18X+060659Y+160729X0120Y0150R090 S2      
327m0919            U6017 -AN7        A01X+050854Y+153334X0150Y         S1      
317m0920            VIA   -    MD0080PA01X+050587Y+153334X0160Y         S0      
317m0920            VIA   -    MD0100PA18X+059443Y+160238X0180Y         S0      
327m0920            C6747 -2          A18X+059453Y+160729X0120Y0150R090 S2      
327m0920            U6017 -AY7        A01X+050382Y+153334X0150Y         S1      
317m0921            VIA   -    MD0080PA01X+050115Y+153334X0160Y         S0      
317m0921            VIA   -    MD0100PA18X+058237Y+160238X0180Y         S0      
327m0921            C6745 -2          A18X+058247Y+160729X0120Y0150R090 S2      
327m0921            U6017 -BG7        A01X+049910Y+153334X0150Y         S1      
317m0922            VIA   -    MD0080PA01X+045390Y+153334X0160Y         S0      
317m0922            VIA   -    MD0100PA18X+046177Y+160238X0180Y         S0      
327m0922            C6725 -2          A18X+046187Y+160729X0120Y0150R090 S2      
327m0922            U6017 -EU7        A01X+045185Y+153334X0150Y         S1      
317m0923            VIA   -    MD0080PA01X+049485Y+153061X0160Y         S0      
317m0923            VIA   -    MD0100PA18X+056691Y+160238X0180Y         S0      
327m0923            C6744 -2          A18X+056681Y+160729X0120Y0150R090 S2      
327m0923            U6017 -BT10       A01X+049280Y+153061X0150Y         S1      
317m0924            VIA   -    MD0080PA01X+049012Y+153061X0160Y         S0      
317m0924            VIA   -    MD0100PA18X+055485Y+160238X0180Y         S0      
327m0924            C6742 -2          A18X+055475Y+160729X0120Y0150R090 S2      
327m0924            U6017 -CC10       A01X+048807Y+153061X0150Y         S1      
317m0925            VIA   -    MD0080PA01X+048540Y+153061X0160Y         S0      
317m0925            VIA   -    MD0100PA18X+054279Y+160238X0180Y         S0      
327m0925            C6740 -2          A18X+054269Y+160729X0120Y0150R090 S2      
327m0925            U6017 -CK10       A01X+048335Y+153061X0150Y         S1      
317m0926            VIA   -    MD0080PA01X+048067Y+153061X0160Y         S0      
317m0926            VIA   -    MD0100PA18X+053073Y+160238X0180Y         S0      
327m0926            C6738 -2          A18X+053063Y+160729X0120Y0150R090 S2      
327m0926            U6017 -CU10       A01X+047862Y+153061X0150Y         S1      
317m0927            VIA   -    MD0080PA01X+047595Y+153061X0160Y         S0      
317m0927            VIA   -    MD0100PA18X+051867Y+160238X0180Y         S0      
327m0927            C6736 -2          A18X+051857Y+160729X0120Y0150R090 S2      
327m0927            U6017 -DD10       A01X+047390Y+153061X0150Y         S1      
317m0928            VIA   -    MD0080PA01X+047122Y+153061X0160Y         S0      
317m0928            VIA   -    MD0100PA18X+050661Y+160238X0180Y         S0      
327m0928            C6734 -2          A18X+050651Y+160729X0120Y0150R090 S2      
327m0928            U6017 -DL10       A01X+046918Y+153061X0150Y         S1      
317m0929            VIA   -    MD0080PA01X+046650Y+153061X0160Y         S0      
317m0929            VIA   -    MD0100PA18X+049455Y+160238X0180Y         S0      
327m0929            C6732 -2          A18X+049445Y+160729X0120Y0150R090 S2      
327m0929            U6017 -DV10       A01X+046445Y+153061X0150Y         S1      
317m0930            VIA   -    MD0080PA01X+046178Y+153061X0160Y         S0      
317m0930            VIA   -    MD0100PA18X+048249Y+160238X0180Y         S0      
327m0930            C6730 -2          A18X+048239Y+160729X0120Y0150R090 S2      
327m0930            U6017 -EE10       A01X+045973Y+153061X0150Y         S1      
317m0931            VIA   -    MD0080PA01X+045705Y+153061X0160Y         S0      
317m0931            VIA   -    MD0100PA18X+047043Y+160238X0180Y         S0      
327m0931            C6728 -2          A18X+047033Y+160729X0120Y0150R090 S2      
327m0931            U6017 -EM10       A01X+045500Y+153061X0150Y         S1      
317m0932            VIA   -    MD0100PA18X+063927Y+160238X0180Y         S0      
327m0932            C6756 -2          A18X+063917Y+160729X0120Y0150R090 S2      
327m0932            U6017 -P10        A01X+052114Y+153061X0150Y         S1      
317m0932            VIA   -    MD0080PA01X+052319Y+153061X0160Y         S0      
317m0933            VIA   -    MD0080PA01X+051847Y+153061X0160Y         S0      
317m0933            VIA   -    MD0100PA18X+062721Y+160238X0180Y         S0      
327m0933            C6754 -2          A18X+062711Y+160729X0120Y0150R090 S2      
327m0933            U6017 -AA10       A01X+051642Y+153061X0150Y         S1      
317m0934            VIA   -    MD0080PA01X+051374Y+153061X0160Y         S0      
317m0934            VIA   -    MD0100PA18X+061515Y+160238X0180Y         S0      
327m0934            C6752 -2          A18X+061505Y+160729X0120Y0150R090 S2      
327m0934            U6017 -AH10       A01X+051170Y+153061X0150Y         S1      
317m0935            VIA   -    MD0080PA01X+050902Y+153061X0160Y         S0      
317m0935            VIA   -    MD0100PA18X+060309Y+160238X0180Y         S0      
327m0935            C6750 -2          A18X+060299Y+160729X0120Y0150R090 S2      
327m0935            U6017 -AR10       A01X+050697Y+153061X0150Y         S1      
317m0936            VIA   -    MD0080PA01X+050430Y+153061X0160Y         S0      
317m0936            VIA   -    MD0100PA18X+059103Y+160238X0180Y         S0      
327m0936            C6748 -2          A18X+059093Y+160729X0120Y0150R090 S2      
327m0936            U6017 -BB10       A01X+050225Y+153061X0150Y         S1      
317m0937            VIA   -    MD0080PA01X+049957Y+153061X0160Y         S0      
317m0937            VIA   -    MD0100PA18X+057897Y+160238X0180Y         S0      
327m0937            C6746 -2          A18X+057887Y+160729X0120Y0150R090 S2      
327m0937            U6017 -BJ10       A01X+049752Y+153061X0150Y         S1      
317m0938            VIA   -    MD0080PA01X+045233Y+153061X0160Y         S0      
317m0938            VIA   -    MD0100PA18X+045837Y+160238X0180Y         S0      
327m0938            C6726 -2          A18X+045827Y+160729X0120Y0150R090 S2      
327m0938            U6017 -EW10       A01X+045028Y+153061X0150Y         S1      
317m0939            VIA   -    MD0100PA18X+057031Y+161429X0180Y         S0      
327m0939            C6743 -1          A18X+057041Y+160939X0120Y0150R090 S2      
317m0939            J109  -L2   D0142PA01X+056988Y+168146X0302Y    R180 S3      
317m0940            VIA   -    MD0100PA18X+055825Y+161429X0180Y         S0      
327m0940            C6741 -1          A18X+055835Y+160939X0120Y0150R090 S2      
317m0940            J109  -M1   D0142PA01X+056201Y+167752X0302Y    R180 S3      
317m0941            VIA   -    MD0100PA18X+054619Y+161429X0180Y         S0      
327m0941            C6739 -1          A18X+054629Y+160939X0120Y0150R090 S2      
317m0941            J110  -L8   D0142PA01X+055020Y+168146X0302Y    R180 S3      
317m0942            VIA   -    MD0100PA18X+053413Y+161429X0180Y         S0      
327m0942            C6737 -1          A18X+053423Y+160939X0120Y0150R090 S2      
317m0942            J110  -M7   D0142PA01X+054232Y+167752X0302Y    R180 S3      
317m0943            VIA   -    MD0100PA18X+052207Y+161429X0180Y         S0      
327m0943            C6735 -1          A18X+052217Y+160939X0120Y0150R090 S2      
317m0943            J110  -L6   D0142PA01X+053445Y+168146X0302Y    R180 S3      
317m0944            VIA   -    MD0100PA18X+051001Y+161429X0180Y         S0      
327m0944            C6733 -1          A18X+051011Y+160939X0120Y0150R090 S2      
317m0944            J110  -M5   D0142PA01X+052657Y+167752X0302Y    R180 S3      
317m0945            VIA   -    MD0100PA18X+049795Y+161429X0180Y         S0      
327m0945            C6731 -1          A18X+049805Y+160939X0120Y0150R090 S2      
317m0945            J110  -L4   D0142PA01X+051870Y+168146X0302Y    R180 S3      
317m0946            VIA   -    MD0100PA18X+048589Y+161429X0180Y         S0      
327m0946            C6729 -1          A18X+048599Y+160939X0120Y0150R090 S2      
317m0946            J110  -M3   D0142PA01X+051083Y+167752X0302Y    R180 S3      
317m0947            VIA   -    MD0100PA18X+047383Y+161429X0180Y         S0      
317m0947            J110  -L2   D0142PA01X+050295Y+168146X0302Y    R180 S3      
327m0947            C6727 -1          A18X+047393Y+160939X0120Y0150R090 S2      
317m0948            VIA   -    MD0100PA18X+064267Y+161429X0180Y         S0      
327m0948            C6755 -1          A18X+064277Y+160939X0120Y0150R090 S2      
317m0948            J109  -L8   D0142PA01X+061713Y+168146X0302Y    R180 S3      
317m0949            VIA   -    MD0100PA18X+063061Y+161429X0180Y         S0      
327m0949            C6753 -1          A18X+063071Y+160939X0120Y0150R090 S2      
317m0949            J109  -M7   D0142PA01X+060925Y+167752X0302Y    R180 S3      
317m0950            VIA   -    MD0100PA18X+061855Y+161429X0180Y         S0      
327m0950            C6751 -1          A18X+061865Y+160939X0120Y0150R090 S2      
317m0950            J109  -L6   D0142PA01X+060138Y+168146X0302Y    R180 S3      
317m0951            VIA   -    MD0100PA18X+060649Y+161429X0180Y         S0      
327m0951            C6749 -1          A18X+060659Y+160939X0120Y0150R090 S2      
317m0951            J109  -M5   D0142PA01X+059350Y+167752X0302Y    R180 S3      
317m0952            VIA   -    MD0100PA18X+059443Y+161429X0180Y         S0      
327m0952            C6747 -1          A18X+059453Y+160939X0120Y0150R090 S2      
317m0952            J109  -L4   D0142PA01X+058563Y+168146X0302Y    R180 S3      
317m0953            VIA   -    MD0100PA18X+058237Y+161429X0180Y         S0      
327m0953            C6745 -1          A18X+058247Y+160939X0120Y0150R090 S2      
317m0953            J109  -M3   D0142PA01X+057776Y+167752X0302Y    R180 S3      
317m0954            VIA   -    MD0100PA18X+046177Y+161429X0180Y         S0      
317m0954            J110  -M1   D0142PA01X+049508Y+167752X0302Y    R180 S3      
327m0954            C6725 -1          A18X+046187Y+160939X0120Y0150R090 S2      
317m0955            VIA   -    MD0100PA18X+056691Y+161429X0180Y         S0      
327m0955            C6744 -1          A18X+056681Y+160939X0120Y0150R090 S2      
317m0955            J109  -K2   D0142PA01X+056988Y+168618X0302Y    R180 S3      
317m0956            VIA   -    MD0100PA18X+055485Y+161429X0180Y         S0      
327m0956            C6742 -1          A18X+055475Y+160939X0120Y0150R090 S2      
317m0956            J109  -L1   D0142PA01X+056201Y+168224X0302Y    R180 S3      
317m0957            VIA   -    MD0100PA18X+054279Y+161429X0180Y         S0      
327m0957            C6740 -1          A18X+054269Y+160939X0120Y0150R090 S2      
317m0957            J110  -K8   D0142PA01X+055020Y+168618X0302Y    R180 S3      
317m0958            VIA   -    MD0100PA18X+053073Y+161429X0180Y         S0      
327m0958            C6738 -1          A18X+053063Y+160939X0120Y0150R090 S2      
317m0958            J110  -L7   D0142PA01X+054232Y+168224X0302Y    R180 S3      
317m0959            VIA   -    MD0100PA18X+051867Y+161429X0180Y         S0      
327m0959            C6736 -1          A18X+051857Y+160939X0120Y0150R090 S2      
317m0959            J110  -K6   D0142PA01X+053445Y+168618X0302Y    R180 S3      
317m0960            VIA   -    MD0100PA18X+050661Y+161429X0180Y         S0      
327m0960            C6734 -1          A18X+050651Y+160939X0120Y0150R090 S2      
317m0960            J110  -L5   D0142PA01X+052657Y+168224X0302Y    R180 S3      
317m0961            VIA   -    MD0100PA18X+049455Y+161429X0180Y         S0      
327m0961            C6732 -1          A18X+049445Y+160939X0120Y0150R090 S2      
317m0961            J110  -K4   D0142PA01X+051870Y+168618X0302Y    R180 S3      
317m0962            VIA   -    MD0100PA18X+048249Y+161429X0180Y         S0      
327m0962            C6730 -1          A18X+048239Y+160939X0120Y0150R090 S2      
317m0962            J110  -L3   D0142PA01X+051083Y+168224X0302Y    R180 S3      
317m0963            VIA   -    MD0100PA18X+047043Y+161429X0180Y         S0      
317m0963            J110  -K2   D0142PA01X+050295Y+168618X0302Y    R180 S3      
327m0963            C6728 -1          A18X+047033Y+160939X0120Y0150R090 S2      
317m0964            VIA   -    MD0100PA18X+063927Y+161429X0180Y         S0      
327m0964            C6756 -1          A18X+063917Y+160939X0120Y0150R090 S2      
317m0964            J109  -K8   D0142PA01X+061713Y+168618X0302Y    R180 S3      
317m0965            VIA   -    MD0100PA18X+062721Y+161429X0180Y         S0      
327m0965            C6754 -1          A18X+062711Y+160939X0120Y0150R090 S2      
317m0965            J109  -L7   D0142PA01X+060925Y+168224X0302Y    R180 S3      
317m0966            VIA   -    MD0100PA18X+061515Y+161429X0180Y         S0      
327m0966            C6752 -1          A18X+061505Y+160939X0120Y0150R090 S2      
317m0966            J109  -K6   D0142PA01X+060138Y+168618X0302Y    R180 S3      
317m0967            VIA   -    MD0100PA18X+060309Y+161429X0180Y         S0      
327m0967            C6750 -1          A18X+060299Y+160939X0120Y0150R090 S2      
317m0967            J109  -L5   D0142PA01X+059350Y+168224X0302Y    R180 S3      
317m0968            VIA   -    MD0100PA18X+059103Y+161429X0180Y         S0      
327m0968            C6748 -1          A18X+059093Y+160939X0120Y0150R090 S2      
317m0968            J109  -K4   D0142PA01X+058563Y+168618X0302Y    R180 S3      
317m0969            VIA   -    MD0100PA18X+057897Y+161429X0180Y         S0      
327m0969            C6746 -1          A18X+057887Y+160939X0120Y0150R090 S2      
317m0969            J109  -L3   D0142PA01X+057776Y+168224X0302Y    R180 S3      
317m0970            VIA   -    MD0100PA18X+045837Y+161429X0180Y         S0      
317m0970            J110  -L1   D0142PA01X+049508Y+168224X0302Y    R180 S3      
327m0970            C6726 -1          A18X+045827Y+160939X0120Y0150R090 S2      
317m0971            VIA   -    MD0100PA01X+049495Y+154840X0180Y         S0      
317m0971            J109  -F2   D0142PA01X+056988Y+170980X0302Y    R180 S3      
327m0971            U6017 -BU1        A01X+049220Y+154048X0100Y0130     S1      
317m0972            VIA   -    MD0100PA01X+049022Y+154840X0180Y         S0      
317m0972            J109  -G1   D0142PA01X+056201Y+170587X0302Y    R180 S3      
327m0972            U6017 -CD1        A01X+048747Y+154048X0100Y0130     S1      
317m0973            VIA   -    MD0100PA01X+048550Y+154840X0180Y         S0      
317m0973            J110  -F8   D0142PA01X+055020Y+170980X0302Y    R180 S3      
327m0973            U6017 -CL1        A01X+048275Y+154048X0100Y0130     S1      
317m0974            VIA   -    MD0100PA01X+048077Y+154840X0180Y         S0      
317m0974            J110  -G7   D0142PA01X+054232Y+170587X0302Y    R180 S3      
327m0974            U6017 -CV1        A01X+047802Y+154048X0100Y0130     S1      
317m0975            VIA   -    MD0100PA01X+047605Y+154840X0180Y         S0      
317m0975            J110  -F6   D0142PA01X+053445Y+170980X0302Y    R180 S3      
327m0975            U6017 -DE1        A01X+047330Y+154048X0100Y0130     S1      
317m0976            VIA   -    MD0100PA01X+047132Y+154840X0180Y         S0      
317m0976            J110  -G5   D0142PA01X+052657Y+170587X0302Y    R180 S3      
327m0976            U6017 -DM1        A01X+046858Y+154048X0100Y0130     S1      
317m0977            VIA   -    MD0100PA01X+046660Y+154840X0180Y         S0      
317m0977            J110  -F4   D0142PA01X+051870Y+170980X0302Y    R180 S3      
327m0977            U6017 -DW1        A01X+046385Y+154048X0100Y0130     S1      
317m0978            VIA   -    MD0100PA01X+046188Y+154840X0180Y         S0      
317m0978            J110  -G3   D0142PA01X+051083Y+170587X0302Y    R180 S3      
327m0978            U6017 -EF1        A01X+045913Y+154048X0100Y0130     S1      
317m0979            VIA   -    MD0100PA01X+045715Y+154840X0180Y         S0      
317m0979            J110  -F2   D0142PA01X+050295Y+170980X0302Y    R180 S3      
327m0979            U6017 -EN1        A01X+045440Y+154048X0100Y0130     S1      
317m0980            VIA   -    MD0100PA01X+052329Y+154840X0180Y         S0      
317m0980            J109  -F8   D0142PA01X+061713Y+170980X0302Y    R180 S3      
327m0980            U6017 -R1         A01X+052054Y+154048X0100Y0130     S1      
317m0981            VIA   -    MD0100PA01X+051857Y+154840X0180Y         S0      
317m0981            J109  -G7   D0142PA01X+060925Y+170587X0302Y    R180 S3      
327m0981            U6017 -AB1        A01X+051582Y+154048X0100Y0130     S1      
317m0982            VIA   -    MD0100PA01X+051384Y+154840X0180Y         S0      
317m0982            J109  -F6   D0142PA01X+060138Y+170980X0302Y    R180 S3      
327m0982            U6017 -AJ1        A01X+051109Y+154048X0100Y0130     S1      
317m0983            VIA   -    MD0100PA01X+050912Y+154840X0180Y         S0      
317m0983            J109  -G5   D0142PA01X+059350Y+170587X0302Y    R180 S3      
327m0983            U6017 -AT1        A01X+050637Y+154048X0100Y0130     S1      
317m0984            VIA   -    MD0100PA01X+050440Y+154840X0180Y         S0      
317m0984            J109  -F4   D0142PA01X+058563Y+170980X0302Y    R180 S3      
327m0984            U6017 -BC1        A01X+050164Y+154048X0100Y0130     S1      
317m0985            VIA   -    MD0100PA01X+049967Y+154840X0180Y         S0      
327m0985            U6017 -BK1        A01X+049692Y+154048X0100Y0130     S1      
317m0985            J109  -G3   D0142PA01X+057776Y+170587X0302Y    R180 S3      
317m0986            VIA   -    MD0100PA01X+045243Y+154840X0180Y         S0      
317m0986            J110  -G1   D0142PA01X+049508Y+170587X0302Y    R180 S3      
327m0986            U6017 -EY1        A01X+044968Y+154048X0100Y0130     S1      
317m0987            VIA   -    MD0100PA01X+049495Y+154500X0180Y         S0      
317m0987            J109  -E2   D0142PA01X+056988Y+171453X0302Y    R180 S3      
327m0987            U6017 -BR2        A01X+049338Y+153843X0120Y         S1      
317m0988            VIA   -    MD0100PA01X+049022Y+154500X0180Y         S0      
317m0988            J109  -F1   D0142PA01X+056201Y+171059X0302Y    R180 S3      
327m0988            U6017 -CB2        A01X+048865Y+153843X0120Y         S1      
317m0989            VIA   -    MD0100PA01X+048550Y+154500X0180Y         S0      
317m0989            J110  -E8   D0142PA01X+055020Y+171453X0302Y    R180 S3      
327m0989            U6017 -CJ2        A01X+048393Y+153843X0120Y         S1      
317m0990            VIA   -    MD0100PA01X+048077Y+154500X0180Y         S0      
317m0990            J110  -F7   D0142PA01X+054232Y+171059X0302Y    R180 S3      
327m0990            U6017 -CT2        A01X+047920Y+153843X0120Y         S1      
317m0991            VIA   -    MD0100PA01X+047605Y+154500X0180Y         S0      
317m0991            J110  -E6   D0142PA01X+053445Y+171453X0302Y    R180 S3      
327m0991            U6017 -DC2        A01X+047448Y+153843X0120Y         S1      
317m0992            VIA   -    MD0100PA01X+047132Y+154500X0180Y         S0      
317m0992            J110  -F5   D0142PA01X+052657Y+171059X0302Y    R180 S3      
327m0992            U6017 -DK2        A01X+046976Y+153843X0120Y         S1      
317m0993            VIA   -    MD0100PA01X+046660Y+154500X0180Y         S0      
317m0993            J110  -E4   D0142PA01X+051870Y+171453X0302Y    R180 S3      
327m0993            U6017 -DU2        A01X+046503Y+153843X0120Y         S1      
317m0994            VIA   -    MD0100PA01X+046188Y+154500X0180Y         S0      
317m0994            J110  -F3   D0142PA01X+051083Y+171059X0302Y    R180 S3      
327m0994            U6017 -ED2        A01X+046031Y+153843X0120Y         S1      
317m0995            VIA   -    MD0100PA01X+045715Y+154500X0180Y         S0      
317m0995            J110  -E2   D0142PA01X+050295Y+171453X0302Y    R180 S3      
327m0995            U6017 -EL2        A01X+045558Y+153843X0120Y         S1      
317m0996            VIA   -    MD0100PA01X+052329Y+154500X0180Y         S0      
317m0996            J109  -E8   D0142PA01X+061713Y+171453X0302Y    R180 S3      
327m0996            U6017 -N2         A01X+052172Y+153843X0120Y         S1      
317m0997            VIA   -    MD0100PA01X+051857Y+154500X0180Y         S0      
317m0997            J109  -F7   D0142PA01X+060925Y+171059X0302Y    R180 S3      
327m0997            U6017 -Y2         A01X+051700Y+153843X0120Y         S1      
317m0998            VIA   -    MD0100PA01X+051384Y+154500X0180Y         S0      
317m0998            J109  -E6   D0142PA01X+060138Y+171453X0302Y    R180 S3      
327m0998            U6017 -AG2        A01X+051228Y+153843X0120Y         S1      
317m0999            VIA   -    MD0100PA01X+050912Y+154500X0180Y         S0      
317m0999            J109  -F5   D0142PA01X+059350Y+171059X0302Y    R180 S3      
327m0999            U6017 -AP2        A01X+050755Y+153843X0120Y         S1      
317m1000            VIA   -    MD0100PA01X+050440Y+154500X0180Y         S0      
317m1000            J109  -E4   D0142PA01X+058563Y+171453X0302Y    R180 S3      
327m1000            U6017 -BA2        A01X+050283Y+153843X0120Y         S1      
317m1001            VIA   -    MD0100PA01X+049967Y+154500X0180Y         S0      
317m1001            J109  -F3   D0142PA01X+057776Y+171059X0302Y    R180 S3      
327m1001            U6017 -BH2        A01X+049810Y+153843X0120Y         S1      
317m1002            VIA   -    MD0100PA01X+045243Y+154500X0180Y         S0      
317m1002            J110  -F1   D0142PA01X+049508Y+171059X0302Y    R180 S3      
327m1002            U6017 -EV2        A01X+045086Y+153843X0120Y         S1      
317m1003            VIA   -    MD0080PA01X+062448Y+153334X0160Y         S0      
317m1003            VIA   -    MD0100PA01X+056428Y+159238X0180Y         S0      
327m1003            C6711 -2          A01X+056438Y+160729X0120Y0150R270 S1      
327m1003            U6016 -BP7        A01X+062243Y+153334X0150Y         S1      
317m1004            VIA   -    MD0080PA01X+061976Y+153334X0160Y         S0      
317m1004            VIA   -    MD0100PA01X+055222Y+159238X0180Y         S0      
327m1004            C6709 -2          A01X+055232Y+160729X0120Y0150R270 S1      
327m1004            U6016 -CA7        A01X+061771Y+153334X0150Y         S1      
317m1005            VIA   -    MD0080PA01X+061504Y+153334X0160Y         S0      
317m1005            VIA   -    MD0100PA01X+054016Y+159238X0180Y         S0      
327m1005            C6707 -2          A01X+054026Y+160729X0120Y0150R270 S1      
327m1005            U6016 -CH7        A01X+061298Y+153334X0150Y         S1      
317m1006            VIA   -    MD0080PA01X+061031Y+153334X0160Y         S0      
317m1006            VIA   -    MD0100PA01X+052810Y+159238X0180Y         S0      
327m1006            C6705 -2          A01X+052820Y+160729X0120Y0150R270 S1      
327m1006            U6016 -CR7        A01X+060826Y+153334X0150Y         S1      
317m1007            VIA   -    MD0080PA01X+060559Y+153334X0160Y         S0      
317m1007            VIA   -    MD0100PA01X+051604Y+159238X0180Y         S0      
327m1007            C6703 -2          A01X+051614Y+160729X0120Y0150R270 S1      
327m1007            U6016 -DB7        A01X+060354Y+153334X0150Y         S1      
317m1008            VIA   -    MD0080PA01X+060086Y+153334X0160Y         S0      
317m1008            VIA   -    MD0100PA01X+050398Y+159238X0180Y         S0      
327m1008            C6701 -2          A01X+050408Y+160729X0120Y0150R270 S1      
327m1008            U6016 -DJ7        A01X+059881Y+153334X0150Y         S1      
317m1009            VIA   -    MD0080PA01X+059614Y+153334X0160Y         S0      
317m1009            VIA   -    MD0100PA01X+049192Y+159238X0180Y         S0      
327m1009            C6699 -2          A01X+049202Y+160729X0120Y0150R270 S1      
327m1009            U6016 -DT7        A01X+059409Y+153334X0150Y         S1      
317m1010            VIA   -    MD0080PA01X+059141Y+153334X0160Y         S0      
317m1010            VIA   -    MD0100PA01X+047986Y+159238X0180Y         S0      
327m1010            C6697 -2          A01X+047996Y+160729X0120Y0150R270 S1      
327m1010            U6016 -EC7        A01X+058936Y+153334X0150Y         S1      
317m1011            VIA   -    MD0080PA01X+058669Y+153334X0160Y         S0      
317m1011            VIA   -    MD0100PA01X+046780Y+159238X0180Y         S0      
327m1011            C6695 -2          A01X+046790Y+160729X0120Y0150R270 S1      
327m1011            U6016 -EK7        A01X+058464Y+153334X0150Y         S1      
317m1012            VIA   -    MD0080PA01X+065283Y+153334X0160Y         S0      
317m1012            VIA   -    MD0100PA01X+063664Y+159238X0180Y         S0      
327m1012            C6723 -2          A01X+063674Y+160729X0120Y0150R270 S1      
327m1012            U6016 -M7         A01X+065078Y+153334X0150Y         S1      
317m1013            VIA   -    MD0080PA01X+064811Y+153334X0160Y         S0      
317m1013            VIA   -    MD0100PA01X+062458Y+159238X0180Y         S0      
327m1013            C6721 -2          A01X+062468Y+160729X0120Y0150R270 S1      
327m1013            U6016 -W7         A01X+064606Y+153334X0150Y         S1      
317m1014            VIA   -    MD0080PA01X+064338Y+153334X0160Y         S0      
317m1014            VIA   -    MD0100PA01X+061252Y+159238X0180Y         S0      
327m1014            C6719 -2          A01X+061262Y+160729X0120Y0150R270 S1      
327m1014            U6016 -AF7        A01X+064133Y+153334X0150Y         S1      
317m1015            VIA   -    MD0080PA01X+063866Y+153334X0160Y         S0      
317m1015            VIA   -    MD0100PA01X+060046Y+159238X0180Y         S0      
327m1015            U6016 -AN7        A01X+063661Y+153334X0150Y         S1      
327m1015            C6717 -2          A01X+060056Y+160729X0120Y0150R270 S1      
317m1016            VIA   -    MD0080PA01X+063393Y+153334X0160Y         S0      
317m1016            VIA   -    MD0100PA01X+058840Y+159238X0180Y         S0      
327m1016            C6715 -2          A01X+058850Y+160729X0120Y0150R270 S1      
327m1016            U6016 -AY7        A01X+063188Y+153334X0150Y         S1      
317m1017            VIA   -    MD0080PA01X+062921Y+153334X0160Y         S0      
317m1017            VIA   -    MD0100PA01X+057634Y+159238X0180Y         S0      
327m1017            U6016 -BG7        A01X+062716Y+153334X0150Y         S1      
327m1017            C6713 -2          A01X+057644Y+160729X0120Y0150R270 S1      
317m1018            VIA   -    MD0080PA01X+058196Y+153334X0160Y         S0      
317m1018            VIA   -    MD0100PA01X+045574Y+159238X0180Y         S0      
327m1018            C6693 -2          A01X+045584Y+160729X0120Y0150R270 S1      
327m1018            U6016 -EU7        A01X+057992Y+153334X0150Y         S1      
317m1019            VIA   -    MD0080PA01X+062291Y+153061X0160Y         S0      
317m1019            VIA   -    MD0100PA01X+056088Y+159238X0180Y         S0      
327m1019            C6712 -2          A01X+056078Y+160729X0120Y0150R270 S1      
327m1019            U6016 -BT10       A01X+062086Y+153061X0150Y         S1      
317m1020            VIA   -    MD0080PA01X+061818Y+153061X0160Y         S0      
317m1020            VIA   -    MD0100PA01X+054882Y+159238X0180Y         S0      
327m1020            C6710 -2          A01X+054872Y+160729X0120Y0150R270 S1      
327m1020            U6016 -CC10       A01X+061614Y+153061X0150Y         S1      
317m1021            VIA   -    MD0080PA01X+061346Y+153061X0160Y         S0      
317m1021            VIA   -    MD0100PA01X+053676Y+159238X0180Y         S0      
327m1021            C6708 -2          A01X+053666Y+160729X0120Y0150R270 S1      
327m1021            U6016 -CK10       A01X+061141Y+153061X0150Y         S1      
317m1022            VIA   -    MD0080PA01X+060874Y+153061X0160Y         S0      
317m1022            VIA   -    MD0100PA01X+052470Y+159238X0180Y         S0      
327m1022            C6706 -2          A01X+052460Y+160729X0120Y0150R270 S1      
327m1022            U6016 -CU10       A01X+060669Y+153061X0150Y         S1      
317m1023            VIA   -    MD0080PA01X+060401Y+153061X0160Y         S0      
317m1023            VIA   -    MD0100PA01X+051264Y+159238X0180Y         S0      
327m1023            C6704 -2          A01X+051254Y+160729X0120Y0150R270 S1      
327m1023            U6016 -DD10       A01X+060196Y+153061X0150Y         S1      
317m1024            VIA   -    MD0080PA01X+059929Y+153061X0160Y         S0      
317m1024            VIA   -    MD0100PA01X+050058Y+159238X0180Y         S0      
327m1024            C6702 -2          A01X+050048Y+160729X0120Y0150R270 S1      
327m1024            U6016 -DL10       A01X+059724Y+153061X0150Y         S1      
317m1025            VIA   -    MD0080PA01X+059456Y+153061X0160Y         S0      
317m1025            VIA   -    MD0100PA01X+048852Y+159238X0180Y         S0      
327m1025            C6700 -2          A01X+048842Y+160729X0120Y0150R270 S1      
327m1025            U6016 -DV10       A01X+059251Y+153061X0150Y         S1      
317m1026            VIA   -    MD0080PA01X+058984Y+153061X0160Y         S0      
317m1026            VIA   -    MD0100PA01X+047646Y+159238X0180Y         S0      
327m1026            C6698 -2          A01X+047636Y+160729X0120Y0150R270 S1      
327m1026            U6016 -EE10       A01X+058779Y+153061X0150Y         S1      
317m1027            VIA   -    MD0080PA01X+058511Y+153061X0160Y         S0      
317m1027            VIA   -    MD0100PA01X+046440Y+159238X0180Y         S0      
327m1027            C6696 -2          A01X+046430Y+160729X0120Y0150R270 S1      
327m1027            U6016 -EM10       A01X+058306Y+153061X0150Y         S1      
317m1028            VIA   -    MD0080PA01X+065126Y+153061X0160Y         S0      
317m1028            VIA   -    MD0100PA01X+063324Y+159238X0180Y         S0      
327m1028            C6724 -2          A01X+063314Y+160729X0120Y0150R270 S1      
327m1028            U6016 -P10        A01X+064921Y+153061X0150Y         S1      
317m1029            VIA   -    MD0080PA01X+064653Y+153061X0160Y         S0      
317m1029            VIA   -    MD0100PA01X+062118Y+159238X0180Y         S0      
327m1029            C6722 -2          A01X+062108Y+160729X0120Y0150R270 S1      
327m1029            U6016 -AA10       A01X+064448Y+153061X0150Y         S1      
317m1030            VIA   -    MD0080PA01X+064181Y+153061X0160Y         S0      
317m1030            VIA   -    MD0100PA01X+060912Y+159238X0180Y         S0      
327m1030            C6720 -2          A01X+060902Y+160729X0120Y0150R270 S1      
327m1030            U6016 -AH10       A01X+063976Y+153061X0150Y         S1      
317m1031            VIA   -    MD0080PA01X+063708Y+153061X0160Y         S0      
317m1031            VIA   -    MD0100PA01X+059706Y+159238X0180Y         S0      
327m1031            U6016 -AR10       A01X+063503Y+153061X0150Y         S1      
327m1031            C6718 -2          A01X+059696Y+160729X0120Y0150R270 S1      
317m1032            VIA   -    MD0080PA01X+063236Y+153061X0160Y         S0      
317m1032            VIA   -    MD0100PA01X+058500Y+159238X0180Y         S0      
327m1032            C6716 -2          A01X+058490Y+160729X0120Y0150R270 S1      
327m1032            U6016 -BB10       A01X+063031Y+153061X0150Y         S1      
317m1033            VIA   -    MD0080PA01X+062763Y+153061X0160Y         S0      
317m1033            VIA   -    MD0100PA01X+057294Y+159238X0180Y         S0      
327m1033            C6714 -2          A01X+057284Y+160729X0120Y0150R270 S1      
327m1033            U6016 -BJ10       A01X+062558Y+153061X0150Y         S1      
317m1034            VIA   -    MD0080PA01X+058039Y+153061X0160Y         S0      
317m1034            VIA   -    MD0100PA01X+045234Y+159238X0180Y         S0      
327m1034            C6694 -2          A01X+045224Y+160729X0120Y0150R270 S1      
327m1034            U6016 -EW10       A01X+057834Y+153061X0150Y         S1      
317m1035            VIA   -    MD0100PA01X+056428Y+162429X0180Y         S0      
317m1035            J109  -I2   D0142PA01X+056988Y+169563X0302Y    R180 S3      
327m1035            C6711 -1          A01X+056438Y+160939X0120Y0150R270 S1      
317m1036            VIA   -    MD0100PA01X+055222Y+162429X0180Y         S0      
317m1036            J109  -J1   D0142PA01X+056201Y+169169X0302Y    R180 S3      
327m1036            C6709 -1          A01X+055232Y+160939X0120Y0150R270 S1      
317m1037            VIA   -    MD0100PA01X+054016Y+162429X0180Y         S0      
317m1037            J110  -I8   D0142PA01X+055020Y+169563X0302Y    R180 S3      
327m1037            C6707 -1          A01X+054026Y+160939X0120Y0150R270 S1      
317m1038            VIA   -    MD0100PA01X+052810Y+162429X0180Y         S0      
317m1038            J110  -J7   D0142PA01X+054232Y+169169X0302Y    R180 S3      
327m1038            C6705 -1          A01X+052820Y+160939X0120Y0150R270 S1      
317m1039            VIA   -    MD0100PA01X+051604Y+162429X0180Y         S0      
317m1039            J110  -I6   D0142PA01X+053445Y+169563X0302Y    R180 S3      
327m1039            C6703 -1          A01X+051614Y+160939X0120Y0150R270 S1      
317m1040            VIA   -    MD0100PA01X+050398Y+162429X0180Y         S0      
317m1040            J110  -J5   D0142PA01X+052657Y+169169X0302Y    R180 S3      
327m1040            C6701 -1          A01X+050408Y+160939X0120Y0150R270 S1      
317m1041            VIA   -    MD0100PA01X+049192Y+162429X0180Y         S0      
317m1041            J110  -I4   D0142PA01X+051870Y+169563X0302Y    R180 S3      
327m1041            C6699 -1          A01X+049202Y+160939X0120Y0150R270 S1      
317m1042            VIA   -    MD0100PA01X+047986Y+162429X0180Y         S0      
317m1042            J110  -J3   D0142PA01X+051083Y+169169X0302Y    R180 S3      
327m1042            C6697 -1          A01X+047996Y+160939X0120Y0150R270 S1      
317m1043            VIA   -    MD0100PA01X+046780Y+162429X0180Y         S0      
317m1043            J110  -I2   D0142PA01X+050295Y+169563X0302Y    R180 S3      
327m1043            C6695 -1          A01X+046790Y+160939X0120Y0150R270 S1      
317m1044            VIA   -    MD0100PA01X+063664Y+162429X0180Y         S0      
317m1044            J109  -I8   D0142PA01X+061713Y+169563X0302Y    R180 S3      
327m1044            C6723 -1          A01X+063674Y+160939X0120Y0150R270 S1      
317m1045            VIA   -    MD0100PA01X+062458Y+162429X0180Y         S0      
317m1045            J109  -J7   D0142PA01X+060925Y+169169X0302Y    R180 S3      
327m1045            C6721 -1          A01X+062468Y+160939X0120Y0150R270 S1      
317m1046            VIA   -    MD0100PA01X+061252Y+162429X0180Y         S0      
317m1046            J109  -I6   D0142PA01X+060138Y+169563X0302Y    R180 S3      
327m1046            C6719 -1          A01X+061262Y+160939X0120Y0150R270 S1      
317m1047            VIA   -    MD0100PA01X+060046Y+162429X0180Y         S0      
317m1047            J109  -J5   D0142PA01X+059350Y+169169X0302Y    R180 S3      
327m1047            C6717 -1          A01X+060056Y+160939X0120Y0150R270 S1      
317m1048            VIA   -    MD0100PA01X+058840Y+162429X0180Y         S0      
317m1048            J109  -I4   D0142PA01X+058563Y+169563X0302Y    R180 S3      
327m1048            C6715 -1          A01X+058850Y+160939X0120Y0150R270 S1      
317m1049            VIA   -    MD0100PA01X+057634Y+162429X0180Y         S0      
317m1049            J109  -J3   D0142PA01X+057776Y+169169X0302Y    R180 S3      
327m1049            C6713 -1          A01X+057644Y+160939X0120Y0150R270 S1      
317m1050            VIA   -    MD0100PA01X+045574Y+162429X0180Y         S0      
317m1050            J110  -J1   D0142PA01X+049508Y+169169X0302Y    R180 S3      
327m1050            C6693 -1          A01X+045584Y+160939X0120Y0150R270 S1      
317m1051            VIA   -    MD0100PA01X+056088Y+162429X0180Y         S0      
317m1051            J109  -H2   D0142PA01X+056988Y+170035X0302Y    R180 S3      
327m1051            C6712 -1          A01X+056078Y+160939X0120Y0150R270 S1      
317m1052            VIA   -    MD0100PA01X+054882Y+162429X0180Y         S0      
317m1052            J109  -I1   D0142PA01X+056201Y+169642X0302Y    R180 S3      
327m1052            C6710 -1          A01X+054872Y+160939X0120Y0150R270 S1      
317m1053            VIA   -    MD0100PA01X+053676Y+162429X0180Y         S0      
317m1053            J110  -H8   D0142PA01X+055020Y+170035X0302Y    R180 S3      
327m1053            C6708 -1          A01X+053666Y+160939X0120Y0150R270 S1      
317m1054            VIA   -    MD0100PA01X+052470Y+162429X0180Y         S0      
317m1054            J110  -I7   D0142PA01X+054232Y+169642X0302Y    R180 S3      
327m1054            C6706 -1          A01X+052460Y+160939X0120Y0150R270 S1      
317m1055            VIA   -    MD0100PA01X+051264Y+162429X0180Y         S0      
317m1055            J110  -H6   D0142PA01X+053445Y+170035X0302Y    R180 S3      
327m1055            C6704 -1          A01X+051254Y+160939X0120Y0150R270 S1      
317m1056            VIA   -    MD0100PA01X+050058Y+162429X0180Y         S0      
317m1056            J110  -I5   D0142PA01X+052657Y+169642X0302Y    R180 S3      
327m1056            C6702 -1          A01X+050048Y+160939X0120Y0150R270 S1      
317m1057            VIA   -    MD0100PA01X+048852Y+162429X0180Y         S0      
317m1057            J110  -H4   D0142PA01X+051870Y+170035X0302Y    R180 S3      
327m1057            C6700 -1          A01X+048842Y+160939X0120Y0150R270 S1      
317m1058            VIA   -    MD0100PA01X+047646Y+162429X0180Y         S0      
317m1058            J110  -I3   D0142PA01X+051083Y+169642X0302Y    R180 S3      
327m1058            C6698 -1          A01X+047636Y+160939X0120Y0150R270 S1      
317m1059            VIA   -    MD0100PA01X+046440Y+162429X0180Y         S0      
317m1059            J110  -H2   D0142PA01X+050295Y+170035X0302Y    R180 S3      
327m1059            C6696 -1          A01X+046430Y+160939X0120Y0150R270 S1      
317m1060            VIA   -    MD0100PA01X+063324Y+162429X0180Y         S0      
317m1060            J109  -H8   D0142PA01X+061713Y+170035X0302Y    R180 S3      
327m1060            C6724 -1          A01X+063314Y+160939X0120Y0150R270 S1      
317m1061            VIA   -    MD0100PA01X+062118Y+162429X0180Y         S0      
317m1061            J109  -I7   D0142PA01X+060925Y+169642X0302Y    R180 S3      
327m1061            C6722 -1          A01X+062108Y+160939X0120Y0150R270 S1      
317m1062            VIA   -    MD0100PA01X+060912Y+162429X0180Y         S0      
317m1062            J109  -H6   D0142PA01X+060138Y+170035X0302Y    R180 S3      
327m1062            C6720 -1          A01X+060902Y+160939X0120Y0150R270 S1      
317m1063            VIA   -    MD0100PA01X+059706Y+162429X0180Y         S0      
317m1063            J109  -I5   D0142PA01X+059350Y+169642X0302Y    R180 S3      
327m1063            C6718 -1          A01X+059696Y+160939X0120Y0150R270 S1      
317m1064            VIA   -    MD0100PA01X+058500Y+162429X0180Y         S0      
317m1064            J109  -H4   D0142PA01X+058563Y+170035X0302Y    R180 S3      
327m1064            C6716 -1          A01X+058490Y+160939X0120Y0150R270 S1      
317m1065            VIA   -    MD0100PA01X+057294Y+162429X0180Y         S0      
317m1065            J109  -I3   D0142PA01X+057776Y+169642X0302Y    R180 S3      
327m1065            C6714 -1          A01X+057284Y+160939X0120Y0150R270 S1      
317m1066            VIA   -    MD0100PA01X+045234Y+162429X0180Y         S0      
317m1066            J110  -I1   D0142PA01X+049508Y+169642X0302Y    R180 S3      
327m1066            C6694 -1          A01X+045224Y+160939X0120Y0150R270 S1      
317m1067            VIA   -    MD0100PA01X+062301Y+154840X0180Y         S0      
317m1067            J109  -C2   D0142PA01X+056988Y+172398X0302Y    R180 S3      
327m1067            U6016 -BU1        A01X+062026Y+154048X0100Y0130     S1      
317m1068            VIA   -    MD0100PA01X+061828Y+154840X0180Y         S0      
317m1068            J109  -D1   D0142PA01X+056201Y+172004X0302Y    R180 S3      
327m1068            U6016 -CD1        A01X+061553Y+154048X0100Y0130     S1      
317m1069            VIA   -    MD0100PA01X+061356Y+154840X0180Y         S0      
317m1069            J110  -C8   D0142PA01X+055020Y+172398X0302Y    R180 S3      
327m1069            U6016 -CL1        A01X+061081Y+154048X0100Y0130     S1      
317m1070            VIA   -    MD0100PA01X+060884Y+154840X0180Y         S0      
317m1070            J110  -D7   D0142PA01X+054232Y+172004X0302Y    R180 S3      
327m1070            U6016 -CV1        A01X+060608Y+154048X0100Y0130     S1      
317m1071            VIA   -    MD0100PA01X+060411Y+154840X0180Y         S0      
317m1071            J110  -C6   D0142PA01X+053445Y+172398X0302Y    R180 S3      
327m1071            U6016 -DE1        A01X+060136Y+154048X0100Y0130     S1      
317m1072            VIA   -    MD0100PA01X+059939Y+154840X0180Y         S0      
317m1072            J110  -D5   D0142PA01X+052657Y+172004X0302Y    R180 S3      
327m1072            U6016 -DM1        A01X+059664Y+154048X0100Y0130     S1      
317m1073            VIA   -    MD0100PA01X+059466Y+154840X0180Y         S0      
317m1073            J110  -C4   D0142PA01X+051870Y+172398X0302Y    R180 S3      
327m1073            U6016 -DW1        A01X+059191Y+154048X0100Y0130     S1      
317m1074            VIA   -    MD0100PA01X+058994Y+154840X0180Y         S0      
317m1074            J110  -D3   D0142PA01X+051083Y+172004X0302Y    R180 S3      
327m1074            U6016 -EF1        A01X+058719Y+154048X0100Y0130     S1      
317m1075            VIA   -    MD0100PA01X+058521Y+154840X0180Y         S0      
317m1075            J110  -C2   D0142PA01X+050295Y+172398X0302Y    R180 S3      
327m1075            U6016 -EN1        A01X+058246Y+154048X0100Y0130     S1      
317m1076            VIA   -    MD0100PA01X+065136Y+154840X0180Y         S0      
317m1076            J109  -C8   D0142PA01X+061713Y+172398X0302Y    R180 S3      
327m1076            U6016 -R1         A01X+064860Y+154048X0100Y0130     S1      
317m1077            VIA   -    MD0100PA01X+064663Y+154840X0180Y         S0      
317m1077            J109  -D7   D0142PA01X+060925Y+172004X0302Y    R180 S3      
327m1077            U6016 -AB1        A01X+064388Y+154048X0100Y0130     S1      
317m1078            VIA   -    MD0100PA01X+064191Y+154840X0180Y         S0      
317m1078            J109  -C6   D0142PA01X+060138Y+172398X0302Y    R180 S3      
327m1078            U6016 -AJ1        A01X+063916Y+154048X0100Y0130     S1      
317m1079            VIA   -    MD0100PA01X+063718Y+154840X0180Y         S0      
317m1079            J109  -D5   D0142PA01X+059350Y+172004X0302Y    R180 S3      
327m1079            U6016 -AT1        A01X+063443Y+154048X0100Y0130     S1      
317m1080            VIA   -    MD0100PA01X+063246Y+154840X0180Y         S0      
317m1080            J109  -C4   D0142PA01X+058563Y+172398X0302Y    R180 S3      
327m1080            U6016 -BC1        A01X+062971Y+154048X0100Y0130     S1      
317m1081            VIA   -    MD0100PA01X+062773Y+154840X0180Y         S0      
327m1081            U6016 -BK1        A01X+062498Y+154048X0100Y0130     S1      
317m1081            J109  -D3   D0142PA01X+057776Y+172004X0302Y    R180 S3      
317m1082            VIA   -    MD0100PA01X+058049Y+154840X0180Y         S0      
317m1082            J110  -D1   D0142PA01X+049508Y+172004X0302Y    R180 S3      
327m1082            U6016 -EY1        A01X+057774Y+154048X0100Y0130     S1      
317m1083            VIA   -    MD0100PA01X+062301Y+154500X0180Y         S0      
317m1083            J109  -B2   D0142PA01X+056988Y+172870X0302Y    R180 S3      
327m1083            U6016 -BR2        A01X+062144Y+153843X0120Y         S1      
317m1084            VIA   -    MD0100PA01X+061828Y+154500X0180Y         S0      
317m1084            J109  -C1   D0142PA01X+056201Y+172476X0302Y    R180 S3      
327m1084            U6016 -CB2        A01X+061672Y+153843X0120Y         S1      
317m1085            VIA   -    MD0100PA01X+061356Y+154500X0180Y         S0      
317m1085            J110  -B8   D0142PA01X+055020Y+172870X0302Y    R180 S3      
327m1085            U6016 -CJ2        A01X+061199Y+153843X0120Y         S1      
317m1086            VIA   -    MD0100PA01X+060884Y+154500X0180Y         S0      
317m1086            J110  -C7   D0142PA01X+054232Y+172476X0302Y    R180 S3      
327m1086            U6016 -CT2        A01X+060727Y+153843X0120Y         S1      
317m1087            VIA   -    MD0100PA01X+060411Y+154500X0180Y         S0      
317m1087            J110  -B6   D0142PA01X+053445Y+172870X0302Y    R180 S3      
327m1087            U6016 -DC2        A01X+060254Y+153843X0120Y         S1      
317m1088            VIA   -    MD0100PA01X+059939Y+154500X0180Y         S0      
317m1088            J110  -C5   D0142PA01X+052657Y+172476X0302Y    R180 S3      
327m1088            U6016 -DK2        A01X+059782Y+153843X0120Y         S1      
317m1089            VIA   -    MD0100PA01X+059466Y+154500X0180Y         S0      
317m1089            J110  -B4   D0142PA01X+051870Y+172870X0302Y    R180 S3      
327m1089            U6016 -DU2        A01X+059309Y+153843X0120Y         S1      
317m1090            VIA   -    MD0100PA01X+058994Y+154500X0180Y         S0      
317m1090            J110  -C3   D0142PA01X+051083Y+172476X0302Y    R180 S3      
327m1090            U6016 -ED2        A01X+058837Y+153843X0120Y         S1      
317m1091            VIA   -    MD0100PA01X+058521Y+154500X0180Y         S0      
317m1091            J110  -B2   D0142PA01X+050295Y+172870X0302Y    R180 S3      
327m1091            U6016 -EL2        A01X+058364Y+153843X0120Y         S1      
317m1092            VIA   -    MD0100PA01X+065136Y+154500X0180Y         S0      
317m1092            J109  -B8   D0142PA01X+061713Y+172870X0302Y    R180 S3      
327m1092            U6016 -N2         A01X+064979Y+153843X0120Y         S1      
317m1093            VIA   -    MD0100PA01X+064663Y+154500X0180Y         S0      
317m1093            J109  -C7   D0142PA01X+060925Y+172476X0302Y    R180 S3      
327m1093            U6016 -Y2         A01X+064506Y+153843X0120Y         S1      
317m1094            VIA   -    MD0100PA01X+064191Y+154500X0180Y         S0      
317m1094            J109  -B6   D0142PA01X+060138Y+172870X0302Y    R180 S3      
327m1094            U6016 -AG2        A01X+064034Y+153843X0120Y         S1      
317m1095            VIA   -    MD0100PA01X+063718Y+154500X0180Y         S0      
317m1095            J109  -C5   D0142PA01X+059350Y+172476X0302Y    R180 S3      
327m1095            U6016 -AP2        A01X+063561Y+153843X0120Y         S1      
317m1096            VIA   -    MD0100PA01X+063246Y+154500X0180Y         S0      
317m1096            J109  -B4   D0142PA01X+058563Y+172870X0302Y    R180 S3      
327m1096            U6016 -BA2        A01X+063089Y+153843X0120Y         S1      
317m1097            VIA   -    MD0100PA01X+062773Y+154500X0180Y         S0      
327m1097            U6016 -BH2        A01X+062616Y+153843X0120Y         S1      
317m1097            J109  -C3   D0142PA01X+057776Y+172476X0302Y    R180 S3      
317m1098            VIA   -    MD0100PA01X+058049Y+154500X0180Y         S0      
317m1098            J110  -C1   D0142PA01X+049508Y+172476X0302Y    R180 S3      
327m1098            U6016 -EV2        A01X+057892Y+153843X0120Y         S1      
317m1099            VIA   -    MD0080PA01X+036031Y+153334X0160Y         S0      
317m1099            VIA   -    MD0100PA18X+030614Y+160238X0180Y         S0      
327m1099            C6679 -2          A18X+030624Y+160729X0120Y0150R090 S2      
327m1099            U6015 -BP7        A01X+035826Y+153334X0150Y         S1      
317m1100            VIA   -    MD0080PA01X+035559Y+153334X0160Y         S0      
317m1100            VIA   -    MD0100PA18X+029408Y+160238X0180Y         S0      
327m1100            C6677 -2          A18X+029418Y+160729X0120Y0150R090 S2      
327m1100            U6015 -CA7        A01X+035354Y+153334X0150Y         S1      
317m1101            VIA   -    MD0080PA01X+035086Y+153334X0160Y         S0      
317m1101            VIA   -    MD0100PA18X+028202Y+160238X0180Y         S0      
327m1101            C6675 -2          A18X+028212Y+160729X0120Y0150R090 S2      
327m1101            U6015 -CH7        A01X+034881Y+153334X0150Y         S1      
317m1102            VIA   -    MD0080PA01X+034614Y+153334X0160Y         S0      
317m1102            VIA   -    MD0100PA18X+026996Y+160238X0180Y         S0      
327m1102            C6673 -2          A18X+027006Y+160729X0120Y0150R090 S2      
327m1102            U6015 -CR7        A01X+034409Y+153334X0150Y         S1      
317m1103            VIA   -    MD0080PA01X+034141Y+153334X0160Y         S0      
317m1103            VIA   -    MD0100PA18X+025790Y+160238X0180Y         S0      
327m1103            C6671 -2          A18X+025800Y+160729X0120Y0150R090 S2      
327m1103            U6015 -DB7        A01X+033936Y+153334X0150Y         S1      
317m1104            VIA   -    MD0080PA01X+033669Y+153334X0160Y         S0      
317m1104            VIA   -    MD0100PA18X+024584Y+160238X0180Y         S0      
327m1104            C6669 -2          A18X+024594Y+160729X0120Y0150R090 S2      
327m1104            U6015 -DJ7        A01X+033464Y+153334X0150Y         S1      
317m1105            VIA   -    MD0080PA01X+033196Y+153334X0160Y         S0      
317m1105            VIA   -    MD0100PA18X+023378Y+160238X0180Y         S0      
327m1105            C6667 -2          A18X+023388Y+160729X0120Y0150R090 S2      
327m1105            U6015 -DT7        A01X+032992Y+153334X0150Y         S1      
317m1106            VIA   -    MD0080PA01X+032724Y+153334X0160Y         S0      
317m1106            VIA   -    MD0100PA18X+022172Y+160238X0180Y         S0      
327m1106            C6665 -2          A18X+022182Y+160729X0120Y0150R090 S2      
327m1106            U6015 -EC7        A01X+032519Y+153334X0150Y         S1      
317m1107            VIA   -    MD0080PA01X+032252Y+153334X0160Y         S0      
317m1107            VIA   -    MD0100PA18X+020966Y+160238X0180Y         S0      
327m1107            C6663 -2          A18X+020976Y+160729X0120Y0150R090 S2      
327m1107            U6015 -EK7        A01X+032047Y+153334X0150Y         S1      
317m1108            VIA   -    MD0080PA01X+038866Y+153334X0160Y         S0      
317m1108            VIA   -    MD0100PA18X+037850Y+160238X0180Y         S0      
327m1108            C6691 -2          A18X+037860Y+160729X0120Y0150R090 S2      
327m1108            U6015 -M7         A01X+038661Y+153334X0150Y         S1      
317m1109            VIA   -    MD0080PA01X+038393Y+153334X0160Y         S0      
317m1109            VIA   -    MD0100PA18X+036644Y+160238X0180Y         S0      
327m1109            C6689 -2          A18X+036654Y+160729X0120Y0150R090 S2      
327m1109            U6015 -W7         A01X+038188Y+153334X0150Y         S1      
317m1110            VIA   -    MD0080PA01X+037921Y+153334X0160Y         S0      
317m1110            VIA   -    MD0100PA18X+035438Y+160238X0180Y         S0      
327m1110            C6687 -2          A18X+035448Y+160729X0120Y0150R090 S2      
327m1110            U6015 -AF7        A01X+037716Y+153334X0150Y         S1      
317m1111            VIA   -    MD0080PA01X+037448Y+153334X0160Y         S0      
317m1111            VIA   -    MD0100PA18X+034232Y+160238X0180Y         S0      
327m1111            C6685 -2          A18X+034242Y+160729X0120Y0150R090 S2      
327m1111            U6015 -AN7        A01X+037243Y+153334X0150Y         S1      
317m1112            VIA   -    MD0080PA01X+036976Y+153334X0160Y         S0      
317m1112            VIA   -    MD0100PA18X+033026Y+160238X0180Y         S0      
327m1112            C6683 -2          A18X+033036Y+160729X0120Y0150R090 S2      
327m1112            U6015 -AY7        A01X+036771Y+153334X0150Y         S1      
317m1113            VIA   -    MD0080PA01X+036504Y+153334X0160Y         S0      
317m1113            VIA   -    MD0100PA18X+031820Y+160238X0180Y         S0      
327m1113            C6681 -2          A18X+031830Y+160729X0120Y0150R090 S2      
327m1113            U6015 -BG7        A01X+036299Y+153334X0150Y         S1      
317m1114            VIA   -    MD0080PA01X+031779Y+153334X0160Y         S0      
317m1114            VIA   -    MD0100PA18X+019760Y+160238X0180Y         S0      
327m1114            C6661 -2          A18X+019770Y+160729X0120Y0150R090 S2      
327m1114            U6015 -EU7        A01X+031574Y+153334X0150Y         S1      
317m1115            VIA   -    MD0080PA01X+035874Y+153061X0160Y         S0      
317m1115            VIA   -    MD0100PA18X+030274Y+160238X0180Y         S0      
327m1115            C6680 -2          A18X+030264Y+160729X0120Y0150R090 S2      
327m1115            U6015 -BT10       A01X+035669Y+153061X0150Y         S1      
317m1116            VIA   -    MD0080PA01X+035401Y+153061X0160Y         S0      
317m1116            VIA   -    MD0100PA18X+029068Y+160238X0180Y         S0      
327m1116            C6678 -2          A18X+029058Y+160729X0120Y0150R090 S2      
327m1116            U6015 -CC10       A01X+035196Y+153061X0150Y         S1      
317m1117            VIA   -    MD0080PA01X+034929Y+153061X0160Y         S0      
317m1117            VIA   -    MD0100PA18X+027862Y+160238X0180Y         S0      
327m1117            C6676 -2          A18X+027852Y+160729X0120Y0150R090 S2      
327m1117            U6015 -CK10       A01X+034724Y+153061X0150Y         S1      
317m1118            VIA   -    MD0080PA01X+034456Y+153061X0160Y         S0      
317m1118            VIA   -    MD0100PA18X+026656Y+160238X0180Y         S0      
327m1118            C6674 -2          A18X+026646Y+160729X0120Y0150R090 S2      
327m1118            U6015 -CU10       A01X+034251Y+153061X0150Y         S1      
317m1119            VIA   -    MD0080PA01X+033984Y+153061X0160Y         S0      
317m1119            VIA   -    MD0100PA18X+025450Y+160238X0180Y         S0      
327m1119            C6672 -2          A18X+025440Y+160729X0120Y0150R090 S2      
327m1119            U6015 -DD10       A01X+033779Y+153061X0150Y         S1      
317m1120            VIA   -    MD0080PA01X+033511Y+153061X0160Y         S0      
317m1120            VIA   -    MD0100PA18X+024244Y+160238X0180Y         S0      
327m1120            C6670 -2          A18X+024234Y+160729X0120Y0150R090 S2      
327m1120            U6015 -DL10       A01X+033306Y+153061X0150Y         S1      
317m1121            VIA   -    MD0080PA01X+033039Y+153061X0160Y         S0      
317m1121            VIA   -    MD0100PA18X+023038Y+160238X0180Y         S0      
327m1121            C6668 -2          A18X+023028Y+160729X0120Y0150R090 S2      
327m1121            U6015 -DV10       A01X+032834Y+153061X0150Y         S1      
317m1122            VIA   -    MD0080PA01X+032567Y+153061X0160Y         S0      
317m1122            VIA   -    MD0100PA18X+021832Y+160238X0180Y         S0      
327m1122            C6666 -2          A18X+021822Y+160729X0120Y0150R090 S2      
327m1122            U6015 -EE10       A01X+032362Y+153061X0150Y         S1      
317m1123            VIA   -    MD0080PA01X+032094Y+153061X0160Y         S0      
317m1123            VIA   -    MD0100PA18X+020626Y+160238X0180Y         S0      
327m1123            C6664 -2          A18X+020616Y+160729X0120Y0150R090 S2      
327m1123            U6015 -EM10       A01X+031889Y+153061X0150Y         S1      
317m1124            VIA   -    MD0080PA01X+038708Y+153061X0160Y         S0      
317m1124            VIA   -    MD0100PA18X+037510Y+160238X0180Y         S0      
327m1124            C6692 -2          A18X+037500Y+160729X0120Y0150R090 S2      
327m1124            U6015 -P10        A01X+038503Y+153061X0150Y         S1      
317m1125            VIA   -    MD0080PA01X+038236Y+153061X0160Y         S0      
317m1125            VIA   -    MD0100PA18X+036304Y+160238X0180Y         S0      
327m1125            C6690 -2          A18X+036294Y+160729X0120Y0150R090 S2      
327m1125            U6015 -AA10       A01X+038031Y+153061X0150Y         S1      
317m1126            VIA   -    MD0080PA01X+037763Y+153061X0160Y         S0      
317m1126            VIA   -    MD0100PA18X+035098Y+160238X0180Y         S0      
327m1126            C6688 -2          A18X+035088Y+160729X0120Y0150R090 S2      
327m1126            U6015 -AH10       A01X+037558Y+153061X0150Y         S1      
317m1127            VIA   -    MD0080PA01X+037291Y+153061X0160Y         S0      
317m1127            VIA   -    MD0100PA18X+033892Y+160238X0180Y         S0      
327m1127            C6686 -2          A18X+033882Y+160729X0120Y0150R090 S2      
327m1127            U6015 -AR10       A01X+037086Y+153061X0150Y         S1      
317m1128            VIA   -    MD0080PA01X+036818Y+153061X0160Y         S0      
317m1128            VIA   -    MD0100PA18X+032686Y+160238X0180Y         S0      
327m1128            C6684 -2          A18X+032676Y+160729X0120Y0150R090 S2      
327m1128            U6015 -BB10       A01X+036614Y+153061X0150Y         S1      
317m1129            VIA   -    MD0080PA01X+036346Y+153061X0160Y         S0      
317m1129            VIA   -    MD0100PA18X+031480Y+160238X0180Y         S0      
327m1129            C6682 -2          A18X+031470Y+160729X0120Y0150R090 S2      
327m1129            U6015 -BJ10       A01X+036141Y+153061X0150Y         S1      
317m1130            VIA   -    MD0080PA01X+031622Y+153061X0160Y         S0      
317m1130            VIA   -    MD0100PA18X+019420Y+160238X0180Y         S0      
327m1130            C6662 -2          A18X+019410Y+160729X0120Y0150R090 S2      
327m1130            U6015 -EW10       A01X+031417Y+153061X0150Y         S1      
317m1131            VIA   -    MD0100PA18X+030614Y+161429X0180Y         S0      
317m1131            J111  -L2   D0142PA01X+030571Y+168146X0302Y    R180 S3      
327m1131            C6679 -1          A18X+030624Y+160939X0120Y0150R090 S2      
317m1132            VIA   -    MD0100PA18X+029408Y+161429X0180Y         S0      
317m1132            J111  -M1   D0142PA01X+029784Y+167752X0302Y    R180 S3      
327m1132            C6677 -1          A18X+029418Y+160939X0120Y0150R090 S2      
317m1133            VIA   -    MD0100PA18X+028202Y+161429X0180Y         S0      
317m1133            J112  -L8   D0142PA01X+028602Y+168146X0302Y    R180 S3      
327m1133            C6675 -1          A18X+028212Y+160939X0120Y0150R090 S2      
317m1134            VIA   -    MD0100PA18X+026996Y+161429X0180Y         S0      
317m1134            J112  -M7   D0142PA01X+027815Y+167752X0302Y    R180 S3      
327m1134            C6673 -1          A18X+027006Y+160939X0120Y0150R090 S2      
317m1135            VIA   -    MD0100PA18X+025790Y+161429X0180Y         S0      
317m1135            J112  -L6   D0142PA01X+027028Y+168146X0302Y    R180 S3      
327m1135            C6671 -1          A18X+025800Y+160939X0120Y0150R090 S2      
317m1136            VIA   -    MD0100PA18X+024584Y+161429X0180Y         S0      
317m1136            J112  -M5   D0142PA01X+026240Y+167752X0302Y    R180 S3      
327m1136            C6669 -1          A18X+024594Y+160939X0120Y0150R090 S2      
317m1137            VIA   -    MD0100PA18X+023378Y+161429X0180Y         S0      
317m1137            J112  -L4   D0142PA01X+025453Y+168146X0302Y    R180 S3      
327m1137            C6667 -1          A18X+023388Y+160939X0120Y0150R090 S2      
317m1138            VIA   -    MD0100PA18X+022172Y+161429X0180Y         S0      
317m1138            J112  -M3   D0142PA01X+024665Y+167752X0302Y    R180 S3      
327m1138            C6665 -1          A18X+022182Y+160939X0120Y0150R090 S2      
317m1139            VIA   -    MD0100PA18X+020966Y+161429X0180Y         S0      
317m1139            J112  -L2   D0142PA01X+023878Y+168146X0302Y    R180 S3      
327m1139            C6663 -1          A18X+020976Y+160939X0120Y0150R090 S2      
317m1140            VIA   -    MD0100PA18X+037850Y+161429X0180Y         S0      
317m1140            J111  -L8   D0142PA01X+035295Y+168146X0302Y    R180 S3      
327m1140            C6691 -1          A18X+037860Y+160939X0120Y0150R090 S2      
317m1141            VIA   -    MD0100PA18X+036644Y+161429X0180Y         S0      
317m1141            J111  -M7   D0142PA01X+034508Y+167752X0302Y    R180 S3      
327m1141            C6689 -1          A18X+036654Y+160939X0120Y0150R090 S2      
317m1142            VIA   -    MD0100PA18X+035438Y+161429X0180Y         S0      
317m1142            J111  -L6   D0142PA01X+033720Y+168146X0302Y    R180 S3      
327m1142            C6687 -1          A18X+035448Y+160939X0120Y0150R090 S2      
317m1143            VIA   -    MD0100PA18X+034232Y+161429X0180Y         S0      
317m1143            J111  -M5   D0142PA01X+032933Y+167752X0302Y    R180 S3      
327m1143            C6685 -1          A18X+034242Y+160939X0120Y0150R090 S2      
317m1144            VIA   -    MD0100PA18X+033026Y+161429X0180Y         S0      
317m1144            J111  -L4   D0142PA01X+032146Y+168146X0302Y    R180 S3      
327m1144            C6683 -1          A18X+033036Y+160939X0120Y0150R090 S2      
317m1145            VIA   -    MD0100PA18X+031820Y+161429X0180Y         S0      
317m1145            J111  -M3   D0142PA01X+031358Y+167752X0302Y    R180 S3      
327m1145            C6681 -1          A18X+031830Y+160939X0120Y0150R090 S2      
317m1146            VIA   -    MD0100PA18X+019760Y+161429X0180Y         S0      
317m1146            J112  -M1   D0142PA01X+023090Y+167752X0302Y    R180 S3      
327m1146            C6661 -1          A18X+019770Y+160939X0120Y0150R090 S2      
317m1147            VIA   -    MD0100PA18X+030274Y+161429X0180Y         S0      
317m1147            J111  -K2   D0142PA01X+030571Y+168618X0302Y    R180 S3      
327m1147            C6680 -1          A18X+030264Y+160939X0120Y0150R090 S2      
317m1148            VIA   -    MD0100PA18X+029068Y+161429X0180Y         S0      
317m1148            J111  -L1   D0142PA01X+029784Y+168224X0302Y    R180 S3      
327m1148            C6678 -1          A18X+029058Y+160939X0120Y0150R090 S2      
317m1149            VIA   -    MD0100PA18X+027862Y+161429X0180Y         S0      
317m1149            J112  -K8   D0142PA01X+028602Y+168618X0302Y    R180 S3      
327m1149            C6676 -1          A18X+027852Y+160939X0120Y0150R090 S2      
317m1150            VIA   -    MD0100PA18X+026656Y+161429X0180Y         S0      
317m1150            J112  -L7   D0142PA01X+027815Y+168224X0302Y    R180 S3      
327m1150            C6674 -1          A18X+026646Y+160939X0120Y0150R090 S2      
317m1151            VIA   -    MD0100PA18X+025450Y+161429X0180Y         S0      
317m1151            J112  -K6   D0142PA01X+027028Y+168618X0302Y    R180 S3      
327m1151            C6672 -1          A18X+025440Y+160939X0120Y0150R090 S2      
317m1152            VIA   -    MD0100PA18X+024244Y+161429X0180Y         S0      
317m1152            J112  -L5   D0142PA01X+026240Y+168224X0302Y    R180 S3      
327m1152            C6670 -1          A18X+024234Y+160939X0120Y0150R090 S2      
317m1153            VIA   -    MD0100PA18X+023038Y+161429X0180Y         S0      
317m1153            J112  -K4   D0142PA01X+025453Y+168618X0302Y    R180 S3      
327m1153            C6668 -1          A18X+023028Y+160939X0120Y0150R090 S2      
317m1154            VIA   -    MD0100PA18X+021832Y+161429X0180Y         S0      
317m1154            J112  -L3   D0142PA01X+024665Y+168224X0302Y    R180 S3      
327m1154            C6666 -1          A18X+021822Y+160939X0120Y0150R090 S2      
317m1155            VIA   -    MD0100PA18X+020626Y+161429X0180Y         S0      
317m1155            J112  -K2   D0142PA01X+023878Y+168618X0302Y    R180 S3      
327m1155            C6664 -1          A18X+020616Y+160939X0120Y0150R090 S2      
317m1156            VIA   -    MD0100PA18X+037510Y+161429X0180Y         S0      
317m1156            J111  -K8   D0142PA01X+035295Y+168618X0302Y    R180 S3      
327m1156            C6692 -1          A18X+037500Y+160939X0120Y0150R090 S2      
317m1157            VIA   -    MD0100PA18X+036304Y+161429X0180Y         S0      
317m1157            J111  -L7   D0142PA01X+034508Y+168224X0302Y    R180 S3      
327m1157            C6690 -1          A18X+036294Y+160939X0120Y0150R090 S2      
317m1158            VIA   -    MD0100PA18X+035098Y+161429X0180Y         S0      
317m1158            J111  -K6   D0142PA01X+033720Y+168618X0302Y    R180 S3      
327m1158            C6688 -1          A18X+035088Y+160939X0120Y0150R090 S2      
317m1159            VIA   -    MD0100PA18X+033892Y+161429X0180Y         S0      
317m1159            J111  -L5   D0142PA01X+032933Y+168224X0302Y    R180 S3      
327m1159            C6686 -1          A18X+033882Y+160939X0120Y0150R090 S2      
317m1160            VIA   -    MD0100PA18X+032686Y+161429X0180Y         S0      
317m1160            J111  -K4   D0142PA01X+032146Y+168618X0302Y    R180 S3      
327m1160            C6684 -1          A18X+032676Y+160939X0120Y0150R090 S2      
317m1161            VIA   -    MD0100PA18X+031480Y+161429X0180Y         S0      
317m1161            J111  -L3   D0142PA01X+031358Y+168224X0302Y    R180 S3      
327m1161            C6682 -1          A18X+031470Y+160939X0120Y0150R090 S2      
317m1162            VIA   -    MD0100PA18X+019420Y+161429X0180Y         S0      
317m1162            J112  -L1   D0142PA01X+023090Y+168224X0302Y    R180 S3      
327m1162            C6662 -1          A18X+019410Y+160939X0120Y0150R090 S2      
317m1163            VIA   -    MD0100PA01X+035884Y+154840X0180Y         S0      
317m1163            J111  -F2   D0142PA01X+030571Y+170980X0302Y    R180 S3      
327m1163            U6015 -BU1        A01X+035609Y+154048X0100Y0130     S1      
317m1164            VIA   -    MD0100PA01X+035411Y+154840X0180Y         S0      
317m1164            J111  -G1   D0142PA01X+029784Y+170587X0302Y    R180 S3      
327m1164            U6015 -CD1        A01X+035136Y+154048X0100Y0130     S1      
317m1165            VIA   -    MD0100PA01X+034939Y+154840X0180Y         S0      
317m1165            J112  -F8   D0142PA01X+028602Y+170980X0302Y    R180 S3      
327m1165            U6015 -CL1        A01X+034664Y+154048X0100Y0130     S1      
317m1166            VIA   -    MD0100PA01X+034466Y+154840X0180Y         S0      
317m1166            J112  -G7   D0142PA01X+027815Y+170587X0302Y    R180 S3      
327m1166            U6015 -CV1        A01X+034191Y+154048X0100Y0130     S1      
317m1167            VIA   -    MD0100PA01X+033994Y+154840X0180Y         S0      
317m1167            J112  -F6   D0142PA01X+027028Y+170980X0302Y    R180 S3      
327m1167            U6015 -DE1        A01X+033719Y+154048X0100Y0130     S1      
317m1168            VIA   -    MD0100PA01X+033521Y+154840X0180Y         S0      
317m1168            J112  -G5   D0142PA01X+026240Y+170587X0302Y    R180 S3      
327m1168            U6015 -DM1        A01X+033246Y+154048X0100Y0130     S1      
317m1169            VIA   -    MD0100PA01X+033049Y+154840X0180Y         S0      
317m1169            J112  -F4   D0142PA01X+025453Y+170980X0302Y    R180 S3      
327m1169            U6015 -DW1        A01X+032774Y+154048X0100Y0130     S1      
317m1170            VIA   -    MD0100PA01X+032576Y+154840X0180Y         S0      
317m1170            J112  -G3   D0142PA01X+024665Y+170587X0302Y    R180 S3      
327m1170            U6015 -EF1        A01X+032302Y+154048X0100Y0130     S1      
317m1171            VIA   -    MD0100PA01X+032104Y+154840X0180Y         S0      
317m1171            J112  -F2   D0142PA01X+023878Y+170980X0302Y    R180 S3      
327m1171            U6015 -EN1        A01X+031829Y+154048X0100Y0130     S1      
317m1172            VIA   -    MD0100PA01X+038718Y+154840X0180Y         S0      
317m1172            J111  -F8   D0142PA01X+035295Y+170980X0302Y    R180 S3      
327m1172            U6015 -R1         A01X+038443Y+154048X0100Y0130     S1      
317m1173            VIA   -    MD0100PA01X+038246Y+154840X0180Y         S0      
317m1173            J111  -G7   D0142PA01X+034508Y+170587X0302Y    R180 S3      
327m1173            U6015 -AB1        A01X+037971Y+154048X0100Y0130     S1      
317m1174            VIA   -    MD0100PA01X+037773Y+154840X0180Y         S0      
317m1174            J111  -F6   D0142PA01X+033720Y+170980X0302Y    R180 S3      
327m1174            U6015 -AJ1        A01X+037498Y+154048X0100Y0130     S1      
317m1175            VIA   -    MD0100PA01X+037301Y+154840X0180Y         S0      
317m1175            J111  -G5   D0142PA01X+032933Y+170587X0302Y    R180 S3      
327m1175            U6015 -AT1        A01X+037026Y+154048X0100Y0130     S1      
317m1176            VIA   -    MD0100PA01X+036828Y+154840X0180Y         S0      
317m1176            J111  -F4   D0142PA01X+032146Y+170980X0302Y    R180 S3      
327m1176            U6015 -BC1        A01X+036553Y+154048X0100Y0130     S1      
317m1177            VIA   -    MD0100PA01X+036356Y+154840X0180Y         S0      
327m1177            U6015 -BK1        A01X+036081Y+154048X0100Y0130     S1      
317m1177            J111  -G3   D0142PA01X+031358Y+170587X0302Y    R180 S3      
317m1178            VIA   -    MD0100PA01X+031632Y+154840X0180Y         S0      
317m1178            J112  -G1   D0142PA01X+023090Y+170587X0302Y    R180 S3      
327m1178            U6015 -EY1        A01X+031357Y+154048X0100Y0130     S1      
317m1179            VIA   -    MD0100PA01X+035884Y+154500X0180Y         S0      
317m1179            J111  -E2   D0142PA01X+030571Y+171453X0302Y    R180 S3      
327m1179            U6015 -BR2        A01X+035727Y+153843X0120Y         S1      
317m1180            VIA   -    MD0100PA01X+035411Y+154500X0180Y         S0      
317m1180            J111  -F1   D0142PA01X+029784Y+171059X0302Y    R180 S3      
327m1180            U6015 -CB2        A01X+035254Y+153843X0120Y         S1      
317m1181            VIA   -    MD0100PA01X+034939Y+154500X0180Y         S0      
317m1181            J112  -E8   D0142PA01X+028602Y+171453X0302Y    R180 S3      
327m1181            U6015 -CJ2        A01X+034782Y+153843X0120Y         S1      
317m1182            VIA   -    MD0100PA01X+034466Y+154500X0180Y         S0      
317m1182            J112  -F7   D0142PA01X+027815Y+171059X0302Y    R180 S3      
327m1182            U6015 -CT2        A01X+034309Y+153843X0120Y         S1      
317m1183            VIA   -    MD0100PA01X+033994Y+154500X0180Y         S0      
317m1183            J112  -E6   D0142PA01X+027028Y+171453X0302Y    R180 S3      
327m1183            U6015 -DC2        A01X+033837Y+153843X0120Y         S1      
317m1184            VIA   -    MD0100PA01X+033521Y+154500X0180Y         S0      
317m1184            J112  -F5   D0142PA01X+026240Y+171059X0302Y    R180 S3      
327m1184            U6015 -DK2        A01X+033364Y+153843X0120Y         S1      
317m1185            VIA   -    MD0100PA01X+033049Y+154500X0180Y         S0      
317m1185            J112  -E4   D0142PA01X+025453Y+171453X0302Y    R180 S3      
327m1185            U6015 -DU2        A01X+032892Y+153843X0120Y         S1      
317m1186            VIA   -    MD0100PA01X+032576Y+154500X0180Y         S0      
317m1186            J112  -F3   D0142PA01X+024665Y+171059X0302Y    R180 S3      
327m1186            U6015 -ED2        A01X+032420Y+153843X0120Y         S1      
317m1187            VIA   -    MD0100PA01X+032104Y+154500X0180Y         S0      
317m1187            J112  -E2   D0142PA01X+023878Y+171453X0302Y    R180 S3      
327m1187            U6015 -EL2        A01X+031947Y+153843X0120Y         S1      
317m1188            VIA   -    MD0100PA01X+038718Y+154500X0180Y         S0      
317m1188            J111  -E8   D0142PA01X+035295Y+171453X0302Y    R180 S3      
327m1188            U6015 -N2         A01X+038561Y+153843X0120Y         S1      
317m1189            VIA   -    MD0100PA01X+038246Y+154500X0180Y         S0      
317m1189            J111  -F7   D0142PA01X+034508Y+171059X0302Y    R180 S3      
327m1189            U6015 -Y2         A01X+038089Y+153843X0120Y         S1      
317m1190            VIA   -    MD0100PA01X+037773Y+154500X0180Y         S0      
317m1190            J111  -E6   D0142PA01X+033720Y+171453X0302Y    R180 S3      
327m1190            U6015 -AG2        A01X+037616Y+153843X0120Y         S1      
317m1191            VIA   -    MD0100PA01X+037301Y+154500X0180Y         S0      
317m1191            J111  -F5   D0142PA01X+032933Y+171059X0302Y    R180 S3      
327m1191            U6015 -AP2        A01X+037144Y+153843X0120Y         S1      
317m1192            VIA   -    MD0100PA01X+036828Y+154500X0180Y         S0      
317m1192            J111  -E4   D0142PA01X+032146Y+171453X0302Y    R180 S3      
327m1192            U6015 -BA2        A01X+036672Y+153843X0120Y         S1      
317m1193            VIA   -    MD0100PA01X+036356Y+154500X0180Y         S0      
327m1193            U6015 -BH2        A01X+036199Y+153843X0120Y         S1      
317m1193            J111  -F3   D0142PA01X+031358Y+171059X0302Y    R180 S3      
317m1194            VIA   -    MD0100PA01X+031632Y+154500X0180Y         S0      
317m1194            J112  -F1   D0142PA01X+023090Y+171059X0302Y    R180 S3      
327m1194            U6015 -EV2        A01X+031475Y+153843X0120Y         S1      
317m1195            VIA   -    MD0080PA01X+023225Y+153334X0160Y         S0      
317m1195            VIA   -    MD0100PA01X+030011Y+159238X0180Y         S0      
327m1195            C6647 -2          A01X+030021Y+160729X0120Y0150R270 S1      
327m1195            U6014 -BP7        A01X+023020Y+153334X0150Y         S1      
317m1196            VIA   -    MD0080PA01X+022752Y+153334X0160Y         S0      
317m1196            VIA   -    MD0100PA01X+028805Y+159238X0180Y         S0      
327m1196            C6645 -2          A01X+028815Y+160729X0120Y0150R270 S1      
327m1196            U6014 -CA7        A01X+022548Y+153334X0150Y         S1      
317m1197            VIA   -    MD0080PA01X+022280Y+153334X0160Y         S0      
317m1197            VIA   -    MD0100PA01X+027599Y+159238X0180Y         S0      
327m1197            C6643 -2          A01X+027609Y+160729X0120Y0150R270 S1      
327m1197            U6014 -CH7        A01X+022075Y+153334X0150Y         S1      
317m1198            VIA   -    MD0080PA01X+021808Y+153334X0160Y         S0      
317m1198            VIA   -    MD0100PA01X+026393Y+159238X0180Y         S0      
327m1198            C6641 -2          A01X+026403Y+160729X0120Y0150R270 S1      
327m1198            U6014 -CR7        A01X+021603Y+153334X0150Y         S1      
317m1199            VIA   -    MD0080PA01X+021335Y+153334X0160Y         S0      
317m1199            VIA   -    MD0100PA01X+025187Y+159238X0180Y         S0      
327m1199            C6639 -2          A01X+025197Y+160729X0120Y0150R270 S1      
327m1199            U6014 -DB7        A01X+021130Y+153334X0150Y         S1      
317m1200            VIA   -    MD0080PA01X+020863Y+153334X0160Y         S0      
317m1200            VIA   -    MD0100PA01X+023981Y+159238X0180Y         S0      
327m1200            C6637 -2          A01X+023991Y+160729X0120Y0150R270 S1      
327m1200            U6014 -DJ7        A01X+020658Y+153334X0150Y         S1      
317m1201            VIA   -    MD0080PA01X+020390Y+153334X0160Y         S0      
317m1201            VIA   -    MD0100PA01X+022775Y+159238X0180Y         S0      
327m1201            C6635 -2          A01X+022785Y+160729X0120Y0150R270 S1      
327m1201            U6014 -DT7        A01X+020185Y+153334X0150Y         S1      
317m1202            VIA   -    MD0080PA01X+019918Y+153334X0160Y         S0      
317m1202            VIA   -    MD0100PA01X+021569Y+159238X0180Y         S0      
327m1202            C6633 -2          A01X+021579Y+160729X0120Y0150R270 S1      
327m1202            U6014 -EC7        A01X+019713Y+153334X0150Y         S1      
317m1203            VIA   -    MD0080PA01X+019445Y+153334X0160Y         S0      
317m1203            VIA   -    MD0100PA01X+020363Y+159238X0180Y         S0      
327m1203            C6631 -2          A01X+020373Y+160729X0120Y0150R270 S1      
327m1203            U6014 -EK7        A01X+019240Y+153334X0150Y         S1      
317m1204            VIA   -    MD0080PA01X+026060Y+153334X0160Y         S0      
317m1204            VIA   -    MD0100PA01X+037247Y+159238X0180Y         S0      
327m1204            C6659 -2          A01X+037257Y+160729X0120Y0150R270 S1      
327m1204            U6014 -M7         A01X+025855Y+153334X0150Y         S1      
317m1205            VIA   -    MD0080PA01X+025587Y+153334X0160Y         S0      
317m1205            VIA   -    MD0100PA01X+036041Y+159238X0180Y         S0      
327m1205            C6657 -2          A01X+036051Y+160729X0120Y0150R270 S1      
327m1205            U6014 -W7         A01X+025382Y+153334X0150Y         S1      
317m1206            VIA   -    MD0080PA01X+025115Y+153334X0160Y         S0      
317m1206            VIA   -    MD0100PA01X+034835Y+159238X0180Y         S0      
327m1206            C6655 -2          A01X+034845Y+160729X0120Y0150R270 S1      
327m1206            U6014 -AF7        A01X+024910Y+153334X0150Y         S1      
317m1207            VIA   -    MD0080PA01X+024642Y+153334X0160Y         S0      
317m1207            VIA   -    MD0100PA01X+033629Y+159238X0180Y         S0      
327m1207            C6653 -2          A01X+033639Y+160729X0120Y0150R270 S1      
327m1207            U6014 -AN7        A01X+024437Y+153334X0150Y         S1      
317m1208            VIA   -    MD0080PA01X+024170Y+153334X0160Y         S0      
317m1208            VIA   -    MD0100PA01X+032423Y+159238X0180Y         S0      
327m1208            C6651 -2          A01X+032433Y+160729X0120Y0150R270 S1      
327m1208            U6014 -AY7        A01X+023965Y+153334X0150Y         S1      
317m1209            VIA   -    MD0080PA01X+023697Y+153334X0160Y         S0      
317m1209            VIA   -    MD0100PA01X+031217Y+159238X0180Y         S0      
327m1209            C6649 -2          A01X+031227Y+160729X0120Y0150R270 S1      
327m1209            U6014 -BG7        A01X+023492Y+153334X0150Y         S1      
317m1210            VIA   -    MD0080PA01X+018973Y+153334X0160Y         S0      
317m1210            VIA   -    MD0100PA01X+019157Y+159238X0180Y         S0      
327m1210            C6629 -2          A01X+019167Y+160729X0120Y0150R270 S1      
327m1210            U6014 -EU7        A01X+018768Y+153334X0150Y         S1      
317m1211            VIA   -    MD0080PA01X+023067Y+153061X0160Y         S0      
317m1211            VIA   -    MD0100PA01X+029671Y+159238X0180Y         S0      
327m1211            C6648 -2          A01X+029661Y+160729X0120Y0150R270 S1      
327m1211            U6014 -BT10       A01X+022862Y+153061X0150Y         S1      
317m1212            VIA   -    MD0080PA01X+022595Y+153061X0160Y         S0      
317m1212            VIA   -    MD0100PA01X+028465Y+159238X0180Y         S0      
327m1212            C6646 -2          A01X+028455Y+160729X0120Y0150R270 S1      
327m1212            U6014 -CC10       A01X+022390Y+153061X0150Y         S1      
317m1213            VIA   -    MD0080PA01X+022123Y+153061X0160Y         S0      
317m1213            VIA   -    MD0100PA01X+027259Y+159238X0180Y         S0      
327m1213            C6644 -2          A01X+027249Y+160729X0120Y0150R270 S1      
327m1213            U6014 -CK10       A01X+021918Y+153061X0150Y         S1      
317m1214            VIA   -    MD0080PA01X+021650Y+153061X0160Y         S0      
317m1214            VIA   -    MD0100PA01X+026053Y+159238X0180Y         S0      
327m1214            C6642 -2          A01X+026043Y+160729X0120Y0150R270 S1      
327m1214            U6014 -CU10       A01X+021445Y+153061X0150Y         S1      
317m1215            VIA   -    MD0080PA01X+021178Y+153061X0160Y         S0      
317m1215            VIA   -    MD0100PA01X+024847Y+159238X0180Y         S0      
327m1215            C6640 -2          A01X+024837Y+160729X0120Y0150R270 S1      
327m1215            U6014 -DD10       A01X+020973Y+153061X0150Y         S1      
317m1216            VIA   -    MD0080PA01X+020705Y+153061X0160Y         S0      
317m1216            VIA   -    MD0100PA01X+023641Y+159238X0180Y         S0      
327m1216            C6638 -2          A01X+023631Y+160729X0120Y0150R270 S1      
327m1216            U6014 -DL10       A01X+020500Y+153061X0150Y         S1      
317m1217            VIA   -    MD0080PA01X+020233Y+153061X0160Y         S0      
317m1217            VIA   -    MD0100PA01X+022435Y+159238X0180Y         S0      
327m1217            C6636 -2          A01X+022425Y+160729X0120Y0150R270 S1      
327m1217            U6014 -DV10       A01X+020028Y+153061X0150Y         S1      
317m1218            VIA   -    MD0080PA01X+019760Y+153061X0160Y         S0      
317m1218            VIA   -    MD0100PA01X+021229Y+159238X0180Y         S0      
327m1218            C6634 -2          A01X+021219Y+160729X0120Y0150R270 S1      
327m1218            U6014 -EE10       A01X+019555Y+153061X0150Y         S1      
317m1219            VIA   -    MD0080PA01X+019288Y+153061X0160Y         S0      
317m1219            VIA   -    MD0100PA01X+020023Y+159238X0180Y         S0      
327m1219            C6632 -2          A01X+020013Y+160729X0120Y0150R270 S1      
327m1219            U6014 -EM10       A01X+019083Y+153061X0150Y         S1      
317m1220            VIA   -    MD0080PA01X+025902Y+153061X0160Y         S0      
317m1220            VIA   -    MD0100PA01X+036907Y+159238X0180Y         S0      
327m1220            C6660 -2          A01X+036897Y+160729X0120Y0150R270 S1      
327m1220            U6014 -P10        A01X+025697Y+153061X0150Y         S1      
317m1221            VIA   -    MD0080PA01X+025430Y+153061X0160Y         S0      
317m1221            VIA   -    MD0100PA01X+035701Y+159238X0180Y         S0      
327m1221            C6658 -2          A01X+035691Y+160729X0120Y0150R270 S1      
327m1221            U6014 -AA10       A01X+025225Y+153061X0150Y         S1      
317m1222            VIA   -    MD0080PA01X+024957Y+153061X0160Y         S0      
317m1222            VIA   -    MD0100PA01X+034495Y+159238X0180Y         S0      
327m1222            C6656 -2          A01X+034485Y+160729X0120Y0150R270 S1      
327m1222            U6014 -AH10       A01X+024752Y+153061X0150Y         S1      
317m1223            VIA   -    MD0080PA01X+024485Y+153061X0160Y         S0      
317m1223            VIA   -    MD0100PA01X+033289Y+159238X0180Y         S0      
327m1223            C6654 -2          A01X+033279Y+160729X0120Y0150R270 S1      
327m1223            U6014 -AR10       A01X+024280Y+153061X0150Y         S1      
317m1224            VIA   -    MD0080PA01X+024012Y+153061X0160Y         S0      
317m1224            VIA   -    MD0100PA01X+032083Y+159238X0180Y         S0      
327m1224            C6652 -2          A01X+032073Y+160729X0120Y0150R270 S1      
327m1224            U6014 -BB10       A01X+023807Y+153061X0150Y         S1      
317m1225            VIA   -    MD0080PA01X+023540Y+153061X0160Y         S0      
317m1225            VIA   -    MD0100PA01X+030877Y+159238X0180Y         S0      
327m1225            C6650 -2          A01X+030867Y+160729X0120Y0150R270 S1      
327m1225            U6014 -BJ10       A01X+023335Y+153061X0150Y         S1      
317m1226            VIA   -    MD0080PA01X+018816Y+153061X0160Y         S0      
317m1226            VIA   -    MD0100PA01X+018817Y+159238X0180Y         S0      
327m1226            C6630 -2          A01X+018807Y+160729X0120Y0150R270 S1      
327m1226            U6014 -EW10       A01X+018610Y+153061X0150Y         S1      
317m1227            VIA   -    MD0100PA01X+030011Y+162429X0180Y         S0      
327m1227            C6647 -1          A01X+030021Y+160939X0120Y0150R270 S1      
317m1227            J111  -I2   D0142PA01X+030571Y+169563X0302Y    R180 S3      
317m1228            VIA   -    MD0100PA01X+028805Y+162429X0180Y         S0      
327m1228            C6645 -1          A01X+028815Y+160939X0120Y0150R270 S1      
317m1228            J111  -J1   D0142PA01X+029784Y+169169X0302Y    R180 S3      
317m1229            VIA   -    MD0100PA01X+027599Y+162429X0180Y         S0      
327m1229            C6643 -1          A01X+027609Y+160939X0120Y0150R270 S1      
317m1229            J112  -I8   D0142PA01X+028602Y+169563X0302Y    R180 S3      
317m1230            VIA   -    MD0100PA01X+026393Y+162429X0180Y         S0      
327m1230            C6641 -1          A01X+026403Y+160939X0120Y0150R270 S1      
317m1230            J112  -J7   D0142PA01X+027815Y+169169X0302Y    R180 S3      
317m1231            VIA   -    MD0100PA01X+025187Y+162429X0180Y         S0      
327m1231            C6639 -1          A01X+025197Y+160939X0120Y0150R270 S1      
317m1231            J112  -I6   D0142PA01X+027028Y+169563X0302Y    R180 S3      
317m1232            VIA   -    MD0100PA01X+023981Y+162429X0180Y         S0      
327m1232            C6637 -1          A01X+023991Y+160939X0120Y0150R270 S1      
317m1232            J112  -J5   D0142PA01X+026240Y+169169X0302Y    R180 S3      
317m1233            VIA   -    MD0100PA01X+022775Y+162429X0180Y         S0      
327m1233            C6635 -1          A01X+022785Y+160939X0120Y0150R270 S1      
317m1233            J112  -I4   D0142PA01X+025453Y+169563X0302Y    R180 S3      
317m1234            VIA   -    MD0100PA01X+021569Y+162429X0180Y         S0      
327m1234            C6633 -1          A01X+021579Y+160939X0120Y0150R270 S1      
317m1234            J112  -J3   D0142PA01X+024665Y+169169X0302Y    R180 S3      
317m1235            VIA   -    MD0100PA01X+020363Y+162429X0180Y         S0      
327m1235            C6631 -1          A01X+020373Y+160939X0120Y0150R270 S1      
317m1235            J112  -I2   D0142PA01X+023878Y+169563X0302Y    R180 S3      
317m1236            VIA   -    MD0100PA01X+037247Y+162429X0180Y         S0      
327m1236            C6659 -1          A01X+037257Y+160939X0120Y0150R270 S1      
317m1236            J111  -I8   D0142PA01X+035295Y+169563X0302Y    R180 S3      
317m1237            VIA   -    MD0100PA01X+036041Y+162429X0180Y         S0      
327m1237            C6657 -1          A01X+036051Y+160939X0120Y0150R270 S1      
317m1237            J111  -J7   D0142PA01X+034508Y+169169X0302Y    R180 S3      
317m1238            VIA   -    MD0100PA01X+034835Y+162429X0180Y         S0      
327m1238            C6655 -1          A01X+034845Y+160939X0120Y0150R270 S1      
317m1238            J111  -I6   D0142PA01X+033720Y+169563X0302Y    R180 S3      
317m1239            VIA   -    MD0100PA01X+033629Y+162429X0180Y         S0      
327m1239            C6653 -1          A01X+033639Y+160939X0120Y0150R270 S1      
317m1239            J111  -J5   D0142PA01X+032933Y+169169X0302Y    R180 S3      
317m1240            VIA   -    MD0100PA01X+032423Y+162429X0180Y         S0      
327m1240            C6651 -1          A01X+032433Y+160939X0120Y0150R270 S1      
317m1240            J111  -I4   D0142PA01X+032146Y+169563X0302Y    R180 S3      
317m1241            VIA   -    MD0100PA01X+031217Y+162429X0180Y         S0      
327m1241            C6649 -1          A01X+031227Y+160939X0120Y0150R270 S1      
317m1241            J111  -J3   D0142PA01X+031358Y+169169X0302Y    R180 S3      
317m1242            VIA   -    MD0100PA01X+019157Y+162429X0180Y         S0      
327m1242            C6629 -1          A01X+019167Y+160939X0120Y0150R270 S1      
317m1242            J112  -J1   D0142PA01X+023090Y+169169X0302Y    R180 S3      
317m1243            VIA   -    MD0100PA01X+029671Y+162429X0180Y         S0      
327m1243            C6648 -1          A01X+029661Y+160939X0120Y0150R270 S1      
317m1243            J111  -H2   D0142PA01X+030571Y+170035X0302Y    R180 S3      
317m1244            VIA   -    MD0100PA01X+028465Y+162429X0180Y         S0      
327m1244            C6646 -1          A01X+028455Y+160939X0120Y0150R270 S1      
317m1244            J111  -I1   D0142PA01X+029784Y+169642X0302Y    R180 S3      
317m1245            VIA   -    MD0100PA01X+027259Y+162429X0180Y         S0      
327m1245            C6644 -1          A01X+027249Y+160939X0120Y0150R270 S1      
317m1245            J112  -H8   D0142PA01X+028602Y+170035X0302Y    R180 S3      
317m1246            VIA   -    MD0100PA01X+026053Y+162429X0180Y         S0      
327m1246            C6642 -1          A01X+026043Y+160939X0120Y0150R270 S1      
317m1246            J112  -I7   D0142PA01X+027815Y+169642X0302Y    R180 S3      
317m1247            VIA   -    MD0100PA01X+024847Y+162429X0180Y         S0      
327m1247            C6640 -1          A01X+024837Y+160939X0120Y0150R270 S1      
317m1247            J112  -H6   D0142PA01X+027028Y+170035X0302Y    R180 S3      
317m1248            VIA   -    MD0100PA01X+023641Y+162429X0180Y         S0      
327m1248            C6638 -1          A01X+023631Y+160939X0120Y0150R270 S1      
317m1248            J112  -I5   D0142PA01X+026240Y+169642X0302Y    R180 S3      
317m1249            VIA   -    MD0100PA01X+022435Y+162429X0180Y         S0      
327m1249            C6636 -1          A01X+022425Y+160939X0120Y0150R270 S1      
317m1249            J112  -H4   D0142PA01X+025453Y+170035X0302Y    R180 S3      
317m1250            VIA   -    MD0100PA01X+021229Y+162429X0180Y         S0      
327m1250            C6634 -1          A01X+021219Y+160939X0120Y0150R270 S1      
317m1250            J112  -I3   D0142PA01X+024665Y+169642X0302Y    R180 S3      
317m1251            VIA   -    MD0100PA01X+020023Y+162429X0180Y         S0      
327m1251            C6632 -1          A01X+020013Y+160939X0120Y0150R270 S1      
317m1251            J112  -H2   D0142PA01X+023878Y+170035X0302Y    R180 S3      
317m1252            VIA   -    MD0100PA01X+036907Y+162429X0180Y         S0      
327m1252            C6660 -1          A01X+036897Y+160939X0120Y0150R270 S1      
317m1252            J111  -H8   D0142PA01X+035295Y+170035X0302Y    R180 S3      
317m1253            VIA   -    MD0100PA01X+035701Y+162429X0180Y         S0      
327m1253            C6658 -1          A01X+035691Y+160939X0120Y0150R270 S1      
317m1253            J111  -I7   D0142PA01X+034508Y+169642X0302Y    R180 S3      
317m1254            VIA   -    MD0100PA01X+034495Y+162429X0180Y         S0      
327m1254            C6656 -1          A01X+034485Y+160939X0120Y0150R270 S1      
317m1254            J111  -H6   D0142PA01X+033720Y+170035X0302Y    R180 S3      
317m1255            VIA   -    MD0100PA01X+033289Y+162429X0180Y         S0      
327m1255            C6654 -1          A01X+033279Y+160939X0120Y0150R270 S1      
317m1255            J111  -I5   D0142PA01X+032933Y+169642X0302Y    R180 S3      
317m1256            VIA   -    MD0100PA01X+032083Y+162429X0180Y         S0      
327m1256            C6652 -1          A01X+032073Y+160939X0120Y0150R270 S1      
317m1256            J111  -H4   D0142PA01X+032146Y+170035X0302Y    R180 S3      
317m1257            VIA   -    MD0100PA01X+030877Y+162429X0180Y         S0      
327m1257            C6650 -1          A01X+030867Y+160939X0120Y0150R270 S1      
317m1257            J111  -I3   D0142PA01X+031358Y+169642X0302Y    R180 S3      
317m1258            VIA   -    MD0100PA01X+018817Y+162429X0180Y         S0      
327m1258            C6630 -1          A01X+018807Y+160939X0120Y0150R270 S1      
317m1258            J112  -I1   D0142PA01X+023090Y+169642X0302Y    R180 S3      
317m1259            VIA   -    MD0100PA01X+023077Y+154840X0180Y         S0      
317m1259            J111  -C2   D0142PA01X+030571Y+172398X0302Y    R180 S3      
327m1259            U6014 -BU1        A01X+022802Y+154048X0100Y0130     S1      
317m1260            VIA   -    MD0100PA01X+022605Y+154840X0180Y         S0      
317m1260            J111  -D1   D0142PA01X+029784Y+172004X0302Y    R180 S3      
327m1260            U6014 -CD1        A01X+022330Y+154048X0100Y0130     S1      
317m1261            VIA   -    MD0100PA01X+022132Y+154840X0180Y         S0      
317m1261            J112  -C8   D0142PA01X+028602Y+172398X0302Y    R180 S3      
327m1261            U6014 -CL1        A01X+021858Y+154048X0100Y0130     S1      
317m1262            VIA   -    MD0100PA01X+021660Y+154840X0180Y         S0      
317m1262            J112  -D7   D0142PA01X+027815Y+172004X0302Y    R180 S3      
327m1262            U6014 -CV1        A01X+021385Y+154048X0100Y0130     S1      
317m1263            VIA   -    MD0100PA01X+021188Y+154840X0180Y         S0      
317m1263            J112  -C6   D0142PA01X+027028Y+172398X0302Y    R180 S3      
327m1263            U6014 -DE1        A01X+020913Y+154048X0100Y0130     S1      
317m1264            VIA   -    MD0100PA01X+020715Y+154840X0180Y         S0      
317m1264            J112  -D5   D0142PA01X+026240Y+172004X0302Y    R180 S3      
327m1264            U6014 -DM1        A01X+020440Y+154048X0100Y0130     S1      
317m1265            VIA   -    MD0100PA01X+020243Y+154840X0180Y         S0      
317m1265            J112  -C4   D0142PA01X+025453Y+172398X0302Y    R180 S3      
327m1265            U6014 -DW1        A01X+019968Y+154048X0100Y0130     S1      
317m1266            VIA   -    MD0100PA01X+019770Y+154840X0180Y         S0      
317m1266            J112  -D3   D0142PA01X+024665Y+172004X0302Y    R180 S3      
327m1266            U6014 -EF1        A01X+019495Y+154048X0100Y0130     S1      
317m1267            VIA   -    MD0100PA01X+019298Y+154840X0180Y         S0      
317m1267            J112  -C2   D0142PA01X+023878Y+172398X0302Y    R180 S3      
327m1267            U6014 -EN1        A01X+019023Y+154048X0100Y0130     S1      
317m1268            VIA   -    MD0100PA01X+025912Y+154840X0180Y         S0      
317m1268            J111  -C8   D0142PA01X+035295Y+172398X0302Y    R180 S3      
327m1268            U6014 -R1         A01X+025637Y+154048X0100Y0130     S1      
317m1269            VIA   -    MD0100PA01X+025440Y+154840X0180Y         S0      
317m1269            J111  -D7   D0142PA01X+034508Y+172004X0302Y    R180 S3      
327m1269            U6014 -AB1        A01X+025165Y+154048X0100Y0130     S1      
317m1270            VIA   -    MD0100PA01X+024967Y+154840X0180Y         S0      
317m1270            J111  -C6   D0142PA01X+033720Y+172398X0302Y    R180 S3      
327m1270            U6014 -AJ1        A01X+024692Y+154048X0100Y0130     S1      
317m1271            VIA   -    MD0100PA01X+024495Y+154840X0180Y         S0      
317m1271            J111  -D5   D0142PA01X+032933Y+172004X0302Y    R180 S3      
327m1271            U6014 -AT1        A01X+024220Y+154048X0100Y0130     S1      
317m1272            VIA   -    MD0100PA01X+024022Y+154840X0180Y         S0      
317m1272            J111  -C4   D0142PA01X+032146Y+172398X0302Y    R180 S3      
327m1272            U6014 -BC1        A01X+023747Y+154048X0100Y0130     S1      
317m1273            VIA   -    MD0100PA01X+023550Y+154840X0180Y         S0      
327m1273            U6014 -BK1        A01X+023275Y+154048X0100Y0130     S1      
317m1273            J111  -D3   D0142PA01X+031358Y+172004X0302Y    R180 S3      
317m1274            VIA   -    MD0100PA01X+018825Y+154840X0180Y         S0      
317m1274            J112  -D1   D0142PA01X+023090Y+172004X0302Y    R180 S3      
327m1274            U6014 -EY1        A01X+018550Y+154048X0100Y0130     S1      
317m1275            VIA   -    MD0100PA01X+023077Y+154500X0180Y         S0      
317m1275            J111  -B2   D0142PA01X+030571Y+172870X0302Y    R180 S3      
327m1275            U6014 -BR2        A01X+022920Y+153843X0120Y         S1      
317m1276            VIA   -    MD0100PA01X+022605Y+154500X0180Y         S0      
317m1276            J111  -C1   D0142PA01X+029784Y+172476X0302Y    R180 S3      
327m1276            U6014 -CB2        A01X+022448Y+153843X0120Y         S1      
317m1277            VIA   -    MD0100PA01X+022132Y+154500X0180Y         S0      
317m1277            J112  -B8   D0142PA01X+028602Y+172870X0302Y    R180 S3      
327m1277            U6014 -CJ2        A01X+021976Y+153843X0120Y         S1      
317m1278            VIA   -    MD0100PA01X+021660Y+154500X0180Y         S0      
317m1278            J112  -C7   D0142PA01X+027815Y+172476X0302Y    R180 S3      
327m1278            U6014 -CT2        A01X+021503Y+153843X0120Y         S1      
317m1279            VIA   -    MD0100PA01X+021188Y+154500X0180Y         S0      
317m1279            J112  -B6   D0142PA01X+027028Y+172870X0302Y    R180 S3      
327m1279            U6014 -DC2        A01X+021031Y+153843X0120Y         S1      
317m1280            VIA   -    MD0100PA01X+020715Y+154500X0180Y         S0      
317m1280            J112  -C5   D0142PA01X+026240Y+172476X0302Y    R180 S3      
327m1280            U6014 -DK2        A01X+020558Y+153843X0120Y         S1      
317m1281            VIA   -    MD0100PA01X+020243Y+154500X0180Y         S0      
317m1281            J112  -B4   D0142PA01X+025453Y+172870X0302Y    R180 S3      
327m1281            U6014 -DU2        A01X+020086Y+153843X0120Y         S1      
317m1282            VIA   -    MD0100PA01X+019770Y+154500X0180Y         S0      
317m1282            J112  -C3   D0142PA01X+024665Y+172476X0302Y    R180 S3      
327m1282            U6014 -ED2        A01X+019613Y+153843X0120Y         S1      
317m1283            VIA   -    MD0100PA01X+019298Y+154500X0180Y         S0      
317m1283            J112  -B2   D0142PA01X+023878Y+172870X0302Y    R180 S3      
327m1283            U6014 -EL2        A01X+019141Y+153843X0120Y         S1      
317m1284            VIA   -    MD0100PA01X+025912Y+154500X0180Y         S0      
317m1284            J111  -B8   D0142PA01X+035295Y+172870X0302Y    R180 S3      
327m1284            U6014 -N2         A01X+025755Y+153843X0120Y         S1      
317m1285            VIA   -    MD0100PA01X+025440Y+154500X0180Y         S0      
317m1285            J111  -C7   D0142PA01X+034508Y+172476X0302Y    R180 S3      
327m1285            U6014 -Y2         A01X+025283Y+153843X0120Y         S1      
317m1286            VIA   -    MD0100PA01X+024967Y+154500X0180Y         S0      
317m1286            J111  -B6   D0142PA01X+033720Y+172870X0302Y    R180 S3      
327m1286            U6014 -AG2        A01X+024810Y+153843X0120Y         S1      
317m1287            VIA   -    MD0100PA01X+024495Y+154500X0180Y         S0      
317m1287            J111  -C5   D0142PA01X+032933Y+172476X0302Y    R180 S3      
327m1287            U6014 -AP2        A01X+024338Y+153843X0120Y         S1      
317m1288            VIA   -    MD0100PA01X+024022Y+154500X0180Y         S0      
317m1288            J111  -B4   D0142PA01X+032146Y+172870X0302Y    R180 S3      
327m1288            U6014 -BA2        A01X+023865Y+153843X0120Y         S1      
317m1289            VIA   -    MD0100PA01X+023550Y+154500X0180Y         S0      
327m1289            U6014 -BH2        A01X+023393Y+153843X0120Y         S1      
317m1289            J111  -C3   D0142PA01X+031358Y+172476X0302Y    R180 S3      
317m1290            VIA   -    MD0100PA01X+018825Y+154500X0180Y         S0      
317m1290            J112  -C1   D0142PA01X+023090Y+172476X0302Y    R180 S3      
327m1290            U6014 -EV2        A01X+018668Y+153843X0120Y         S1      
317m1291            VIA   -    MD0080PA01X+150430Y+156634X0160Y         S0      
317m1291            VIA   -    MD0100PA18X+157818Y+163538X0180Y         S0      
327m1291            C6615 -2          A18X+157828Y+164029X0120Y0150R090 S2      
327m1291            U6013 -BP7        A01X+150225Y+156634X0150Y         S1      
317m1292            VIA   -    MD0080PA01X+149957Y+156634X0160Y         S0      
317m1292            VIA   -    MD0100PA18X+156612Y+163538X0180Y         S0      
327m1292            C6613 -2          A18X+156622Y+164029X0120Y0150R090 S2      
327m1292            U6013 -CA7        A01X+149752Y+156634X0150Y         S1      
317m1293            VIA   -    MD0080PA01X+149485Y+156634X0160Y         S0      
317m1293            VIA   -    MD0100PA18X+155406Y+163538X0180Y         S0      
327m1293            C6611 -2          A18X+155416Y+164029X0120Y0150R090 S2      
327m1293            U6013 -CH7        A01X+149280Y+156634X0150Y         S1      
317m1294            VIA   -    MD0080PA01X+149012Y+156634X0160Y         S0      
317m1294            VIA   -    MD0100PA18X+154200Y+163538X0180Y         S0      
327m1294            C6609 -2          A18X+154210Y+164029X0120Y0150R090 S2      
327m1294            U6013 -CR7        A01X+148807Y+156634X0150Y         S1      
317m1295            VIA   -    MD0080PA01X+148540Y+156634X0160Y         S0      
317m1295            VIA   -    MD0100PA18X+152994Y+163538X0180Y         S0      
327m1295            C6607 -2          A18X+153004Y+164029X0120Y0150R090 S2      
327m1295            U6013 -DB7        A01X+148335Y+156634X0150Y         S1      
317m1296            VIA   -    MD0080PA01X+148067Y+156634X0160Y         S0      
317m1296            VIA   -    MD0100PA18X+151788Y+163538X0180Y         S0      
327m1296            C6605 -2          A18X+151798Y+164029X0120Y0150R090 S2      
327m1296            U6013 -DJ7        A01X+147862Y+156634X0150Y         S1      
317m1297            VIA   -    MD0080PA01X+147595Y+156634X0160Y         S0      
317m1297            VIA   -    MD0100PA18X+150582Y+163538X0180Y         S0      
327m1297            C6603 -2          A18X+150592Y+164029X0120Y0150R090 S2      
327m1297            U6013 -DT7        A01X+147390Y+156634X0150Y         S1      
317m1298            VIA   -    MD0080PA01X+147122Y+156634X0160Y         S0      
317m1298            VIA   -    MD0100PA18X+149376Y+163538X0180Y         S0      
327m1298            C6601 -2          A18X+149386Y+164029X0120Y0150R090 S2      
327m1298            U6013 -EC7        A01X+146918Y+156634X0150Y         S1      
317m1299            VIA   -    MD0080PA01X+146650Y+156634X0160Y         S0      
317m1299            VIA   -    MD0100PA18X+148170Y+163538X0180Y         S0      
327m1299            C6599 -2          A18X+148180Y+164029X0120Y0150R090 S2      
327m1299            U6013 -EK7        A01X+146445Y+156634X0150Y         S1      
317m1300            VIA   -    MD0080PA01X+153264Y+156634X0160Y         S0      
317m1300            VIA   -    MD0100PA18X+165054Y+163538X0180Y         S0      
327m1300            C6627 -2          A18X+165064Y+164029X0120Y0150R090 S2      
327m1300            U6013 -M7         A01X+153059Y+156634X0150Y         S1      
317m1301            VIA   -    MD0080PA01X+152792Y+156634X0160Y         S0      
317m1301            VIA   -    MD0100PA18X+163848Y+163538X0180Y         S0      
327m1301            C6625 -2          A18X+163858Y+164029X0120Y0150R090 S2      
327m1301            U6013 -W7         A01X+152587Y+156634X0150Y         S1      
317m1302            VIA   -    MD0080PA01X+152319Y+156634X0160Y         S0      
317m1302            VIA   -    MD0100PA18X+162642Y+163538X0180Y         S0      
327m1302            C6623 -2          A18X+162652Y+164029X0120Y0150R090 S2      
327m1302            U6013 -AF7        A01X+152114Y+156634X0150Y         S1      
317m1303            VIA   -    MD0080PA01X+151847Y+156634X0160Y         S0      
317m1303            VIA   -    MD0100PA18X+161436Y+163538X0180Y         S0      
327m1303            C6621 -2          A18X+161446Y+164029X0120Y0150R090 S2      
327m1303            U6013 -AN7        A01X+151642Y+156634X0150Y         S1      
317m1304            VIA   -    MD0080PA01X+151374Y+156634X0160Y         S0      
317m1304            VIA   -    MD0100PA18X+160230Y+163538X0180Y         S0      
327m1304            C6619 -2          A18X+160240Y+164029X0120Y0150R090 S2      
327m1304            U6013 -AY7        A01X+151170Y+156634X0150Y         S1      
317m1305            VIA   -    MD0080PA01X+150902Y+156634X0160Y         S0      
317m1305            VIA   -    MD0100PA18X+159024Y+163538X0180Y         S0      
327m1305            C6617 -2          A18X+159034Y+164029X0120Y0150R090 S2      
327m1305            U6013 -BG7        A01X+150697Y+156634X0150Y         S1      
317m1306            VIA   -    MD0080PA01X+146178Y+156634X0160Y         S0      
317m1306            VIA   -    MD0100PA18X+146964Y+163538X0180Y         S0      
327m1306            C6597 -2          A18X+146974Y+164029X0120Y0150R090 S2      
327m1306            U6013 -EU7        A01X+145973Y+156634X0150Y         S1      
317m1307            VIA   -    MD0080PA01X+150272Y+156361X0160Y         S0      
317m1307            VIA   -    MD0100PA18X+157478Y+163538X0180Y         S0      
327m1307            C6616 -2          A18X+157468Y+164029X0120Y0150R090 S2      
327m1307            U6013 -BT10       A01X+150067Y+156361X0150Y         S1      
317m1308            VIA   -    MD0080PA01X+149800Y+156361X0160Y         S0      
317m1308            VIA   -    MD0100PA18X+156272Y+163538X0180Y         S0      
327m1308            C6614 -2          A18X+156262Y+164029X0120Y0150R090 S2      
327m1308            U6013 -CC10       A01X+149595Y+156361X0150Y         S1      
317m1309            VIA   -    MD0080PA01X+149327Y+156361X0160Y         S0      
317m1309            VIA   -    MD0100PA18X+155066Y+163538X0180Y         S0      
327m1309            C6612 -2          A18X+155056Y+164029X0120Y0150R090 S2      
327m1309            U6013 -CK10       A01X+149122Y+156361X0150Y         S1      
317m1310            VIA   -    MD0080PA01X+148855Y+156361X0160Y         S0      
317m1310            VIA   -    MD0100PA18X+153860Y+163538X0180Y         S0      
327m1310            C6610 -2          A18X+153850Y+164029X0120Y0150R090 S2      
327m1310            U6013 -CU10       A01X+148650Y+156361X0150Y         S1      
317m1311            VIA   -    MD0080PA01X+148382Y+156361X0160Y         S0      
317m1311            VIA   -    MD0100PA18X+152654Y+163538X0180Y         S0      
327m1311            C6608 -2          A18X+152644Y+164029X0120Y0150R090 S2      
327m1311            U6013 -DD10       A01X+148177Y+156361X0150Y         S1      
317m1312            VIA   -    MD0080PA01X+147910Y+156361X0160Y         S0      
317m1312            VIA   -    MD0100PA18X+151448Y+163538X0180Y         S0      
327m1312            C6606 -2          A18X+151438Y+164029X0120Y0150R090 S2      
327m1312            U6013 -DL10       A01X+147705Y+156361X0150Y         S1      
317m1313            VIA   -    MD0080PA01X+147438Y+156361X0160Y         S0      
317m1313            VIA   -    MD0100PA18X+150242Y+163538X0180Y         S0      
327m1313            C6604 -2          A18X+150232Y+164029X0120Y0150R090 S2      
327m1313            U6013 -DV10       A01X+147232Y+156361X0150Y         S1      
317m1314            VIA   -    MD0080PA01X+146965Y+156361X0160Y         S0      
317m1314            VIA   -    MD0100PA18X+149036Y+163538X0180Y         S0      
327m1314            C6602 -2          A18X+149026Y+164029X0120Y0150R090 S2      
327m1314            U6013 -EE10       A01X+146760Y+156361X0150Y         S1      
317m1315            VIA   -    MD0080PA01X+146493Y+156361X0160Y         S0      
317m1315            VIA   -    MD0100PA18X+147830Y+163538X0180Y         S0      
327m1315            C6600 -2          A18X+147820Y+164029X0120Y0150R090 S2      
327m1315            U6013 -EM10       A01X+146288Y+156361X0150Y         S1      
317m1316            VIA   -    MD0080PA01X+153107Y+156361X0160Y         S0      
317m1316            VIA   -    MD0100PA18X+164714Y+163538X0180Y         S0      
327m1316            C6628 -2          A18X+164704Y+164029X0120Y0150R090 S2      
327m1316            U6013 -P10        A01X+152902Y+156361X0150Y         S1      
317m1317            VIA   -    MD0080PA01X+152634Y+156361X0160Y         S0      
317m1317            VIA   -    MD0100PA18X+163508Y+163538X0180Y         S0      
327m1317            C6626 -2          A18X+163498Y+164029X0120Y0150R090 S2      
327m1317            U6013 -AA10       A01X+152429Y+156361X0150Y         S1      
317m1318            VIA   -    MD0080PA01X+152162Y+156361X0160Y         S0      
317m1318            VIA   -    MD0100PA18X+162302Y+163538X0180Y         S0      
327m1318            C6624 -2          A18X+162292Y+164029X0120Y0150R090 S2      
327m1318            U6013 -AH10       A01X+151957Y+156361X0150Y         S1      
317m1319            VIA   -    MD0080PA01X+151690Y+156361X0160Y         S0      
317m1319            VIA   -    MD0100PA18X+161096Y+163538X0180Y         S0      
327m1319            C6622 -2          A18X+161086Y+164029X0120Y0150R090 S2      
327m1319            U6013 -AR10       A01X+151484Y+156361X0150Y         S1      
317m1320            VIA   -    MD0080PA01X+151217Y+156361X0160Y         S0      
317m1320            VIA   -    MD0100PA18X+159890Y+163538X0180Y         S0      
327m1320            C6620 -2          A18X+159880Y+164029X0120Y0150R090 S2      
327m1320            U6013 -BB10       A01X+151012Y+156361X0150Y         S1      
317m1321            VIA   -    MD0080PA01X+150745Y+156361X0160Y         S0      
317m1321            VIA   -    MD0100PA18X+158684Y+163538X0180Y         S0      
327m1321            C6618 -2          A18X+158674Y+164029X0120Y0150R090 S2      
327m1321            U6013 -BJ10       A01X+150540Y+156361X0150Y         S1      
317m1322            VIA   -    MD0080PA01X+146020Y+156361X0160Y         S0      
317m1322            VIA   -    MD0100PA18X+146624Y+163538X0180Y         S0      
327m1322            C6598 -2          A18X+146614Y+164029X0120Y0150R090 S2      
327m1322            U6013 -EW10       A01X+145815Y+156361X0150Y         S1      
317m1323            VIA   -    MD0100PA18X+157818Y+164729X0180Y         S0      
317m1323            J105  -L2   D0142PA01X+157776Y+168146X0302Y    R180 S3      
327m1323            C6615 -1          A18X+157828Y+164239X0120Y0150R090 S2      
317m1324            VIA   -    MD0100PA18X+156612Y+164729X0180Y         S0      
317m1324            J105  -M1   D0142PA01X+156988Y+167752X0302Y    R180 S3      
327m1324            C6613 -1          A18X+156622Y+164239X0120Y0150R090 S2      
317m1325            VIA   -    MD0100PA18X+155406Y+164729X0180Y         S0      
317m1325            J106  -L8   D0142PA01X+155807Y+168146X0302Y    R180 S3      
327m1325            C6611 -1          A18X+155416Y+164239X0120Y0150R090 S2      
317m1326            VIA   -    MD0100PA18X+154200Y+164729X0180Y         S0      
317m1326            J106  -M7   D0142PA01X+155020Y+167752X0302Y    R180 S3      
327m1326            C6609 -1          A18X+154210Y+164239X0120Y0150R090 S2      
317m1327            VIA   -    MD0100PA18X+152994Y+164729X0180Y         S0      
317m1327            J106  -L6   D0142PA01X+154232Y+168146X0302Y    R180 S3      
327m1327            C6607 -1          A18X+153004Y+164239X0120Y0150R090 S2      
317m1328            VIA   -    MD0100PA18X+151788Y+164729X0180Y         S0      
317m1328            J106  -M5   D0142PA01X+153445Y+167752X0302Y    R180 S3      
327m1328            C6605 -1          A18X+151798Y+164239X0120Y0150R090 S2      
317m1329            VIA   -    MD0100PA18X+150582Y+164729X0180Y         S0      
317m1329            J106  -L4   D0142PA01X+152657Y+168146X0302Y    R180 S3      
327m1329            C6603 -1          A18X+150592Y+164239X0120Y0150R090 S2      
317m1330            VIA   -    MD0100PA18X+149376Y+164729X0180Y         S0      
317m1330            J106  -M3   D0142PA01X+151870Y+167752X0302Y    R180 S3      
327m1330            C6601 -1          A18X+149386Y+164239X0120Y0150R090 S2      
317m1331            VIA   -    MD0100PA18X+148170Y+164729X0180Y         S0      
317m1331            J106  -L2   D0142PA01X+151083Y+168146X0302Y    R180 S3      
327m1331            C6599 -1          A18X+148180Y+164239X0120Y0150R090 S2      
317m1332            VIA   -    MD0100PA18X+165054Y+164729X0180Y         S0      
317m1332            J105  -L8   D0142PA01X+162500Y+168146X0302Y    R180 S3      
327m1332            C6627 -1          A18X+165064Y+164239X0120Y0150R090 S2      
317m1333            VIA   -    MD0100PA18X+163848Y+164729X0180Y         S0      
317m1333            J105  -M7   D0142PA01X+161713Y+167752X0302Y    R180 S3      
327m1333            C6625 -1          A18X+163858Y+164239X0120Y0150R090 S2      
317m1334            VIA   -    MD0100PA18X+162642Y+164729X0180Y         S0      
317m1334            J105  -L6   D0142PA01X+160925Y+168146X0302Y    R180 S3      
327m1334            C6623 -1          A18X+162652Y+164239X0120Y0150R090 S2      
317m1335            VIA   -    MD0100PA18X+161436Y+164729X0180Y         S0      
317m1335            J105  -M5   D0142PA01X+160138Y+167752X0302Y    R180 S3      
327m1335            C6621 -1          A18X+161446Y+164239X0120Y0150R090 S2      
317m1336            VIA   -    MD0100PA18X+160230Y+164729X0180Y         S0      
317m1336            J105  -L4   D0142PA01X+159350Y+168146X0302Y    R180 S3      
327m1336            C6619 -1          A18X+160240Y+164239X0120Y0150R090 S2      
317m1337            VIA   -    MD0100PA18X+159024Y+164729X0180Y         S0      
317m1337            J105  -M3   D0142PA01X+158563Y+167752X0302Y    R180 S3      
327m1337            C6617 -1          A18X+159034Y+164239X0120Y0150R090 S2      
317m1338            VIA   -    MD0100PA18X+146964Y+164729X0180Y         S0      
317m1338            J106  -M1   D0142PA01X+150295Y+167752X0302Y    R180 S3      
327m1338            C6597 -1          A18X+146974Y+164239X0120Y0150R090 S2      
317m1339            VIA   -    MD0100PA18X+157478Y+164729X0180Y         S0      
317m1339            J105  -K2   D0142PA01X+157776Y+168618X0302Y    R180 S3      
327m1339            C6616 -1          A18X+157468Y+164239X0120Y0150R090 S2      
317m1340            VIA   -    MD0100PA18X+156272Y+164729X0180Y         S0      
317m1340            J105  -L1   D0142PA01X+156988Y+168224X0302Y    R180 S3      
327m1340            C6614 -1          A18X+156262Y+164239X0120Y0150R090 S2      
317m1341            VIA   -    MD0100PA18X+155066Y+164729X0180Y         S0      
317m1341            J106  -K8   D0142PA01X+155807Y+168618X0302Y    R180 S3      
327m1341            C6612 -1          A18X+155056Y+164239X0120Y0150R090 S2      
317m1342            VIA   -    MD0100PA18X+153860Y+164729X0180Y         S0      
317m1342            J106  -L7   D0142PA01X+155020Y+168224X0302Y    R180 S3      
327m1342            C6610 -1          A18X+153850Y+164239X0120Y0150R090 S2      
317m1343            VIA   -    MD0100PA18X+152654Y+164729X0180Y         S0      
317m1343            J106  -K6   D0142PA01X+154232Y+168618X0302Y    R180 S3      
327m1343            C6608 -1          A18X+152644Y+164239X0120Y0150R090 S2      
317m1344            VIA   -    MD0100PA18X+151448Y+164729X0180Y         S0      
317m1344            J106  -L5   D0142PA01X+153445Y+168224X0302Y    R180 S3      
327m1344            C6606 -1          A18X+151438Y+164239X0120Y0150R090 S2      
317m1345            VIA   -    MD0100PA18X+150242Y+164729X0180Y         S0      
317m1345            J106  -K4   D0142PA01X+152657Y+168618X0302Y    R180 S3      
327m1345            C6604 -1          A18X+150232Y+164239X0120Y0150R090 S2      
317m1346            VIA   -    MD0100PA18X+149036Y+164729X0180Y         S0      
317m1346            J106  -L3   D0142PA01X+151870Y+168224X0302Y    R180 S3      
327m1346            C6602 -1          A18X+149026Y+164239X0120Y0150R090 S2      
317m1347            VIA   -    MD0100PA18X+147830Y+164729X0180Y         S0      
317m1347            J106  -K2   D0142PA01X+151083Y+168618X0302Y    R180 S3      
327m1347            C6600 -1          A18X+147820Y+164239X0120Y0150R090 S2      
317m1348            VIA   -    MD0100PA18X+164714Y+164729X0180Y         S0      
317m1348            J105  -K8   D0142PA01X+162500Y+168618X0302Y    R180 S3      
327m1348            C6628 -1          A18X+164704Y+164239X0120Y0150R090 S2      
317m1349            VIA   -    MD0100PA18X+163508Y+164729X0180Y         S0      
317m1349            J105  -L7   D0142PA01X+161713Y+168224X0302Y    R180 S3      
327m1349            C6626 -1          A18X+163498Y+164239X0120Y0150R090 S2      
317m1350            VIA   -    MD0100PA18X+162302Y+164729X0180Y         S0      
317m1350            J105  -K6   D0142PA01X+160925Y+168618X0302Y    R180 S3      
327m1350            C6624 -1          A18X+162292Y+164239X0120Y0150R090 S2      
317m1351            VIA   -    MD0100PA18X+161096Y+164729X0180Y         S0      
317m1351            J105  -L5   D0142PA01X+160138Y+168224X0302Y    R180 S3      
327m1351            C6622 -1          A18X+161086Y+164239X0120Y0150R090 S2      
317m1352            VIA   -    MD0100PA18X+159890Y+164729X0180Y         S0      
317m1352            J105  -K4   D0142PA01X+159350Y+168618X0302Y    R180 S3      
327m1352            C6620 -1          A18X+159880Y+164239X0120Y0150R090 S2      
317m1353            VIA   -    MD0100PA18X+158684Y+164729X0180Y         S0      
317m1353            J105  -L3   D0142PA01X+158563Y+168224X0302Y    R180 S3      
327m1353            C6618 -1          A18X+158674Y+164239X0120Y0150R090 S2      
317m1354            VIA   -    MD0100PA18X+146624Y+164729X0180Y         S0      
317m1354            J106  -L1   D0142PA01X+150295Y+168224X0302Y    R180 S3      
327m1354            C6598 -1          A18X+146614Y+164239X0120Y0150R090 S2      
317m1355            VIA   -    MD0100PA01X+150282Y+158140X0180Y         S0      
327m1355            U6013 -BU1        A01X+150007Y+157348X0100Y0130     S1      
317m1355            J105  -F2   D0142PA01X+157776Y+170980X0302Y    R180 S3      
317m1356            VIA   -    MD0100PA01X+149810Y+158140X0180Y         S0      
327m1356            U6013 -CD1        A01X+149535Y+157348X0100Y0130     S1      
317m1356            J105  -G1   D0142PA01X+156988Y+170587X0302Y    R180 S3      
317m1357            VIA   -    MD0100PA01X+149337Y+158140X0180Y         S0      
327m1357            U6013 -CL1        A01X+149062Y+157348X0100Y0130     S1      
317m1357            J106  -F8   D0142PA01X+155807Y+170980X0302Y    R180 S3      
317m1358            VIA   -    MD0100PA01X+148865Y+158140X0180Y         S0      
327m1358            U6013 -CV1        A01X+148590Y+157348X0100Y0130     S1      
317m1358            J106  -G7   D0142PA01X+155020Y+170587X0302Y    R180 S3      
317m1359            VIA   -    MD0100PA01X+148392Y+158140X0180Y         S0      
327m1359            U6013 -DE1        A01X+148117Y+157348X0100Y0130     S1      
317m1359            J106  -F6   D0142PA01X+154232Y+170980X0302Y    R180 S3      
317m1360            VIA   -    MD0100PA01X+147920Y+158140X0180Y         S0      
327m1360            U6013 -DM1        A01X+147645Y+157348X0100Y0130     S1      
317m1360            J106  -G5   D0142PA01X+153445Y+170587X0302Y    R180 S3      
317m1361            VIA   -    MD0100PA01X+147447Y+158140X0180Y         S0      
327m1361            U6013 -DW1        A01X+147172Y+157348X0100Y0130     S1      
317m1361            J106  -F4   D0142PA01X+152657Y+170980X0302Y    R180 S3      
317m1362            VIA   -    MD0100PA01X+146975Y+158140X0180Y         S0      
327m1362            U6013 -EF1        A01X+146700Y+157348X0100Y0130     S1      
317m1362            J106  -G3   D0142PA01X+151870Y+170587X0302Y    R180 S3      
317m1363            VIA   -    MD0100PA01X+146502Y+158140X0180Y         S0      
327m1363            U6013 -EN1        A01X+146228Y+157348X0100Y0130     S1      
317m1363            J106  -F2   D0142PA01X+151083Y+170980X0302Y    R180 S3      
317m1364            VIA   -    MD0100PA01X+153117Y+158140X0180Y         S0      
327m1364            U6013 -R1         A01X+152842Y+157348X0100Y0130     S1      
317m1364            J105  -F8   D0142PA01X+162500Y+170980X0302Y    R180 S3      
317m1365            VIA   -    MD0100PA01X+152644Y+158140X0180Y         S0      
327m1365            U6013 -AB1        A01X+152369Y+157348X0100Y0130     S1      
317m1365            J105  -G7   D0142PA01X+161713Y+170587X0302Y    R180 S3      
317m1366            VIA   -    MD0100PA01X+152172Y+158140X0180Y         S0      
327m1366            U6013 -AJ1        A01X+151897Y+157348X0100Y0130     S1      
317m1366            J105  -F6   D0142PA01X+160925Y+170980X0302Y    R180 S3      
317m1367            VIA   -    MD0100PA01X+151699Y+158140X0180Y         S0      
327m1367            U6013 -AT1        A01X+151424Y+157348X0100Y0130     S1      
317m1367            J105  -G5   D0142PA01X+160138Y+170587X0302Y    R180 S3      
317m1368            VIA   -    MD0100PA01X+151227Y+158140X0180Y         S0      
327m1368            U6013 -BC1        A01X+150952Y+157348X0100Y0130     S1      
317m1368            J105  -F4   D0142PA01X+159350Y+170980X0302Y    R180 S3      
317m1369            VIA   -    MD0100PA01X+150755Y+158140X0180Y         S0      
327m1369            U6013 -BK1        A01X+150480Y+157348X0100Y0130     S1      
317m1369            J105  -G3   D0142PA01X+158563Y+170587X0302Y    R180 S3      
317m1370            VIA   -    MD0100PA01X+146030Y+158140X0180Y         S0      
327m1370            U6013 -EY1        A01X+145755Y+157348X0100Y0130     S1      
317m1370            J106  -G1   D0142PA01X+150295Y+170587X0302Y    R180 S3      
317m1371            VIA   -    MD0100PA01X+150282Y+157800X0180Y         S0      
327m1371            U6013 -BR2        A01X+150125Y+157143X0120Y         S1      
317m1371            J105  -E2   D0142PA01X+157776Y+171453X0302Y    R180 S3      
317m1372            VIA   -    MD0100PA01X+149810Y+157800X0180Y         S0      
327m1372            U6013 -CB2        A01X+149653Y+157143X0120Y         S1      
317m1372            J105  -F1   D0142PA01X+156988Y+171059X0302Y    R180 S3      
317m1373            VIA   -    MD0100PA01X+149337Y+157800X0180Y         S0      
327m1373            U6013 -CJ2        A01X+149180Y+157143X0120Y         S1      
317m1373            J106  -E8   D0142PA01X+155807Y+171453X0302Y    R180 S3      
317m1374            VIA   -    MD0100PA01X+148865Y+157800X0180Y         S0      
327m1374            U6013 -CT2        A01X+148708Y+157143X0120Y         S1      
317m1374            J106  -F7   D0142PA01X+155020Y+171059X0302Y    R180 S3      
317m1375            VIA   -    MD0100PA01X+148392Y+157800X0180Y         S0      
327m1375            U6013 -DC2        A01X+148235Y+157143X0120Y         S1      
317m1375            J106  -E6   D0142PA01X+154232Y+171453X0302Y    R180 S3      
317m1376            VIA   -    MD0100PA01X+147920Y+157800X0180Y         S0      
327m1376            U6013 -DK2        A01X+147763Y+157143X0120Y         S1      
317m1376            J106  -F5   D0142PA01X+153445Y+171059X0302Y    R180 S3      
317m1377            VIA   -    MD0100PA01X+147447Y+157800X0180Y         S0      
327m1377            U6013 -DU2        A01X+147290Y+157143X0120Y         S1      
317m1377            J106  -E4   D0142PA01X+152657Y+171453X0302Y    R180 S3      
317m1378            VIA   -    MD0100PA01X+146975Y+157800X0180Y         S0      
327m1378            U6013 -ED2        A01X+146818Y+157143X0120Y         S1      
317m1378            J106  -F3   D0142PA01X+151870Y+171059X0302Y    R180 S3      
317m1379            VIA   -    MD0100PA01X+146502Y+157800X0180Y         S0      
327m1379            U6013 -EL2        A01X+146346Y+157143X0120Y         S1      
317m1379            J106  -E2   D0142PA01X+151083Y+171453X0302Y    R180 S3      
317m1380            VIA   -    MD0100PA01X+153117Y+157800X0180Y         S0      
327m1380            U6013 -N2         A01X+152960Y+157143X0120Y         S1      
317m1380            J105  -E8   D0142PA01X+162500Y+171453X0302Y    R180 S3      
317m1381            VIA   -    MD0100PA01X+152644Y+157800X0180Y         S0      
327m1381            U6013 -Y2         A01X+152487Y+157143X0120Y         S1      
317m1381            J105  -F7   D0142PA01X+161713Y+171059X0302Y    R180 S3      
317m1382            VIA   -    MD0100PA01X+152172Y+157800X0180Y         S0      
327m1382            U6013 -AG2        A01X+152015Y+157143X0120Y         S1      
317m1382            J105  -E6   D0142PA01X+160925Y+171453X0302Y    R180 S3      
317m1383            VIA   -    MD0100PA01X+151699Y+157800X0180Y         S0      
327m1383            U6013 -AP2        A01X+151542Y+157143X0120Y         S1      
317m1383            J105  -F5   D0142PA01X+160138Y+171059X0302Y    R180 S3      
317m1384            VIA   -    MD0100PA01X+151227Y+157800X0180Y         S0      
327m1384            U6013 -BA2        A01X+151070Y+157143X0120Y         S1      
317m1384            J105  -E4   D0142PA01X+159350Y+171453X0302Y    R180 S3      
317m1385            VIA   -    MD0100PA01X+150755Y+157800X0180Y         S0      
327m1385            U6013 -BH2        A01X+150598Y+157143X0120Y         S1      
317m1385            J105  -F3   D0142PA01X+158563Y+171059X0302Y    R180 S3      
317m1386            VIA   -    MD0100PA01X+146030Y+157800X0180Y         S0      
327m1386            U6013 -EV2        A01X+145873Y+157143X0120Y         S1      
317m1386            J106  -F1   D0142PA01X+150295Y+171059X0302Y    R180 S3      
317m1387            VIA   -    MD0080PA01X+163236Y+156634X0160Y         S0      
317m1387            VIA   -    MD0100PA01X+157215Y+162538X0180Y         S0      
327m1387            C6583 -2          A01X+157225Y+164029X0120Y0150R270 S1      
327m1387            U6012 -BP7        A01X+163031Y+156634X0150Y         S1      
317m1388            VIA   -    MD0080PA01X+162763Y+156634X0160Y         S0      
317m1388            VIA   -    MD0100PA01X+156009Y+162538X0180Y         S0      
327m1388            C6581 -2          A01X+156019Y+164029X0120Y0150R270 S1      
327m1388            U6012 -CA7        A01X+162558Y+156634X0150Y         S1      
317m1389            VIA   -    MD0080PA01X+162291Y+156634X0160Y         S0      
317m1389            VIA   -    MD0100PA01X+154803Y+162538X0180Y         S0      
327m1389            C6579 -2          A01X+154813Y+164029X0120Y0150R270 S1      
327m1389            U6012 -CH7        A01X+162086Y+156634X0150Y         S1      
317m1390            VIA   -    MD0080PA01X+161818Y+156634X0160Y         S0      
317m1390            VIA   -    MD0100PA01X+153597Y+162538X0180Y         S0      
327m1390            C6577 -2          A01X+153607Y+164029X0120Y0150R270 S1      
327m1390            U6012 -CR7        A01X+161614Y+156634X0150Y         S1      
317m1391            VIA   -    MD0080PA01X+161346Y+156634X0160Y         S0      
317m1391            VIA   -    MD0100PA01X+152391Y+162538X0180Y         S0      
327m1391            C6575 -2          A01X+152401Y+164029X0120Y0150R270 S1      
327m1391            U6012 -DB7        A01X+161141Y+156634X0150Y         S1      
317m1392            VIA   -    MD0080PA01X+160874Y+156634X0160Y         S0      
317m1392            VIA   -    MD0100PA01X+151185Y+162538X0180Y         S0      
327m1392            C6573 -2          A01X+151195Y+164029X0120Y0150R270 S1      
327m1392            U6012 -DJ7        A01X+160669Y+156634X0150Y         S1      
317m1393            VIA   -    MD0080PA01X+160401Y+156634X0160Y         S0      
317m1393            VIA   -    MD0100PA01X+149979Y+162538X0180Y         S0      
327m1393            C6571 -2          A01X+149989Y+164029X0120Y0150R270 S1      
327m1393            U6012 -DT7        A01X+160196Y+156634X0150Y         S1      
317m1394            VIA   -    MD0080PA01X+159929Y+156634X0160Y         S0      
317m1394            VIA   -    MD0100PA01X+148773Y+162538X0180Y         S0      
327m1394            C6569 -2          A01X+148783Y+164029X0120Y0150R270 S1      
327m1394            U6012 -EC7        A01X+159724Y+156634X0150Y         S1      
317m1395            VIA   -    MD0080PA01X+159456Y+156634X0160Y         S0      
317m1395            VIA   -    MD0100PA01X+147567Y+162538X0180Y         S0      
327m1395            C6567 -2          A01X+147577Y+164029X0120Y0150R270 S1      
327m1395            U6012 -EK7        A01X+159251Y+156634X0150Y         S1      
317m1396            VIA   -    MD0080PA01X+166070Y+156634X0160Y         S0      
317m1396            VIA   -    MD0100PA01X+164451Y+162538X0180Y         S0      
327m1396            C6595 -2          A01X+164461Y+164029X0120Y0150R270 S1      
327m1396            U6012 -M7         A01X+165866Y+156634X0150Y         S1      
317m1397            VIA   -    MD0080PA01X+165598Y+156634X0160Y         S0      
317m1397            VIA   -    MD0100PA01X+163245Y+162538X0180Y         S0      
327m1397            C6593 -2          A01X+163255Y+164029X0120Y0150R270 S1      
327m1397            U6012 -W7         A01X+165393Y+156634X0150Y         S1      
317m1398            VIA   -    MD0080PA01X+165126Y+156634X0160Y         S0      
317m1398            VIA   -    MD0100PA01X+162039Y+162538X0180Y         S0      
327m1398            C6591 -2          A01X+162049Y+164029X0120Y0150R270 S1      
327m1398            U6012 -AF7        A01X+164921Y+156634X0150Y         S1      
317m1399            VIA   -    MD0080PA01X+164653Y+156634X0160Y         S0      
317m1399            VIA   -    MD0100PA01X+160833Y+162538X0180Y         S0      
327m1399            U6012 -AN7        A01X+164448Y+156634X0150Y         S1      
327m1399            C6589 -2          A01X+160843Y+164029X0120Y0150R270 S1      
317m1400            VIA   -    MD0080PA01X+164181Y+156634X0160Y         S0      
317m1400            VIA   -    MD0100PA01X+159627Y+162538X0180Y         S0      
327m1400            C6587 -2          A01X+159637Y+164029X0120Y0150R270 S1      
327m1400            U6012 -AY7        A01X+163976Y+156634X0150Y         S1      
317m1401            VIA   -    MD0080PA01X+163708Y+156634X0160Y         S0      
317m1401            VIA   -    MD0100PA01X+158421Y+162538X0180Y         S0      
327m1401            U6012 -BG7        A01X+163503Y+156634X0150Y         S1      
327m1401            C6585 -2          A01X+158431Y+164029X0120Y0150R270 S1      
317m1402            VIA   -    MD0080PA01X+158984Y+156634X0160Y         S0      
317m1402            VIA   -    MD0100PA01X+146361Y+162538X0180Y         S0      
327m1402            C6565 -2          A01X+146331Y+163138X0120Y0150R270 S1      
327m1402            U6012 -EU7        A01X+158779Y+156634X0150Y         S1      
317m1403            VIA   -    MD0080PA01X+163078Y+156361X0160Y         S0      
317m1403            VIA   -    MD0100PA01X+156875Y+162538X0180Y         S0      
327m1403            C6584 -2          A01X+156865Y+164029X0120Y0150R270 S1      
327m1403            U6012 -BT10       A01X+162873Y+156361X0150Y         S1      
317m1404            VIA   -    MD0080PA01X+162606Y+156361X0160Y         S0      
317m1404            VIA   -    MD0100PA01X+155669Y+162538X0180Y         S0      
327m1404            C6582 -2          A01X+155659Y+164029X0120Y0150R270 S1      
327m1404            U6012 -CC10       A01X+162401Y+156361X0150Y         S1      
317m1405            VIA   -    MD0080PA01X+162134Y+156361X0160Y         S0      
317m1405            VIA   -    MD0100PA01X+154463Y+162538X0180Y         S0      
327m1405            C6580 -2          A01X+154453Y+164029X0120Y0150R270 S1      
327m1405            U6012 -CK10       A01X+161928Y+156361X0150Y         S1      
317m1406            VIA   -    MD0080PA01X+161661Y+156361X0160Y         S0      
317m1406            VIA   -    MD0100PA01X+153257Y+162538X0180Y         S0      
327m1406            C6578 -2          A01X+153247Y+164029X0120Y0150R270 S1      
327m1406            U6012 -CU10       A01X+161456Y+156361X0150Y         S1      
317m1407            VIA   -    MD0080PA01X+161189Y+156361X0160Y         S0      
317m1407            VIA   -    MD0100PA01X+152051Y+162538X0180Y         S0      
327m1407            C6576 -2          A01X+152041Y+164029X0120Y0150R270 S1      
327m1407            U6012 -DD10       A01X+160984Y+156361X0150Y         S1      
317m1408            VIA   -    MD0080PA01X+160716Y+156361X0160Y         S0      
317m1408            VIA   -    MD0100PA01X+150845Y+162538X0180Y         S0      
327m1408            C6574 -2          A01X+150835Y+164029X0120Y0150R270 S1      
327m1408            U6012 -DL10       A01X+160511Y+156361X0150Y         S1      
317m1409            VIA   -    MD0080PA01X+160244Y+156361X0160Y         S0      
317m1409            VIA   -    MD0100PA01X+149639Y+162538X0180Y         S0      
327m1409            C6572 -2          A01X+149629Y+164029X0120Y0150R270 S1      
327m1409            U6012 -DV10       A01X+160039Y+156361X0150Y         S1      
317m1410            VIA   -    MD0080PA01X+159771Y+156361X0160Y         S0      
317m1410            VIA   -    MD0100PA01X+148433Y+162538X0180Y         S0      
327m1410            C6570 -2          A01X+148423Y+164029X0120Y0150R270 S1      
327m1410            U6012 -EE10       A01X+159566Y+156361X0150Y         S1      
317m1411            VIA   -    MD0080PA01X+159299Y+156361X0160Y         S0      
317m1411            VIA   -    MD0100PA01X+147227Y+162538X0180Y         S0      
327m1411            C6568 -2          A01X+147217Y+164029X0120Y0150R270 S1      
327m1411            U6012 -EM10       A01X+159094Y+156361X0150Y         S1      
317m1412            VIA   -    MD0080PA01X+165913Y+156361X0160Y         S0      
317m1412            VIA   -    MD0100PA01X+164111Y+162538X0180Y         S0      
327m1412            C6596 -2          A01X+164101Y+164029X0120Y0150R270 S1      
327m1412            U6012 -P10        A01X+165708Y+156361X0150Y         S1      
317m1413            VIA   -    MD0080PA01X+165441Y+156361X0160Y         S0      
317m1413            VIA   -    MD0100PA01X+162905Y+162538X0180Y         S0      
327m1413            C6594 -2          A01X+162895Y+164029X0120Y0150R270 S1      
327m1413            U6012 -AA10       A01X+165236Y+156361X0150Y         S1      
317m1414            VIA   -    MD0080PA01X+164968Y+156361X0160Y         S0      
317m1414            VIA   -    MD0100PA01X+161699Y+162538X0180Y         S0      
327m1414            C6592 -2          A01X+161689Y+164029X0120Y0150R270 S1      
327m1414            U6012 -AH10       A01X+164763Y+156361X0150Y         S1      
317m1415            VIA   -    MD0080PA01X+164496Y+156361X0160Y         S0      
317m1415            VIA   -    MD0100PA01X+160493Y+162538X0180Y         S0      
327m1415            U6012 -AR10       A01X+164291Y+156361X0150Y         S1      
327m1415            C6590 -2          A01X+160483Y+164029X0120Y0150R270 S1      
317m1416            VIA   -    MD0080PA01X+164023Y+156361X0160Y         S0      
317m1416            VIA   -    MD0100PA01X+159287Y+162538X0180Y         S0      
327m1416            C6588 -2          A01X+159277Y+164029X0120Y0150R270 S1      
327m1416            U6012 -BB10       A01X+163818Y+156361X0150Y         S1      
317m1417            VIA   -    MD0080PA01X+163551Y+156361X0160Y         S0      
317m1417            VIA   -    MD0100PA01X+158081Y+162538X0180Y         S0      
327m1417            C6586 -2          A01X+158071Y+164029X0120Y0150R270 S1      
327m1417            U6012 -BJ10       A01X+163346Y+156361X0150Y         S1      
317m1418            VIA   -    MD0080PA01X+158826Y+156361X0160Y         S0      
317m1418            VIA   -    MD0100PA01X+146021Y+162538X0180Y         S0      
327m1418            C6566 -2          A01X+145971Y+163138X0120Y0150R270 S1      
327m1418            U6012 -EW10       A01X+158621Y+156361X0150Y         S1      
317m1419            VIA   -    MD0100PA01X+157215Y+165729X0180Y         S0      
317m1419            J105  -I2   D0142PA01X+157776Y+169563X0302Y    R180 S3      
327m1419            C6583 -1          A01X+157225Y+164239X0120Y0150R270 S1      
317m1420            VIA   -    MD0100PA01X+156009Y+165729X0180Y         S0      
317m1420            J105  -J1   D0142PA01X+156988Y+169169X0302Y    R180 S3      
327m1420            C6581 -1          A01X+156019Y+164239X0120Y0150R270 S1      
317m1421            VIA   -    MD0100PA01X+154803Y+165729X0180Y         S0      
317m1421            J106  -I8   D0142PA01X+155807Y+169563X0302Y    R180 S3      
327m1421            C6579 -1          A01X+154813Y+164239X0120Y0150R270 S1      
317m1422            VIA   -    MD0100PA01X+153597Y+165729X0180Y         S0      
317m1422            J106  -J7   D0142PA01X+155020Y+169169X0302Y    R180 S3      
327m1422            C6577 -1          A01X+153607Y+164239X0120Y0150R270 S1      
317m1423            VIA   -    MD0100PA01X+152391Y+165729X0180Y         S0      
327m1423            C6575 -1          A01X+152401Y+164239X0120Y0150R270 S1      
317m1423            J106  -I6   D0142PA01X+154232Y+169563X0302Y    R180 S3      
317m1424            VIA   -    MD0100PA01X+151185Y+165729X0180Y         S0      
317m1424            J106  -J5   D0142PA01X+153445Y+169169X0302Y    R180 S3      
327m1424            C6573 -1          A01X+151195Y+164239X0120Y0150R270 S1      
317m1425            VIA   -    MD0100PA01X+149979Y+165729X0180Y         S0      
317m1425            J106  -I4   D0142PA01X+152657Y+169563X0302Y    R180 S3      
327m1425            C6571 -1          A01X+149989Y+164239X0120Y0150R270 S1      
317m1426            VIA   -    MD0100PA01X+148773Y+165729X0180Y         S0      
317m1426            J106  -J3   D0142PA01X+151870Y+169169X0302Y    R180 S3      
327m1426            C6569 -1          A01X+148783Y+164239X0120Y0150R270 S1      
317m1427            VIA   -    MD0100PA01X+147567Y+165729X0180Y         S0      
317m1427            J106  -I2   D0142PA01X+151083Y+169563X0302Y    R180 S3      
327m1427            C6567 -1          A01X+147577Y+164239X0120Y0150R270 S1      
317m1428            VIA   -    MD0100PA01X+164451Y+165729X0180Y         S0      
317m1428            J105  -I8   D0142PA01X+162500Y+169563X0302Y    R180 S3      
327m1428            C6595 -1          A01X+164461Y+164239X0120Y0150R270 S1      
317m1429            VIA   -    MD0100PA01X+163245Y+165729X0180Y         S0      
317m1429            J105  -J7   D0142PA01X+161713Y+169169X0302Y    R180 S3      
327m1429            C6593 -1          A01X+163255Y+164239X0120Y0150R270 S1      
317m1430            VIA   -    MD0100PA01X+162039Y+165729X0180Y         S0      
317m1430            J105  -I6   D0142PA01X+160925Y+169563X0302Y    R180 S3      
327m1430            C6591 -1          A01X+162049Y+164239X0120Y0150R270 S1      
317m1431            VIA   -    MD0100PA01X+160833Y+165729X0180Y         S0      
317m1431            J105  -J5   D0142PA01X+160138Y+169169X0302Y    R180 S3      
327m1431            C6589 -1          A01X+160843Y+164239X0120Y0150R270 S1      
317m1432            VIA   -    MD0100PA01X+159627Y+165729X0180Y         S0      
317m1432            J105  -I4   D0142PA01X+159350Y+169563X0302Y    R180 S3      
327m1432            C6587 -1          A01X+159637Y+164239X0120Y0150R270 S1      
317m1433            VIA   -    MD0100PA01X+158421Y+165729X0180Y         S0      
317m1433            J105  -J3   D0142PA01X+158563Y+169169X0302Y    R180 S3      
327m1433            C6585 -1          A01X+158431Y+164239X0120Y0150R270 S1      
317m1434            VIA   -    MD0100PA01X+146361Y+165729X0180Y         S0      
327m1434            C6565 -1          A01X+146331Y+163348X0120Y0150R270 S1      
317m1434            J106  -J1   D0142PA01X+150295Y+169169X0302Y    R180 S3      
317m1435            VIA   -    MD0100PA01X+156875Y+165729X0180Y         S0      
317m1435            J105  -H2   D0142PA01X+157776Y+170035X0302Y    R180 S3      
327m1435            C6584 -1          A01X+156865Y+164239X0120Y0150R270 S1      
317m1436            VIA   -    MD0100PA01X+155669Y+165729X0180Y         S0      
317m1436            J105  -I1   D0142PA01X+156988Y+169642X0302Y    R180 S3      
327m1436            C6582 -1          A01X+155659Y+164239X0120Y0150R270 S1      
317m1437            VIA   -    MD0100PA01X+154463Y+165729X0180Y         S0      
317m1437            J106  -H8   D0142PA01X+155807Y+170035X0302Y    R180 S3      
327m1437            C6580 -1          A01X+154453Y+164239X0120Y0150R270 S1      
317m1438            VIA   -    MD0100PA01X+153257Y+165729X0180Y         S0      
317m1438            J106  -I7   D0142PA01X+155020Y+169642X0302Y    R180 S3      
327m1438            C6578 -1          A01X+153247Y+164239X0120Y0150R270 S1      
317m1439            VIA   -    MD0100PA01X+152051Y+165729X0180Y         S0      
327m1439            C6576 -1          A01X+152041Y+164239X0120Y0150R270 S1      
317m1439            J106  -H6   D0142PA01X+154232Y+170035X0302Y    R180 S3      
317m1440            VIA   -    MD0100PA01X+150845Y+165729X0180Y         S0      
317m1440            J106  -I5   D0142PA01X+153445Y+169642X0302Y    R180 S3      
327m1440            C6574 -1          A01X+150835Y+164239X0120Y0150R270 S1      
317m1441            VIA   -    MD0100PA01X+149639Y+165729X0180Y         S0      
317m1441            J106  -H4   D0142PA01X+152657Y+170035X0302Y    R180 S3      
327m1441            C6572 -1          A01X+149629Y+164239X0120Y0150R270 S1      
317m1442            VIA   -    MD0100PA01X+148433Y+165729X0180Y         S0      
317m1442            J106  -I3   D0142PA01X+151870Y+169642X0302Y    R180 S3      
327m1442            C6570 -1          A01X+148423Y+164239X0120Y0150R270 S1      
317m1443            VIA   -    MD0100PA01X+147227Y+165729X0180Y         S0      
317m1443            J106  -H2   D0142PA01X+151083Y+170035X0302Y    R180 S3      
327m1443            C6568 -1          A01X+147217Y+164239X0120Y0150R270 S1      
317m1444            VIA   -    MD0100PA01X+164111Y+165729X0180Y         S0      
317m1444            J105  -H8   D0142PA01X+162500Y+170035X0302Y    R180 S3      
327m1444            C6596 -1          A01X+164101Y+164239X0120Y0150R270 S1      
317m1445            VIA   -    MD0100PA01X+162905Y+165729X0180Y         S0      
317m1445            J105  -I7   D0142PA01X+161713Y+169642X0302Y    R180 S3      
327m1445            C6594 -1          A01X+162895Y+164239X0120Y0150R270 S1      
317m1446            VIA   -    MD0100PA01X+161699Y+165729X0180Y         S0      
317m1446            J105  -H6   D0142PA01X+160925Y+170035X0302Y    R180 S3      
327m1446            C6592 -1          A01X+161689Y+164239X0120Y0150R270 S1      
317m1447            VIA   -    MD0100PA01X+160493Y+165729X0180Y         S0      
317m1447            J105  -I5   D0142PA01X+160138Y+169642X0302Y    R180 S3      
327m1447            C6590 -1          A01X+160483Y+164239X0120Y0150R270 S1      
317m1448            VIA   -    MD0100PA01X+159287Y+165729X0180Y         S0      
317m1448            J105  -H4   D0142PA01X+159350Y+170035X0302Y    R180 S3      
327m1448            C6588 -1          A01X+159277Y+164239X0120Y0150R270 S1      
317m1449            VIA   -    MD0100PA01X+158081Y+165729X0180Y         S0      
317m1449            J105  -I3   D0142PA01X+158563Y+169642X0302Y    R180 S3      
327m1449            C6586 -1          A01X+158071Y+164239X0120Y0150R270 S1      
317m1450            VIA   -    MD0100PA01X+146021Y+165729X0180Y         S0      
327m1450            C6566 -1          A01X+145971Y+163348X0120Y0150R270 S1      
317m1450            J106  -I1   D0142PA01X+150295Y+169642X0302Y    R180 S3      
317m1451            VIA   -    MD0100PA01X+163088Y+158140X0180Y         S0      
317m1451            J105  -C2   D0142PA01X+157776Y+172398X0302Y    R180 S3      
327m1451            U6012 -BU1        A01X+162813Y+157348X0100Y0130     S1      
317m1452            VIA   -    MD0100PA01X+162616Y+158140X0180Y         S0      
317m1452            J105  -D1   D0142PA01X+156988Y+172004X0302Y    R180 S3      
327m1452            U6012 -CD1        A01X+162341Y+157348X0100Y0130     S1      
317m1453            VIA   -    MD0100PA01X+162143Y+158140X0180Y         S0      
317m1453            J106  -C8   D0142PA01X+155807Y+172398X0302Y    R180 S3      
327m1453            U6012 -CL1        A01X+161868Y+157348X0100Y0130     S1      
317m1454            VIA   -    MD0100PA01X+161671Y+158140X0180Y         S0      
317m1454            J106  -D7   D0142PA01X+155020Y+172004X0302Y    R180 S3      
327m1454            U6012 -CV1        A01X+161396Y+157348X0100Y0130     S1      
317m1455            VIA   -    MD0100PA01X+161198Y+158140X0180Y         S0      
317m1455            J106  -C6   D0142PA01X+154232Y+172398X0302Y    R180 S3      
327m1455            U6012 -DE1        A01X+160924Y+157348X0100Y0130     S1      
317m1456            VIA   -    MD0100PA01X+160726Y+158140X0180Y         S0      
317m1456            J106  -D5   D0142PA01X+153445Y+172004X0302Y    R180 S3      
327m1456            U6012 -DM1        A01X+160451Y+157348X0100Y0130     S1      
317m1457            VIA   -    MD0100PA01X+160254Y+158140X0180Y         S0      
317m1457            J106  -C4   D0142PA01X+152657Y+172398X0302Y    R180 S3      
327m1457            U6012 -DW1        A01X+159979Y+157348X0100Y0130     S1      
317m1458            VIA   -    MD0100PA01X+159781Y+158140X0180Y         S0      
317m1458            J106  -D3   D0142PA01X+151870Y+172004X0302Y    R180 S3      
327m1458            U6012 -EF1        A01X+159506Y+157348X0100Y0130     S1      
317m1459            VIA   -    MD0100PA01X+159309Y+158140X0180Y         S0      
317m1459            J106  -C2   D0142PA01X+151083Y+172398X0302Y    R180 S3      
327m1459            U6012 -EN1        A01X+159034Y+157348X0100Y0130     S1      
317m1460            VIA   -    MD0100PA01X+165923Y+158140X0180Y         S0      
317m1460            J105  -C8   D0142PA01X+162500Y+172398X0302Y    R180 S3      
327m1460            U6012 -R1         A01X+165648Y+157348X0100Y0130     S1      
317m1461            VIA   -    MD0100PA01X+165450Y+158140X0180Y         S0      
317m1461            J105  -D7   D0142PA01X+161713Y+172004X0302Y    R180 S3      
327m1461            U6012 -AB1        A01X+165176Y+157348X0100Y0130     S1      
317m1462            VIA   -    MD0100PA01X+164978Y+158140X0180Y         S0      
317m1462            J105  -C6   D0142PA01X+160925Y+172398X0302Y    R180 S3      
327m1462            U6012 -AJ1        A01X+164703Y+157348X0100Y0130     S1      
317m1463            VIA   -    MD0100PA01X+164506Y+158140X0180Y         S0      
317m1463            J105  -D5   D0142PA01X+160138Y+172004X0302Y    R180 S3      
327m1463            U6012 -AT1        A01X+164231Y+157348X0100Y0130     S1      
317m1464            VIA   -    MD0100PA01X+164033Y+158140X0180Y         S0      
317m1464            J105  -C4   D0142PA01X+159350Y+172398X0302Y    R180 S3      
327m1464            U6012 -BC1        A01X+163758Y+157348X0100Y0130     S1      
317m1465            VIA   -    MD0100PA01X+163561Y+158140X0180Y         S0      
327m1465            U6012 -BK1        A01X+163286Y+157348X0100Y0130     S1      
317m1465            J105  -D3   D0142PA01X+158563Y+172004X0302Y    R180 S3      
317m1466            VIA   -    MD0100PA01X+158836Y+158140X0180Y         S0      
317m1466            J106  -D1   D0142PA01X+150295Y+172004X0302Y    R180 S3      
327m1466            U6012 -EY1        A01X+158561Y+157348X0100Y0130     S1      
317m1467            VIA   -    MD0100PA01X+163088Y+157800X0180Y         S0      
317m1467            J105  -B2   D0142PA01X+157776Y+172870X0302Y    R180 S3      
327m1467            U6012 -BR2        A01X+162931Y+157143X0120Y         S1      
317m1468            VIA   -    MD0100PA01X+162616Y+157800X0180Y         S0      
317m1468            J105  -C1   D0142PA01X+156988Y+172476X0302Y    R180 S3      
327m1468            U6012 -CB2        A01X+162459Y+157143X0120Y         S1      
317m1469            VIA   -    MD0100PA01X+162143Y+157800X0180Y         S0      
317m1469            J106  -B8   D0142PA01X+155807Y+172870X0302Y    R180 S3      
327m1469            U6012 -CJ2        A01X+161986Y+157143X0120Y         S1      
317m1470            VIA   -    MD0100PA01X+161671Y+157800X0180Y         S0      
317m1470            J106  -C7   D0142PA01X+155020Y+172476X0302Y    R180 S3      
327m1470            U6012 -CT2        A01X+161514Y+157143X0120Y         S1      
317m1471            VIA   -    MD0100PA01X+161198Y+157800X0180Y         S0      
317m1471            J106  -B6   D0142PA01X+154232Y+172870X0302Y    R180 S3      
327m1471            U6012 -DC2        A01X+161042Y+157143X0120Y         S1      
317m1472            VIA   -    MD0100PA01X+160726Y+157800X0180Y         S0      
317m1472            J106  -C5   D0142PA01X+153445Y+172476X0302Y    R180 S3      
327m1472            U6012 -DK2        A01X+160569Y+157143X0120Y         S1      
317m1473            VIA   -    MD0100PA01X+160254Y+157800X0180Y         S0      
317m1473            J106  -B4   D0142PA01X+152657Y+172870X0302Y    R180 S3      
327m1473            U6012 -DU2        A01X+160097Y+157143X0120Y         S1      
317m1474            VIA   -    MD0100PA01X+159781Y+157800X0180Y         S0      
317m1474            J106  -C3   D0142PA01X+151870Y+172476X0302Y    R180 S3      
327m1474            U6012 -ED2        A01X+159624Y+157143X0120Y         S1      
317m1475            VIA   -    MD0100PA01X+159309Y+157800X0180Y         S0      
317m1475            J106  -B2   D0142PA01X+151083Y+172870X0302Y    R180 S3      
327m1475            U6012 -EL2        A01X+159152Y+157143X0120Y         S1      
317m1476            VIA   -    MD0100PA01X+165923Y+157800X0180Y         S0      
317m1476            J105  -B8   D0142PA01X+162500Y+172870X0302Y    R180 S3      
327m1476            U6012 -N2         A01X+165766Y+157143X0120Y         S1      
317m1477            VIA   -    MD0100PA01X+165450Y+157800X0180Y         S0      
317m1477            J105  -C7   D0142PA01X+161713Y+172476X0302Y    R180 S3      
327m1477            U6012 -Y2         A01X+165294Y+157143X0120Y         S1      
317m1478            VIA   -    MD0100PA01X+164978Y+157800X0180Y         S0      
317m1478            J105  -B6   D0142PA01X+160925Y+172870X0302Y    R180 S3      
327m1478            U6012 -AG2        A01X+164821Y+157143X0120Y         S1      
317m1479            VIA   -    MD0100PA01X+164506Y+157800X0180Y         S0      
317m1479            J105  -C5   D0142PA01X+160138Y+172476X0302Y    R180 S3      
327m1479            U6012 -AP2        A01X+164349Y+157143X0120Y         S1      
317m1480            VIA   -    MD0100PA01X+164033Y+157800X0180Y         S0      
317m1480            J105  -B4   D0142PA01X+159350Y+172870X0302Y    R180 S3      
327m1480            U6012 -BA2        A01X+163876Y+157143X0120Y         S1      
317m1481            VIA   -    MD0100PA01X+163561Y+157800X0180Y         S0      
327m1481            U6012 -BH2        A01X+163404Y+157143X0120Y         S1      
317m1481            J105  -C3   D0142PA01X+158563Y+172476X0302Y    R180 S3      
317m1482            VIA   -    MD0100PA01X+158836Y+157800X0180Y         S0      
317m1482            J106  -C1   D0142PA01X+150295Y+172476X0302Y    R180 S3      
327m1482            U6012 -EV2        A01X+158679Y+157143X0120Y         S1      
317m1483            VIA   -    MD0080PA01X+136818Y+156634X0160Y         S0      
317m1483            VIA   -    MD0100PA18X+131401Y+163538X0180Y         S0      
327m1483            C6551 -2          A18X+131411Y+164029X0120Y0150R090 S2      
327m1483            U6011 -BP7        A01X+136613Y+156634X0150Y         S1      
317m1484            VIA   -    MD0080PA01X+136346Y+156634X0160Y         S0      
317m1484            VIA   -    MD0100PA18X+130195Y+163538X0180Y         S0      
327m1484            C6549 -2          A18X+130205Y+164029X0120Y0150R090 S2      
327m1484            U6011 -CA7        A01X+136141Y+156634X0150Y         S1      
317m1485            VIA   -    MD0080PA01X+135874Y+156634X0160Y         S0      
317m1485            VIA   -    MD0100PA18X+128989Y+163538X0180Y         S0      
327m1485            C6547 -2          A18X+128999Y+164029X0120Y0150R090 S2      
327m1485            U6011 -CH7        A01X+135668Y+156634X0150Y         S1      
317m1486            VIA   -    MD0080PA01X+135401Y+156634X0160Y         S0      
317m1486            VIA   -    MD0100PA18X+127783Y+163538X0180Y         S0      
327m1486            C6545 -2          A18X+127793Y+164029X0120Y0150R090 S2      
327m1486            U6011 -CR7        A01X+135196Y+156634X0150Y         S1      
317m1487            VIA   -    MD0080PA01X+134929Y+156634X0160Y         S0      
317m1487            VIA   -    MD0100PA18X+126577Y+163538X0180Y         S0      
327m1487            C6543 -2          A18X+126587Y+164029X0120Y0150R090 S2      
327m1487            U6011 -DB7        A01X+134724Y+156634X0150Y         S1      
317m1488            VIA   -    MD0080PA01X+134456Y+156634X0160Y         S0      
317m1488            VIA   -    MD0100PA18X+125371Y+163538X0180Y         S0      
327m1488            C6541 -2          A18X+125381Y+164029X0120Y0150R090 S2      
327m1488            U6011 -DJ7        A01X+134251Y+156634X0150Y         S1      
317m1489            VIA   -    MD0080PA01X+133984Y+156634X0160Y         S0      
317m1489            VIA   -    MD0100PA18X+124165Y+163538X0180Y         S0      
327m1489            C6539 -2          A18X+124175Y+164029X0120Y0150R090 S2      
327m1489            U6011 -DT7        A01X+133779Y+156634X0150Y         S1      
317m1490            VIA   -    MD0080PA01X+133511Y+156634X0160Y         S0      
317m1490            VIA   -    MD0100PA18X+122959Y+163538X0180Y         S0      
327m1490            C6537 -2          A18X+122969Y+164029X0120Y0150R090 S2      
327m1490            U6011 -EC7        A01X+133306Y+156634X0150Y         S1      
317m1491            VIA   -    MD0080PA01X+133039Y+156634X0160Y         S0      
317m1491            VIA   -    MD0100PA18X+121753Y+163538X0180Y         S0      
327m1491            C6535 -2          A18X+121763Y+164029X0120Y0150R090 S2      
327m1491            U6011 -EK7        A01X+132834Y+156634X0150Y         S1      
317m1492            VIA   -    MD0080PA01X+139653Y+156634X0160Y         S0      
317m1492            VIA   -    MD0100PA18X+138637Y+163538X0180Y         S0      
327m1492            C6563 -2          A18X+138647Y+164029X0120Y0150R090 S2      
327m1492            U6011 -M7         A01X+139448Y+156634X0150Y         S1      
317m1493            VIA   -    MD0080PA01X+139181Y+156634X0160Y         S0      
317m1493            VIA   -    MD0100PA18X+137431Y+163538X0180Y         S0      
327m1493            C6561 -2          A18X+137441Y+164029X0120Y0150R090 S2      
327m1493            U6011 -W7         A01X+138976Y+156634X0150Y         S1      
317m1494            VIA   -    MD0080PA01X+138708Y+156634X0160Y         S0      
317m1494            VIA   -    MD0100PA18X+136225Y+163538X0180Y         S0      
327m1494            C6559 -2          A18X+136235Y+164029X0120Y0150R090 S2      
327m1494            U6011 -AF7        A01X+138503Y+156634X0150Y         S1      
317m1495            VIA   -    MD0080PA01X+138236Y+156634X0160Y         S0      
317m1495            VIA   -    MD0100PA18X+135019Y+163538X0180Y         S0      
327m1495            C6557 -2          A18X+135029Y+164029X0120Y0150R090 S2      
327m1495            U6011 -AN7        A01X+138031Y+156634X0150Y         S1      
317m1496            VIA   -    MD0080PA01X+137763Y+156634X0160Y         S0      
317m1496            VIA   -    MD0100PA18X+133813Y+163538X0180Y         S0      
327m1496            C6555 -2          A18X+133823Y+164029X0120Y0150R090 S2      
327m1496            U6011 -AY7        A01X+137558Y+156634X0150Y         S1      
317m1497            VIA   -    MD0080PA01X+137291Y+156634X0160Y         S0      
317m1497            VIA   -    MD0100PA18X+132607Y+163538X0180Y         S0      
327m1497            C6553 -2          A18X+132617Y+164029X0120Y0150R090 S2      
327m1497            U6011 -BG7        A01X+137086Y+156634X0150Y         S1      
317m1498            VIA   -    MD0080PA01X+132566Y+156634X0160Y         S0      
317m1498            VIA   -    MD0100PA18X+120547Y+163538X0180Y         S0      
327m1498            C6533 -2          A18X+120557Y+164029X0120Y0150R090 S2      
327m1498            U6011 -EU7        A01X+132362Y+156634X0150Y         S1      
317m1499            VIA   -    MD0080PA01X+136661Y+156361X0160Y         S0      
317m1499            VIA   -    MD0100PA18X+131061Y+163538X0180Y         S0      
327m1499            C6552 -2          A18X+131051Y+164029X0120Y0150R090 S2      
327m1499            U6011 -BT10       A01X+136456Y+156361X0150Y         S1      
317m1500            VIA   -    MD0080PA01X+136188Y+156361X0160Y         S0      
317m1500            VIA   -    MD0100PA18X+129855Y+163538X0180Y         S0      
327m1500            C6550 -2          A18X+129845Y+164029X0120Y0150R090 S2      
327m1500            U6011 -CC10       A01X+135984Y+156361X0150Y         S1      
317m1501            VIA   -    MD0080PA01X+135716Y+156361X0160Y         S0      
317m1501            VIA   -    MD0100PA18X+128649Y+163538X0180Y         S0      
327m1501            C6548 -2          A18X+128639Y+164029X0120Y0150R090 S2      
327m1501            U6011 -CK10       A01X+135511Y+156361X0150Y         S1      
317m1502            VIA   -    MD0080PA01X+135244Y+156361X0160Y         S0      
317m1502            VIA   -    MD0100PA18X+127443Y+163538X0180Y         S0      
327m1502            C6546 -2          A18X+127433Y+164029X0120Y0150R090 S2      
327m1502            U6011 -CU10       A01X+135039Y+156361X0150Y         S1      
317m1503            VIA   -    MD0080PA01X+134771Y+156361X0160Y         S0      
317m1503            VIA   -    MD0100PA18X+126237Y+163538X0180Y         S0      
327m1503            C6544 -2          A18X+126227Y+164029X0120Y0150R090 S2      
327m1503            U6011 -DD10       A01X+134566Y+156361X0150Y         S1      
317m1504            VIA   -    MD0080PA01X+134299Y+156361X0160Y         S0      
317m1504            VIA   -    MD0100PA18X+125031Y+163538X0180Y         S0      
327m1504            C6542 -2          A18X+125021Y+164029X0120Y0150R090 S2      
327m1504            U6011 -DL10       A01X+134094Y+156361X0150Y         S1      
317m1505            VIA   -    MD0080PA01X+133826Y+156361X0160Y         S0      
317m1505            VIA   -    MD0100PA18X+123825Y+163538X0180Y         S0      
327m1505            C6540 -2          A18X+123815Y+164029X0120Y0150R090 S2      
327m1505            U6011 -DV10       A01X+133621Y+156361X0150Y         S1      
317m1506            VIA   -    MD0080PA01X+133354Y+156361X0160Y         S0      
317m1506            VIA   -    MD0100PA18X+122619Y+163538X0180Y         S0      
327m1506            C6538 -2          A18X+122609Y+164029X0120Y0150R090 S2      
327m1506            U6011 -EE10       A01X+133149Y+156361X0150Y         S1      
317m1507            VIA   -    MD0080PA01X+132881Y+156361X0160Y         S0      
317m1507            VIA   -    MD0100PA18X+121413Y+163538X0180Y         S0      
327m1507            C6536 -2          A18X+121403Y+164029X0120Y0150R090 S2      
327m1507            U6011 -EM10       A01X+132676Y+156361X0150Y         S1      
317m1508            VIA   -    MD0080PA01X+139496Y+156361X0160Y         S0      
317m1508            VIA   -    MD0100PA18X+138297Y+163538X0180Y         S0      
327m1508            C6564 -2          A18X+138287Y+164029X0120Y0150R090 S2      
327m1508            U6011 -P10        A01X+139291Y+156361X0150Y         S1      
317m1509            VIA   -    MD0080PA01X+139023Y+156361X0160Y         S0      
317m1509            VIA   -    MD0100PA18X+137091Y+163538X0180Y         S0      
327m1509            C6562 -2          A18X+137081Y+164029X0120Y0150R090 S2      
327m1509            U6011 -AA10       A01X+138818Y+156361X0150Y         S1      
317m1510            VIA   -    MD0080PA01X+138551Y+156361X0160Y         S0      
317m1510            VIA   -    MD0100PA18X+135885Y+163538X0180Y         S0      
327m1510            C6560 -2          A18X+135875Y+164029X0120Y0150R090 S2      
327m1510            U6011 -AH10       A01X+138346Y+156361X0150Y         S1      
317m1511            VIA   -    MD0080PA01X+138078Y+156361X0160Y         S0      
317m1511            VIA   -    MD0100PA18X+134679Y+163538X0180Y         S0      
327m1511            C6558 -2          A18X+134669Y+164029X0120Y0150R090 S2      
327m1511            U6011 -AR10       A01X+137873Y+156361X0150Y         S1      
317m1512            VIA   -    MD0080PA01X+137606Y+156361X0160Y         S0      
317m1512            VIA   -    MD0100PA18X+133473Y+163538X0180Y         S0      
327m1512            C6556 -2          A18X+133463Y+164029X0120Y0150R090 S2      
327m1512            U6011 -BB10       A01X+137401Y+156361X0150Y         S1      
317m1513            VIA   -    MD0080PA01X+137133Y+156361X0160Y         S0      
317m1513            VIA   -    MD0100PA18X+132267Y+163538X0180Y         S0      
327m1513            C6554 -2          A18X+132257Y+164029X0120Y0150R090 S2      
327m1513            U6011 -BJ10       A01X+136928Y+156361X0150Y         S1      
317m1514            VIA   -    MD0080PA01X+132409Y+156361X0160Y         S0      
317m1514            VIA   -    MD0100PA18X+120207Y+163538X0180Y         S0      
327m1514            C6534 -2          A18X+120197Y+164029X0120Y0150R090 S2      
327m1514            U6011 -EW10       A01X+132204Y+156361X0150Y         S1      
317m1515            VIA   -    MD0100PA18X+131401Y+164729X0180Y         S0      
327m1515            C6551 -1          A18X+131411Y+164239X0120Y0150R090 S2      
317m1515            J107  -L2   D0142PA01X+131358Y+168146X0302Y    R180 S3      
317m1516            VIA   -    MD0100PA18X+130195Y+164729X0180Y         S0      
327m1516            C6549 -1          A18X+130205Y+164239X0120Y0150R090 S2      
317m1516            J107  -M1   D0142PA01X+130571Y+167752X0302Y    R180 S3      
317m1517            VIA   -    MD0100PA18X+128989Y+164729X0180Y         S0      
327m1517            C6547 -1          A18X+128999Y+164239X0120Y0150R090 S2      
317m1517            J108  -L8   D0142PA01X+129390Y+168146X0302Y    R180 S3      
317m1518            VIA   -    MD0100PA18X+127783Y+164729X0180Y         S0      
327m1518            C6545 -1          A18X+127793Y+164239X0120Y0150R090 S2      
317m1518            J108  -M7   D0142PA01X+128602Y+167752X0302Y    R180 S3      
317m1519            VIA   -    MD0100PA18X+126577Y+164729X0180Y         S0      
327m1519            C6543 -1          A18X+126587Y+164239X0120Y0150R090 S2      
317m1519            J108  -L6   D0142PA01X+127815Y+168146X0302Y    R180 S3      
317m1520            VIA   -    MD0100PA18X+125371Y+164729X0180Y         S0      
327m1520            C6541 -1          A18X+125381Y+164239X0120Y0150R090 S2      
317m1520            J108  -M5   D0142PA01X+127027Y+167752X0302Y    R180 S3      
317m1521            VIA   -    MD0100PA18X+124165Y+164729X0180Y         S0      
327m1521            C6539 -1          A18X+124175Y+164239X0120Y0150R090 S2      
317m1521            J108  -L4   D0142PA01X+126240Y+168146X0302Y    R180 S3      
317m1522            VIA   -    MD0100PA18X+122959Y+164729X0180Y         S0      
327m1522            C6537 -1          A18X+122969Y+164239X0120Y0150R090 S2      
317m1522            J108  -M3   D0142PA01X+125453Y+167752X0302Y    R180 S3      
317m1523            VIA   -    MD0100PA18X+121753Y+164729X0180Y         S0      
317m1523            J108  -L2   D0142PA01X+124665Y+168146X0302Y    R180 S3      
327m1523            C6535 -1          A18X+121763Y+164239X0120Y0150R090 S2      
317m1524            VIA   -    MD0100PA18X+138637Y+164729X0180Y         S0      
317m1524            J107  -L8   D0142PA01X+136083Y+168146X0302Y    R180 S3      
327m1524            C6563 -1          A18X+138647Y+164239X0120Y0150R090 S2      
317m1525            VIA   -    MD0100PA18X+137431Y+164729X0180Y         S0      
317m1525            J107  -M7   D0142PA01X+135295Y+167752X0302Y    R180 S3      
327m1525            C6561 -1          A18X+137441Y+164239X0120Y0150R090 S2      
317m1526            VIA   -    MD0100PA18X+136225Y+164729X0180Y         S0      
327m1526            C6559 -1          A18X+136235Y+164239X0120Y0150R090 S2      
317m1526            J107  -L6   D0142PA01X+134508Y+168146X0302Y    R180 S3      
317m1527            VIA   -    MD0100PA18X+135019Y+164729X0180Y         S0      
327m1527            C6557 -1          A18X+135029Y+164239X0120Y0150R090 S2      
317m1527            J107  -M5   D0142PA01X+133720Y+167752X0302Y    R180 S3      
317m1528            VIA   -    MD0100PA18X+133813Y+164729X0180Y         S0      
327m1528            C6555 -1          A18X+133823Y+164239X0120Y0150R090 S2      
317m1528            J107  -L4   D0142PA01X+132933Y+168146X0302Y    R180 S3      
317m1529            VIA   -    MD0100PA18X+132607Y+164729X0180Y         S0      
327m1529            C6553 -1          A18X+132617Y+164239X0120Y0150R090 S2      
317m1529            J107  -M3   D0142PA01X+132146Y+167752X0302Y    R180 S3      
317m1530            VIA   -    MD0100PA18X+120547Y+164729X0180Y         S0      
327m1530            C6533 -1          A18X+120557Y+164239X0120Y0150R090 S2      
317m1530            J108  -M1   D0142PA01X+123878Y+167752X0302Y    R180 S3      
317m1531            VIA   -    MD0100PA18X+131061Y+164729X0180Y         S0      
327m1531            C6552 -1          A18X+131051Y+164239X0120Y0150R090 S2      
317m1531            J107  -K2   D0142PA01X+131358Y+168618X0302Y    R180 S3      
317m1532            VIA   -    MD0100PA18X+129855Y+164729X0180Y         S0      
327m1532            C6550 -1          A18X+129845Y+164239X0120Y0150R090 S2      
317m1532            J107  -L1   D0142PA01X+130571Y+168224X0302Y    R180 S3      
317m1533            VIA   -    MD0100PA18X+128649Y+164729X0180Y         S0      
327m1533            C6548 -1          A18X+128639Y+164239X0120Y0150R090 S2      
317m1533            J108  -K8   D0142PA01X+129390Y+168618X0302Y    R180 S3      
317m1534            VIA   -    MD0100PA18X+127443Y+164729X0180Y         S0      
327m1534            C6546 -1          A18X+127433Y+164239X0120Y0150R090 S2      
317m1534            J108  -L7   D0142PA01X+128602Y+168224X0302Y    R180 S3      
317m1535            VIA   -    MD0100PA18X+126237Y+164729X0180Y         S0      
327m1535            C6544 -1          A18X+126227Y+164239X0120Y0150R090 S2      
317m1535            J108  -K6   D0142PA01X+127815Y+168618X0302Y    R180 S3      
317m1536            VIA   -    MD0100PA18X+125031Y+164729X0180Y         S0      
327m1536            C6542 -1          A18X+125021Y+164239X0120Y0150R090 S2      
317m1536            J108  -L5   D0142PA01X+127027Y+168224X0302Y    R180 S3      
317m1537            VIA   -    MD0100PA18X+123825Y+164729X0180Y         S0      
327m1537            C6540 -1          A18X+123815Y+164239X0120Y0150R090 S2      
317m1537            J108  -K4   D0142PA01X+126240Y+168618X0302Y    R180 S3      
317m1538            VIA   -    MD0100PA18X+122619Y+164729X0180Y         S0      
327m1538            C6538 -1          A18X+122609Y+164239X0120Y0150R090 S2      
317m1538            J108  -L3   D0142PA01X+125453Y+168224X0302Y    R180 S3      
317m1539            VIA   -    MD0100PA18X+121413Y+164729X0180Y         S0      
317m1539            J108  -K2   D0142PA01X+124665Y+168618X0302Y    R180 S3      
327m1539            C6536 -1          A18X+121403Y+164239X0120Y0150R090 S2      
317m1540            VIA   -    MD0100PA18X+138297Y+164729X0180Y         S0      
317m1540            J107  -K8   D0142PA01X+136083Y+168618X0302Y    R180 S3      
327m1540            C6564 -1          A18X+138287Y+164239X0120Y0150R090 S2      
317m1541            VIA   -    MD0100PA18X+137091Y+164729X0180Y         S0      
317m1541            J107  -L7   D0142PA01X+135295Y+168224X0302Y    R180 S3      
327m1541            C6562 -1          A18X+137081Y+164239X0120Y0150R090 S2      
317m1542            VIA   -    MD0100PA18X+135885Y+164729X0180Y         S0      
327m1542            C6560 -1          A18X+135875Y+164239X0120Y0150R090 S2      
317m1542            J107  -K6   D0142PA01X+134508Y+168618X0302Y    R180 S3      
317m1543            VIA   -    MD0100PA18X+134679Y+164729X0180Y         S0      
327m1543            C6558 -1          A18X+134669Y+164239X0120Y0150R090 S2      
317m1543            J107  -L5   D0142PA01X+133720Y+168224X0302Y    R180 S3      
317m1544            VIA   -    MD0100PA18X+133473Y+164729X0180Y         S0      
327m1544            C6556 -1          A18X+133463Y+164239X0120Y0150R090 S2      
317m1544            J107  -K4   D0142PA01X+132933Y+168618X0302Y    R180 S3      
317m1545            VIA   -    MD0100PA18X+132267Y+164729X0180Y         S0      
327m1545            C6554 -1          A18X+132257Y+164239X0120Y0150R090 S2      
317m1545            J107  -L3   D0142PA01X+132146Y+168224X0302Y    R180 S3      
317m1546            VIA   -    MD0100PA18X+120207Y+164729X0180Y         S0      
327m1546            C6534 -1          A18X+120197Y+164239X0120Y0150R090 S2      
317m1546            J108  -L1   D0142PA01X+123878Y+168224X0302Y    R180 S3      
317m1547            VIA   -    MD0100PA01X+136671Y+158140X0180Y         S0      
317m1547            J107  -F2   D0142PA01X+131358Y+170980X0302Y    R180 S3      
327m1547            U6011 -BU1        A01X+136396Y+157348X0100Y0130     S1      
317m1548            VIA   -    MD0100PA01X+136198Y+158140X0180Y         S0      
317m1548            J107  -G1   D0142PA01X+130571Y+170587X0302Y    R180 S3      
327m1548            U6011 -CD1        A01X+135923Y+157348X0100Y0130     S1      
317m1549            VIA   -    MD0100PA01X+135726Y+158140X0180Y         S0      
317m1549            J108  -F8   D0142PA01X+129390Y+170980X0302Y    R180 S3      
327m1549            U6011 -CL1        A01X+135451Y+157348X0100Y0130     S1      
317m1550            VIA   -    MD0100PA01X+135254Y+158140X0180Y         S0      
317m1550            J108  -G7   D0142PA01X+128602Y+170587X0302Y    R180 S3      
327m1550            U6011 -CV1        A01X+134978Y+157348X0100Y0130     S1      
317m1551            VIA   -    MD0100PA01X+134781Y+158140X0180Y         S0      
317m1551            J108  -F6   D0142PA01X+127815Y+170980X0302Y    R180 S3      
327m1551            U6011 -DE1        A01X+134506Y+157348X0100Y0130     S1      
317m1552            VIA   -    MD0100PA01X+134309Y+158140X0180Y         S0      
317m1552            J108  -G5   D0142PA01X+127027Y+170587X0302Y    R180 S3      
327m1552            U6011 -DM1        A01X+134034Y+157348X0100Y0130     S1      
317m1553            VIA   -    MD0100PA01X+133836Y+158140X0180Y         S0      
317m1553            J108  -F4   D0142PA01X+126240Y+170980X0302Y    R180 S3      
327m1553            U6011 -DW1        A01X+133561Y+157348X0100Y0130     S1      
317m1554            VIA   -    MD0100PA01X+133364Y+158140X0180Y         S0      
317m1554            J108  -G3   D0142PA01X+125453Y+170587X0302Y    R180 S3      
327m1554            U6011 -EF1        A01X+133089Y+157348X0100Y0130     S1      
317m1555            VIA   -    MD0100PA01X+132891Y+158140X0180Y         S0      
317m1555            J108  -F2   D0142PA01X+124665Y+170980X0302Y    R180 S3      
327m1555            U6011 -EN1        A01X+132616Y+157348X0100Y0130     S1      
317m1556            VIA   -    MD0100PA01X+139506Y+158140X0180Y         S0      
317m1556            J107  -F8   D0142PA01X+136083Y+170980X0302Y    R180 S3      
327m1556            U6011 -R1         A01X+139230Y+157348X0100Y0130     S1      
317m1557            VIA   -    MD0100PA01X+139033Y+158140X0180Y         S0      
317m1557            J107  -G7   D0142PA01X+135295Y+170587X0302Y    R180 S3      
327m1557            U6011 -AB1        A01X+138758Y+157348X0100Y0130     S1      
317m1558            VIA   -    MD0100PA01X+138561Y+158140X0180Y         S0      
317m1558            J107  -F6   D0142PA01X+134508Y+170980X0302Y    R180 S3      
327m1558            U6011 -AJ1        A01X+138286Y+157348X0100Y0130     S1      
317m1559            VIA   -    MD0100PA01X+138088Y+158140X0180Y         S0      
317m1559            J107  -G5   D0142PA01X+133720Y+170587X0302Y    R180 S3      
327m1559            U6011 -AT1        A01X+137813Y+157348X0100Y0130     S1      
317m1560            VIA   -    MD0100PA01X+137616Y+158140X0180Y         S0      
317m1560            J107  -F4   D0142PA01X+132933Y+170980X0302Y    R180 S3      
327m1560            U6011 -BC1        A01X+137341Y+157348X0100Y0130     S1      
317m1561            VIA   -    MD0100PA01X+137143Y+158140X0180Y         S0      
327m1561            U6011 -BK1        A01X+136868Y+157348X0100Y0130     S1      
317m1561            J107  -G3   D0142PA01X+132146Y+170587X0302Y    R180 S3      
317m1562            VIA   -    MD0100PA01X+132419Y+158140X0180Y         S0      
317m1562            J108  -G1   D0142PA01X+123878Y+170587X0302Y    R180 S3      
327m1562            U6011 -EY1        A01X+132144Y+157348X0100Y0130     S1      
317m1563            VIA   -    MD0100PA01X+136671Y+157800X0180Y         S0      
317m1563            J107  -E2   D0142PA01X+131358Y+171453X0302Y    R180 S3      
327m1563            U6011 -BR2        A01X+136514Y+157143X0120Y         S1      
317m1564            VIA   -    MD0100PA01X+136198Y+157800X0180Y         S0      
317m1564            J107  -F1   D0142PA01X+130571Y+171059X0302Y    R180 S3      
327m1564            U6011 -CB2        A01X+136042Y+157143X0120Y         S1      
317m1565            VIA   -    MD0100PA01X+135726Y+157800X0180Y         S0      
317m1565            J108  -E8   D0142PA01X+129390Y+171453X0302Y    R180 S3      
327m1565            U6011 -CJ2        A01X+135569Y+157143X0120Y         S1      
317m1566            VIA   -    MD0100PA01X+135254Y+157800X0180Y         S0      
317m1566            J108  -F7   D0142PA01X+128602Y+171059X0302Y    R180 S3      
327m1566            U6011 -CT2        A01X+135097Y+157143X0120Y         S1      
317m1567            VIA   -    MD0100PA01X+134781Y+157800X0180Y         S0      
317m1567            J108  -E6   D0142PA01X+127815Y+171453X0302Y    R180 S3      
327m1567            U6011 -DC2        A01X+134624Y+157143X0120Y         S1      
317m1568            VIA   -    MD0100PA01X+134309Y+157800X0180Y         S0      
317m1568            J108  -F5   D0142PA01X+127027Y+171059X0302Y    R180 S3      
327m1568            U6011 -DK2        A01X+134152Y+157143X0120Y         S1      
317m1569            VIA   -    MD0100PA01X+133836Y+157800X0180Y         S0      
317m1569            J108  -E4   D0142PA01X+126240Y+171453X0302Y    R180 S3      
327m1569            U6011 -DU2        A01X+133679Y+157143X0120Y         S1      
317m1570            VIA   -    MD0100PA01X+133364Y+157800X0180Y         S0      
317m1570            J108  -F3   D0142PA01X+125453Y+171059X0302Y    R180 S3      
327m1570            U6011 -ED2        A01X+133207Y+157143X0120Y         S1      
317m1571            VIA   -    MD0100PA01X+132891Y+157800X0180Y         S0      
317m1571            J108  -E2   D0142PA01X+124665Y+171453X0302Y    R180 S3      
327m1571            U6011 -EL2        A01X+132734Y+157143X0120Y         S1      
317m1572            VIA   -    MD0100PA01X+139506Y+157800X0180Y         S0      
317m1572            J107  -E8   D0142PA01X+136083Y+171453X0302Y    R180 S3      
327m1572            U6011 -N2         A01X+139349Y+157143X0120Y         S1      
317m1573            VIA   -    MD0100PA01X+139033Y+157800X0180Y         S0      
317m1573            J107  -F7   D0142PA01X+135295Y+171059X0302Y    R180 S3      
327m1573            U6011 -Y2         A01X+138876Y+157143X0120Y         S1      
317m1574            VIA   -    MD0100PA01X+138561Y+157800X0180Y         S0      
317m1574            J107  -E6   D0142PA01X+134508Y+171453X0302Y    R180 S3      
327m1574            U6011 -AG2        A01X+138404Y+157143X0120Y         S1      
317m1575            VIA   -    MD0100PA01X+138088Y+157800X0180Y         S0      
317m1575            J107  -F5   D0142PA01X+133720Y+171059X0302Y    R180 S3      
327m1575            U6011 -AP2        A01X+137931Y+157143X0120Y         S1      
317m1576            VIA   -    MD0100PA01X+137616Y+157800X0180Y         S0      
317m1576            J107  -E4   D0142PA01X+132933Y+171453X0302Y    R180 S3      
327m1576            U6011 -BA2        A01X+137459Y+157143X0120Y         S1      
317m1577            VIA   -    MD0100PA01X+137143Y+157800X0180Y         S0      
327m1577            U6011 -BH2        A01X+136986Y+157143X0120Y         S1      
317m1577            J107  -F3   D0142PA01X+132146Y+171059X0302Y    R180 S3      
317m1578            VIA   -    MD0100PA01X+132419Y+157800X0180Y         S0      
317m1578            J108  -F1   D0142PA01X+123878Y+171059X0302Y    R180 S3      
327m1578            U6011 -EV2        A01X+132262Y+157143X0120Y         S1      
317m1579            VIA   -    MD0080PA01X+124012Y+156634X0160Y         S0      
317m1579            VIA   -    MD0100PA01X+130798Y+162538X0180Y         S0      
327m1579            C6519 -2          A01X+130808Y+164029X0120Y0150R270 S1      
327m1579            U6010 -BP7        A01X+123807Y+156634X0150Y         S1      
317m1580            VIA   -    MD0080PA01X+123540Y+156634X0160Y         S0      
317m1580            VIA   -    MD0100PA01X+129592Y+162538X0180Y         S0      
327m1580            C6517 -2          A01X+129602Y+164029X0120Y0150R270 S1      
327m1580            U6010 -CA7        A01X+123335Y+156634X0150Y         S1      
317m1581            VIA   -    MD0080PA01X+123067Y+156634X0160Y         S0      
317m1581            VIA   -    MD0100PA01X+128386Y+162538X0180Y         S0      
327m1581            C6515 -2          A01X+128396Y+164029X0120Y0150R270 S1      
327m1581            U6010 -CH7        A01X+122862Y+156634X0150Y         S1      
317m1582            VIA   -    MD0080PA01X+122595Y+156634X0160Y         S0      
317m1582            VIA   -    MD0100PA01X+127180Y+162538X0180Y         S0      
327m1582            C6513 -2          A01X+127190Y+164029X0120Y0150R270 S1      
327m1582            U6010 -CR7        A01X+122390Y+156634X0150Y         S1      
317m1583            VIA   -    MD0080PA01X+122122Y+156634X0160Y         S0      
317m1583            VIA   -    MD0100PA01X+125974Y+162538X0180Y         S0      
327m1583            C6511 -2          A01X+125984Y+164029X0120Y0150R270 S1      
327m1583            U6010 -DB7        A01X+121918Y+156634X0150Y         S1      
317m1584            VIA   -    MD0080PA01X+121650Y+156634X0160Y         S0      
317m1584            VIA   -    MD0100PA01X+124768Y+162538X0180Y         S0      
327m1584            C6509 -2          A01X+124778Y+164029X0120Y0150R270 S1      
327m1584            U6010 -DJ7        A01X+121445Y+156634X0150Y         S1      
317m1585            VIA   -    MD0080PA01X+121178Y+156634X0160Y         S0      
317m1585            VIA   -    MD0100PA01X+123562Y+162538X0180Y         S0      
327m1585            C6507 -2          A01X+123572Y+164029X0120Y0150R270 S1      
327m1585            U6010 -DT7        A01X+120973Y+156634X0150Y         S1      
317m1586            VIA   -    MD0080PA01X+120705Y+156634X0160Y         S0      
317m1586            VIA   -    MD0100PA01X+122356Y+162538X0180Y         S0      
327m1586            C6505 -2          A01X+122366Y+164029X0120Y0150R270 S1      
327m1586            U6010 -EC7        A01X+120500Y+156634X0150Y         S1      
317m1587            VIA   -    MD0080PA01X+120233Y+156634X0160Y         S0      
317m1587            VIA   -    MD0100PA01X+121150Y+162538X0180Y         S0      
327m1587            C6503 -2          A01X+121160Y+164029X0120Y0150R270 S1      
327m1587            U6010 -EK7        A01X+120028Y+156634X0150Y         S1      
317m1588            VIA   -    MD0080PA01X+126847Y+156634X0160Y         S0      
317m1588            VIA   -    MD0100PA01X+138034Y+162538X0180Y         S0      
327m1588            C6531 -2          A01X+138044Y+164029X0120Y0150R270 S1      
327m1588            U6010 -M7         A01X+126642Y+156634X0150Y         S1      
317m1589            VIA   -    MD0080PA01X+126374Y+156634X0160Y         S0      
317m1589            VIA   -    MD0100PA01X+136828Y+162538X0180Y         S0      
327m1589            C6529 -2          A01X+136838Y+164029X0120Y0150R270 S1      
327m1589            U6010 -W7         A01X+126169Y+156634X0150Y         S1      
317m1590            VIA   -    MD0080PA01X+125902Y+156634X0160Y         S0      
317m1590            VIA   -    MD0100PA01X+135622Y+162538X0180Y         S0      
327m1590            C6527 -2          A01X+135632Y+164029X0120Y0150R270 S1      
327m1590            U6010 -AF7        A01X+125697Y+156634X0150Y         S1      
317m1591            VIA   -    MD0080PA01X+125430Y+156634X0160Y         S0      
317m1591            VIA   -    MD0100PA01X+134416Y+162538X0180Y         S0      
327m1591            C6525 -2          A01X+134426Y+164029X0120Y0150R270 S1      
327m1591            U6010 -AN7        A01X+125224Y+156634X0150Y         S1      
317m1592            VIA   -    MD0080PA01X+124957Y+156634X0160Y         S0      
317m1592            VIA   -    MD0100PA01X+133210Y+162538X0180Y         S0      
327m1592            C6523 -2          A01X+133220Y+164029X0120Y0150R270 S1      
327m1592            U6010 -AY7        A01X+124752Y+156634X0150Y         S1      
317m1593            VIA   -    MD0080PA01X+124485Y+156634X0160Y         S0      
317m1593            VIA   -    MD0100PA01X+132004Y+162538X0180Y         S0      
327m1593            C6521 -2          A01X+132014Y+164029X0120Y0150R270 S1      
327m1593            U6010 -BG7        A01X+124280Y+156634X0150Y         S1      
317m1594            VIA   -    MD0080PA01X+119760Y+156634X0160Y         S0      
317m1594            VIA   -    MD0100PA01X+119944Y+162538X0180Y         S0      
327m1594            U6010 -EU7        A01X+119555Y+156634X0150Y         S1      
327m1594            C6501 -2          A01X+119954Y+164029X0120Y0150R270 S1      
317m1595            VIA   -    MD0080PA01X+123855Y+156361X0160Y         S0      
317m1595            VIA   -    MD0100PA01X+130458Y+162538X0180Y         S0      
327m1595            C6520 -2          A01X+130448Y+164029X0120Y0150R270 S1      
327m1595            U6010 -BT10       A01X+123650Y+156361X0150Y         S1      
317m1596            VIA   -    MD0080PA01X+123382Y+156361X0160Y         S0      
317m1596            VIA   -    MD0100PA01X+129252Y+162538X0180Y         S0      
327m1596            C6518 -2          A01X+129242Y+164029X0120Y0150R270 S1      
327m1596            U6010 -CC10       A01X+123177Y+156361X0150Y         S1      
317m1597            VIA   -    MD0080PA01X+122910Y+156361X0160Y         S0      
317m1597            VIA   -    MD0100PA01X+128046Y+162538X0180Y         S0      
327m1597            C6516 -2          A01X+128036Y+164029X0120Y0150R270 S1      
327m1597            U6010 -CK10       A01X+122705Y+156361X0150Y         S1      
317m1598            VIA   -    MD0080PA01X+122437Y+156361X0160Y         S0      
317m1598            VIA   -    MD0100PA01X+126840Y+162538X0180Y         S0      
327m1598            C6514 -2          A01X+126830Y+164029X0120Y0150R270 S1      
327m1598            U6010 -CU10       A01X+122232Y+156361X0150Y         S1      
317m1599            VIA   -    MD0080PA01X+121965Y+156361X0160Y         S0      
317m1599            VIA   -    MD0100PA01X+125634Y+162538X0180Y         S0      
327m1599            C6512 -2          A01X+125624Y+164029X0120Y0150R270 S1      
327m1599            U6010 -DD10       A01X+121760Y+156361X0150Y         S1      
317m1600            VIA   -    MD0080PA01X+121492Y+156361X0160Y         S0      
317m1600            VIA   -    MD0100PA01X+124428Y+162538X0180Y         S0      
327m1600            C6510 -2          A01X+124418Y+164029X0120Y0150R270 S1      
327m1600            U6010 -DL10       A01X+121288Y+156361X0150Y         S1      
317m1601            VIA   -    MD0080PA01X+121020Y+156361X0160Y         S0      
317m1601            VIA   -    MD0100PA01X+123222Y+162538X0180Y         S0      
327m1601            C6508 -2          A01X+123212Y+164029X0120Y0150R270 S1      
327m1601            U6010 -DV10       A01X+120815Y+156361X0150Y         S1      
317m1602            VIA   -    MD0080PA01X+120548Y+156361X0160Y         S0      
317m1602            VIA   -    MD0100PA01X+122016Y+162538X0180Y         S0      
327m1602            C6506 -2          A01X+122006Y+164029X0120Y0150R270 S1      
327m1602            U6010 -EE10       A01X+120343Y+156361X0150Y         S1      
317m1603            VIA   -    MD0080PA01X+120075Y+156361X0160Y         S0      
317m1603            VIA   -    MD0100PA01X+120810Y+162538X0180Y         S0      
327m1603            C6504 -2          A01X+120800Y+164029X0120Y0150R270 S1      
327m1603            U6010 -EM10       A01X+119870Y+156361X0150Y         S1      
317m1604            VIA   -    MD0080PA01X+126689Y+156361X0160Y         S0      
317m1604            VIA   -    MD0100PA01X+137694Y+162538X0180Y         S0      
327m1604            C6532 -2          A01X+137684Y+164029X0120Y0150R270 S1      
327m1604            U6010 -P10        A01X+126484Y+156361X0150Y         S1      
317m1605            VIA   -    MD0080PA01X+126217Y+156361X0160Y         S0      
317m1605            VIA   -    MD0100PA01X+136488Y+162538X0180Y         S0      
327m1605            C6530 -2          A01X+136478Y+164029X0120Y0150R270 S1      
327m1605            U6010 -AA10       A01X+126012Y+156361X0150Y         S1      
317m1606            VIA   -    MD0080PA01X+125744Y+156361X0160Y         S0      
317m1606            VIA   -    MD0100PA01X+135282Y+162538X0180Y         S0      
327m1606            C6528 -2          A01X+135272Y+164029X0120Y0150R270 S1      
327m1606            U6010 -AH10       A01X+125540Y+156361X0150Y         S1      
317m1607            VIA   -    MD0080PA01X+125272Y+156361X0160Y         S0      
317m1607            VIA   -    MD0100PA01X+134076Y+162538X0180Y         S0      
327m1607            C6526 -2          A01X+134066Y+164029X0120Y0150R270 S1      
327m1607            U6010 -AR10       A01X+125067Y+156361X0150Y         S1      
317m1608            VIA   -    MD0080PA01X+124800Y+156361X0160Y         S0      
317m1608            VIA   -    MD0100PA01X+132870Y+162538X0180Y         S0      
327m1608            C6524 -2          A01X+132860Y+164029X0120Y0150R270 S1      
327m1608            U6010 -BB10       A01X+124595Y+156361X0150Y         S1      
317m1609            VIA   -    MD0080PA01X+124327Y+156361X0160Y         S0      
317m1609            VIA   -    MD0100PA01X+131664Y+162538X0180Y         S0      
327m1609            C6522 -2          A01X+131654Y+164029X0120Y0150R270 S1      
327m1609            U6010 -BJ10       A01X+124122Y+156361X0150Y         S1      
317m1610            VIA   -    MD0080PA01X+119603Y+156361X0160Y         S0      
317m1610            VIA   -    MD0100PA01X+119604Y+162538X0180Y         S0      
327m1610            U6010 -EW10       A01X+119398Y+156361X0150Y         S1      
327m1610            C6502 -2          A01X+119594Y+164029X0120Y0150R270 S1      
317m1611            VIA   -    MD0100PA01X+130798Y+165729X0180Y         S0      
317m1611            J107  -I2   D0142PA01X+131358Y+169563X0302Y    R180 S3      
327m1611            C6519 -1          A01X+130808Y+164239X0120Y0150R270 S1      
317m1612            VIA   -    MD0100PA01X+129592Y+165729X0180Y         S0      
317m1612            J107  -J1   D0142PA01X+130571Y+169169X0302Y    R180 S3      
327m1612            C6517 -1          A01X+129602Y+164239X0120Y0150R270 S1      
317m1613            VIA   -    MD0100PA01X+128386Y+165729X0180Y         S0      
317m1613            J108  -I8   D0142PA01X+129390Y+169563X0302Y    R180 S3      
327m1613            C6515 -1          A01X+128396Y+164239X0120Y0150R270 S1      
317m1614            VIA   -    MD0100PA01X+127180Y+165729X0180Y         S0      
317m1614            J108  -J7   D0142PA01X+128602Y+169169X0302Y    R180 S3      
327m1614            C6513 -1          A01X+127190Y+164239X0120Y0150R270 S1      
317m1615            VIA   -    MD0100PA01X+125974Y+165729X0180Y         S0      
327m1615            C6511 -1          A01X+125984Y+164239X0120Y0150R270 S1      
317m1615            J108  -I6   D0142PA01X+127815Y+169563X0302Y    R180 S3      
317m1616            VIA   -    MD0100PA01X+124768Y+165729X0180Y         S0      
317m1616            J108  -J5   D0142PA01X+127027Y+169169X0302Y    R180 S3      
327m1616            C6509 -1          A01X+124778Y+164239X0120Y0150R270 S1      
317m1617            VIA   -    MD0100PA01X+123562Y+165729X0180Y         S0      
317m1617            J108  -I4   D0142PA01X+126240Y+169563X0302Y    R180 S3      
327m1617            C6507 -1          A01X+123572Y+164239X0120Y0150R270 S1      
317m1618            VIA   -    MD0100PA01X+122356Y+165729X0180Y         S0      
317m1618            J108  -J3   D0142PA01X+125453Y+169169X0302Y    R180 S3      
327m1618            C6505 -1          A01X+122366Y+164239X0120Y0150R270 S1      
317m1619            VIA   -    MD0100PA01X+121150Y+165729X0180Y         S0      
317m1619            J108  -I2   D0142PA01X+124665Y+169563X0302Y    R180 S3      
327m1619            C6503 -1          A01X+121160Y+164239X0120Y0150R270 S1      
317m1620            VIA   -    MD0100PA01X+138034Y+165729X0180Y         S0      
317m1620            J107  -I8   D0142PA01X+136083Y+169563X0302Y    R180 S3      
327m1620            C6531 -1          A01X+138044Y+164239X0120Y0150R270 S1      
317m1621            VIA   -    MD0100PA01X+136828Y+165729X0180Y         S0      
317m1621            J107  -J7   D0142PA01X+135295Y+169169X0302Y    R180 S3      
327m1621            C6529 -1          A01X+136838Y+164239X0120Y0150R270 S1      
317m1622            VIA   -    MD0100PA01X+135622Y+165729X0180Y         S0      
317m1622            J107  -I6   D0142PA01X+134508Y+169563X0302Y    R180 S3      
327m1622            C6527 -1          A01X+135632Y+164239X0120Y0150R270 S1      
317m1623            VIA   -    MD0100PA01X+134416Y+165729X0180Y         S0      
317m1623            J107  -J5   D0142PA01X+133720Y+169169X0302Y    R180 S3      
327m1623            C6525 -1          A01X+134426Y+164239X0120Y0150R270 S1      
317m1624            VIA   -    MD0100PA01X+133210Y+165729X0180Y         S0      
317m1624            J107  -I4   D0142PA01X+132933Y+169563X0302Y    R180 S3      
327m1624            C6523 -1          A01X+133220Y+164239X0120Y0150R270 S1      
317m1625            VIA   -    MD0100PA01X+132004Y+165729X0180Y         S0      
317m1625            J107  -J3   D0142PA01X+132146Y+169169X0302Y    R180 S3      
327m1625            C6521 -1          A01X+132014Y+164239X0120Y0150R270 S1      
317m1626            VIA   -    MD0100PA01X+119944Y+165729X0180Y         S0      
317m1626            J108  -J1   D0142PA01X+123878Y+169169X0302Y    R180 S3      
327m1626            C6501 -1          A01X+119954Y+164239X0120Y0150R270 S1      
317m1627            VIA   -    MD0100PA01X+130458Y+165729X0180Y         S0      
317m1627            J107  -H2   D0142PA01X+131358Y+170035X0302Y    R180 S3      
327m1627            C6520 -1          A01X+130448Y+164239X0120Y0150R270 S1      
317m1628            VIA   -    MD0100PA01X+129252Y+165729X0180Y         S0      
317m1628            J107  -I1   D0142PA01X+130571Y+169642X0302Y    R180 S3      
327m1628            C6518 -1          A01X+129242Y+164239X0120Y0150R270 S1      
317m1629            VIA   -    MD0100PA01X+128046Y+165729X0180Y         S0      
317m1629            J108  -H8   D0142PA01X+129390Y+170035X0302Y    R180 S3      
327m1629            C6516 -1          A01X+128036Y+164239X0120Y0150R270 S1      
317m1630            VIA   -    MD0100PA01X+126840Y+165729X0180Y         S0      
317m1630            J108  -I7   D0142PA01X+128602Y+169642X0302Y    R180 S3      
327m1630            C6514 -1          A01X+126830Y+164239X0120Y0150R270 S1      
317m1631            VIA   -    MD0100PA01X+125634Y+165729X0180Y         S0      
327m1631            C6512 -1          A01X+125624Y+164239X0120Y0150R270 S1      
317m1631            J108  -H6   D0142PA01X+127815Y+170035X0302Y    R180 S3      
317m1632            VIA   -    MD0100PA01X+124428Y+165729X0180Y         S0      
317m1632            J108  -I5   D0142PA01X+127027Y+169642X0302Y    R180 S3      
327m1632            C6510 -1          A01X+124418Y+164239X0120Y0150R270 S1      
317m1633            VIA   -    MD0100PA01X+123222Y+165729X0180Y         S0      
317m1633            J108  -H4   D0142PA01X+126240Y+170035X0302Y    R180 S3      
327m1633            C6508 -1          A01X+123212Y+164239X0120Y0150R270 S1      
317m1634            VIA   -    MD0100PA01X+122016Y+165729X0180Y         S0      
317m1634            J108  -I3   D0142PA01X+125453Y+169642X0302Y    R180 S3      
327m1634            C6506 -1          A01X+122006Y+164239X0120Y0150R270 S1      
317m1635            VIA   -    MD0100PA01X+120810Y+165729X0180Y         S0      
317m1635            J108  -H2   D0142PA01X+124665Y+170035X0302Y    R180 S3      
327m1635            C6504 -1          A01X+120800Y+164239X0120Y0150R270 S1      
317m1636            VIA   -    MD0100PA01X+137694Y+165729X0180Y         S0      
317m1636            J107  -H8   D0142PA01X+136083Y+170035X0302Y    R180 S3      
327m1636            C6532 -1          A01X+137684Y+164239X0120Y0150R270 S1      
317m1637            VIA   -    MD0100PA01X+136488Y+165729X0180Y         S0      
317m1637            J107  -I7   D0142PA01X+135295Y+169642X0302Y    R180 S3      
327m1637            C6530 -1          A01X+136478Y+164239X0120Y0150R270 S1      
317m1638            VIA   -    MD0100PA01X+135282Y+165729X0180Y         S0      
317m1638            J107  -H6   D0142PA01X+134508Y+170035X0302Y    R180 S3      
327m1638            C6528 -1          A01X+135272Y+164239X0120Y0150R270 S1      
317m1639            VIA   -    MD0100PA01X+134076Y+165729X0180Y         S0      
317m1639            J107  -I5   D0142PA01X+133720Y+169642X0302Y    R180 S3      
327m1639            C6526 -1          A01X+134066Y+164239X0120Y0150R270 S1      
317m1640            VIA   -    MD0100PA01X+132870Y+165729X0180Y         S0      
317m1640            J107  -H4   D0142PA01X+132933Y+170035X0302Y    R180 S3      
327m1640            C6524 -1          A01X+132860Y+164239X0120Y0150R270 S1      
317m1641            VIA   -    MD0100PA01X+131664Y+165729X0180Y         S0      
317m1641            J107  -I3   D0142PA01X+132146Y+169642X0302Y    R180 S3      
327m1641            C6522 -1          A01X+131654Y+164239X0120Y0150R270 S1      
317m1642            VIA   -    MD0100PA01X+119604Y+165729X0180Y         S0      
317m1642            J108  -I1   D0142PA01X+123878Y+169642X0302Y    R180 S3      
327m1642            C6502 -1          A01X+119594Y+164239X0120Y0150R270 S1      
317m1643            VIA   -    MD0100PA01X+123865Y+158140X0180Y         S0      
327m1643            U6010 -BU1        A01X+123590Y+157348X0100Y0130     S1      
317m1643            J107  -C2   D0142PA01X+131358Y+172398X0302Y    R180 S3      
317m1644            VIA   -    MD0100PA01X+123392Y+158140X0180Y         S0      
327m1644            U6010 -CD1        A01X+123117Y+157348X0100Y0130     S1      
317m1644            J107  -D1   D0142PA01X+130571Y+172004X0302Y    R180 S3      
317m1645            VIA   -    MD0100PA01X+122920Y+158140X0180Y         S0      
327m1645            U6010 -CL1        A01X+122645Y+157348X0100Y0130     S1      
317m1645            J108  -C8   D0142PA01X+129390Y+172398X0302Y    R180 S3      
317m1646            VIA   -    MD0100PA01X+122447Y+158140X0180Y         S0      
327m1646            U6010 -CV1        A01X+122172Y+157348X0100Y0130     S1      
317m1646            J108  -D7   D0142PA01X+128602Y+172004X0302Y    R180 S3      
317m1647            VIA   -    MD0100PA01X+121975Y+158140X0180Y         S0      
327m1647            U6010 -DE1        A01X+121700Y+157348X0100Y0130     S1      
317m1647            J108  -C6   D0142PA01X+127815Y+172398X0302Y    R180 S3      
317m1648            VIA   -    MD0100PA01X+121502Y+158140X0180Y         S0      
327m1648            U6010 -DM1        A01X+121228Y+157348X0100Y0130     S1      
317m1648            J108  -D5   D0142PA01X+127027Y+172004X0302Y    R180 S3      
317m1649            VIA   -    MD0100PA01X+121030Y+158140X0180Y         S0      
327m1649            U6010 -DW1        A01X+120755Y+157348X0100Y0130     S1      
317m1649            J108  -C4   D0142PA01X+126240Y+172398X0302Y    R180 S3      
317m1650            VIA   -    MD0100PA01X+120558Y+158140X0180Y         S0      
327m1650            U6010 -EF1        A01X+120283Y+157348X0100Y0130     S1      
317m1650            J108  -D3   D0142PA01X+125453Y+172004X0302Y    R180 S3      
317m1651            VIA   -    MD0100PA01X+120085Y+158140X0180Y         S0      
327m1651            U6010 -EN1        A01X+119810Y+157348X0100Y0130     S1      
317m1651            J108  -C2   D0142PA01X+124665Y+172398X0302Y    R180 S3      
317m1652            VIA   -    MD0100PA01X+126699Y+158140X0180Y         S0      
327m1652            U6010 -R1         A01X+126424Y+157348X0100Y0130     S1      
317m1652            J107  -C8   D0142PA01X+136083Y+172398X0302Y    R180 S3      
317m1653            VIA   -    MD0100PA01X+126227Y+158140X0180Y         S0      
327m1653            U6010 -AB1        A01X+125952Y+157348X0100Y0130     S1      
317m1653            J107  -D7   D0142PA01X+135295Y+172004X0302Y    R180 S3      
317m1654            VIA   -    MD0100PA01X+125754Y+158140X0180Y         S0      
327m1654            U6010 -AJ1        A01X+125479Y+157348X0100Y0130     S1      
317m1654            J107  -C6   D0142PA01X+134508Y+172398X0302Y    R180 S3      
317m1655            VIA   -    MD0100PA01X+125282Y+158140X0180Y         S0      
327m1655            U6010 -AT1        A01X+125007Y+157348X0100Y0130     S1      
317m1655            J107  -D5   D0142PA01X+133720Y+172004X0302Y    R180 S3      
317m1656            VIA   -    MD0100PA01X+124810Y+158140X0180Y         S0      
327m1656            U6010 -BC1        A01X+124534Y+157348X0100Y0130     S1      
317m1656            J107  -C4   D0142PA01X+132933Y+172398X0302Y    R180 S3      
317m1657            VIA   -    MD0100PA01X+124337Y+158140X0180Y         S0      
327m1657            U6010 -BK1        A01X+124062Y+157348X0100Y0130     S1      
317m1657            J107  -D3   D0142PA01X+132146Y+172004X0302Y    R180 S3      
317m1658            VIA   -    MD0100PA01X+119613Y+158140X0180Y         S0      
327m1658            U6010 -EY1        A01X+119338Y+157348X0100Y0130     S1      
317m1658            J108  -D1   D0142PA01X+123878Y+172004X0302Y    R180 S3      
317m1659            VIA   -    MD0100PA01X+123865Y+157800X0180Y         S0      
327m1659            U6010 -BR2        A01X+123708Y+157143X0120Y         S1      
317m1659            J107  -B2   D0142PA01X+131358Y+172870X0302Y    R180 S3      
317m1660            VIA   -    MD0100PA01X+123392Y+157800X0180Y         S0      
327m1660            U6010 -CB2        A01X+123235Y+157143X0120Y         S1      
317m1660            J107  -C1   D0142PA01X+130571Y+172476X0302Y    R180 S3      
317m1661            VIA   -    MD0100PA01X+122920Y+157800X0180Y         S0      
327m1661            U6010 -CJ2        A01X+122763Y+157143X0120Y         S1      
317m1661            J108  -B8   D0142PA01X+129390Y+172870X0302Y    R180 S3      
317m1662            VIA   -    MD0100PA01X+122447Y+157800X0180Y         S0      
327m1662            U6010 -CT2        A01X+122290Y+157143X0120Y         S1      
317m1662            J108  -C7   D0142PA01X+128602Y+172476X0302Y    R180 S3      
317m1663            VIA   -    MD0100PA01X+121975Y+157800X0180Y         S0      
327m1663            U6010 -DC2        A01X+121818Y+157143X0120Y         S1      
317m1663            J108  -B6   D0142PA01X+127815Y+172870X0302Y    R180 S3      
317m1664            VIA   -    MD0100PA01X+121502Y+157800X0180Y         S0      
327m1664            U6010 -DK2        A01X+121346Y+157143X0120Y         S1      
317m1664            J108  -C5   D0142PA01X+127027Y+172476X0302Y    R180 S3      
317m1665            VIA   -    MD0100PA01X+121030Y+157800X0180Y         S0      
327m1665            U6010 -DU2        A01X+120873Y+157143X0120Y         S1      
317m1665            J108  -B4   D0142PA01X+126240Y+172870X0302Y    R180 S3      
317m1666            VIA   -    MD0100PA01X+120558Y+157800X0180Y         S0      
327m1666            U6010 -ED2        A01X+120401Y+157143X0120Y         S1      
317m1666            J108  -C3   D0142PA01X+125453Y+172476X0302Y    R180 S3      
317m1667            VIA   -    MD0100PA01X+120085Y+157800X0180Y         S0      
327m1667            U6010 -EL2        A01X+119928Y+157143X0120Y         S1      
317m1667            J108  -B2   D0142PA01X+124665Y+172870X0302Y    R180 S3      
317m1668            VIA   -    MD0100PA01X+126699Y+157800X0180Y         S0      
327m1668            U6010 -N2         A01X+126542Y+157143X0120Y         S1      
317m1668            J107  -B8   D0142PA01X+136083Y+172870X0302Y    R180 S3      
317m1669            VIA   -    MD0100PA01X+126227Y+157800X0180Y         S0      
327m1669            U6010 -Y2         A01X+126070Y+157143X0120Y         S1      
317m1669            J107  -C7   D0142PA01X+135295Y+172476X0302Y    R180 S3      
317m1670            VIA   -    MD0100PA01X+125754Y+157800X0180Y         S0      
327m1670            U6010 -AG2        A01X+125598Y+157143X0120Y         S1      
317m1670            J107  -B6   D0142PA01X+134508Y+172870X0302Y    R180 S3      
317m1671            VIA   -    MD0100PA01X+125282Y+157800X0180Y         S0      
327m1671            U6010 -AP2        A01X+125125Y+157143X0120Y         S1      
317m1671            J107  -C5   D0142PA01X+133720Y+172476X0302Y    R180 S3      
317m1672            VIA   -    MD0100PA01X+124810Y+157800X0180Y         S0      
327m1672            U6010 -BA2        A01X+124653Y+157143X0120Y         S1      
317m1672            J107  -B4   D0142PA01X+132933Y+172870X0302Y    R180 S3      
317m1673            VIA   -    MD0100PA01X+124337Y+157800X0180Y         S0      
327m1673            U6010 -BH2        A01X+124180Y+157143X0120Y         S1      
317m1673            J107  -C3   D0142PA01X+132146Y+172476X0302Y    R180 S3      
317m1674            VIA   -    MD0100PA01X+119613Y+157800X0180Y         S0      
327m1674            U6010 -EV2        A01X+119456Y+157143X0120Y         S1      
317m1674            J108  -C1   D0142PA01X+123878Y+172476X0302Y    R180 S3      
327m1675            R419  -2          A01X+065364Y+048694X0198Y0197     S1      
317m1675            VIA   -    MD0100PA00X+065752Y+048633X0200Y         S0      
327m1675            U18   -C17        A01X+070363Y+047029X0160Y    R090 S1      
317m1675            VIA   -    MD0100PA00X+070210Y+047182X0180Y    R090 S0      
327m1675            VIA   -    M      A18X+069624Y+047490X0260Y    R090 S2      
327m1676            J41   -OB11       A01X+072859Y+006516X0150Y0570R180 S1      
327m1676            R419  -1          A01X+065049Y+048694X0198Y0197     S1      
317m1676            VIA   -    M      A01X+066709Y+038515X0200Y         S2      
017m1676            VIA   -    M      A18X+066709Y+038515X0260Y         S2      
017m1676                  -    MD0100PA00X+066709Y+038515                       
317m1676            VIA   -    MD0100PA00X+065238Y+048239X0200Y         S0      
317m1676            VIA   -    MD0100PA00X+065195Y+009989X0200Y         S0      
317m1676            VIA   -    MD0100PA00X+072720Y+007321X0200Y         S0      
317m1677            VIA   -    MD0100PA00X+111946Y+155634X0200Y    R270 S0      
327m1677            VIA   -    M      A01X+111500Y+158794X0300Y    R270 S1      
327m1677            R353  -2   M      A01X+111500Y+158263X0198Y0197R090 S1      
327m1677            R354  -2          A01X+111503Y+159318X0198Y0197R270 S1      
317m1677            VIA   -    MD0100PA00X+170135Y+146656X0200Y         S0      
317m1677            VIA   -    MD0100PA00X+114306Y+051648X0200Y         S0      
327m1677            U18   -K4         A01X+072568Y+042934X0160Y    R090 S1      
317m1677            VIA   -    MD0100PA00X+072414Y+042781X0180Y    R090 S0      
317m1677            VIA   -    MD0100PA00X+073653Y+057648X0200Y         S0      
317m1677            VIA   -    MD0100PA00X+100527Y+062571X0200Y         S0      
317m1677            VIA   -    MD0100PA00X+177100Y+127806X0200Y         S0      
317m1677            VIA   -    MD0100PA00X+107331Y+145193X0200Y         S0      
327m1678            R353  -1          A01X+111500Y+157948X0198Y0197R090 S1      
327m1678            VIA   -    M      A01X+111500Y+157335X0300Y    R270 S1      
327m1678            U143  -4          A01X+111907Y+156524X0170Y0590R180 S1      
317m1679            VIA   -    MD0100PA00X+176965Y+128020X0200Y         S0      
317m1679            VIA   -    MD0100PA00X+113936Y+051603X0200Y         S0      
327m1679            U18   -N7         A01X+073513Y+043879X0160Y    R090 S1      
317m1679            VIA   -    MD0100PA00X+073666Y+043726X0180Y    R090 S0      
317m1679            VIA   -    MD0100PA00X+076504Y+056587X0200Y         S0      
317m1679            VIA   -    MD0100PA00X+102854Y+062100X0200Y         S0      
317m1679            VIA   -    MD0100PA00X+170525Y+146532X0200Y         S0      
317m1679            VIA   -    MD0100PA00X+107031Y+145203X0200Y         S0      
327m1679            R355  -2   M      A01X+110956Y+154766X0198Y0197R090 S1      
327m1679            R2628 -2          A01X+110952Y+155136X0198Y0197R270 S1      
317m1679            VIA   -    MD0100PA00X+111253Y+154766X0200Y    R270 S2      
327m1680            VIA   -    M      A01X+111317Y+155451X0300Y         S1      
327m1680            R2628 -1          A01X+110952Y+155451X0198Y0197R270 S1      
327m1680            U143  -6          A01X+112163Y+154673X0170Y0590R180 S1      
327m1681            R407  -2          A18X+064624Y+046193X0198Y0197R180 S2      
327m1681            U18   -E13        A01X+070993Y+045769X0160Y    R090 S1      
327m1681            VIA   -    M      A18X+068645Y+045958X0260Y    R090 S2      
317m1681            VIA   -    MD0100PA00X+070840Y+045922X0180Y    R090 S0      
327U9_NR            U9    -4          A01X+120485Y+009832X0160Y0360R270 S1      
317U9_NR            VIA   -    MD0100PA00X+120658Y+009485X0200Y         S2      
327U9_NR            C22   -1          A01X+121001Y+009485X0198Y0197     S1      
317m1682            VIA   -    MD0100PA00X+075806Y+151835X0200Y    R270 S0      
317m1682            VIA   -    M      A01X+070926Y+161790X0200Y         S2      
017m1682            VIA   -    M      A18X+070926Y+161790X0260Y         S2      
017m1682                  -    MD0100PA00X+070926Y+161790                       
327m1682            R348  -2          A01X+070572Y+161666X0198Y0197     S1      
317m1682            JP10  -2    D0410PA00X+075718Y+171277X0610Y         S3      
327m1682            PJ38  -19         A01X+076291Y+151835X0240Y0650R090 S1      
327m1683            R347  -2          A01X+069915Y+162306X0198Y0197R180 S1      
317m1683            JP10  -1    D0410PA00X+075718Y+172277X0610Y0610     S3      
317m1683            VIA   -    MD0100PA00X+069593Y+162346X0200Y         S0      
317m1683            VIA   -    MD0100PA00X+075783Y+151441X0200Y    R270 S2      
327m1683            PJ38  -18         A01X+076291Y+151441X0240Y0650R090 S1      
317m1684            VIA   -    MD0100PA00X+164938Y+144671X0200Y         S0      
317m1684            VIA   -    M      A01X+128770Y+143170X0200Y         S2      
017m1684            VIA   -    M      A18X+128770Y+143170X0260Y         S2      
017m1684                  -    MD0100PA00X+128770Y+143170                       
327m1684            R352  -2          A01X+128468Y+143000X0198Y0197     S1      
327m1684            R6857 -1          A01X+165789Y+145228X0198Y0197R090 S1      
327m1684            R119  -1          A01X+164975Y+144049X0198Y0197R180 S1      
327m1685            R6856 -1          A01X+165361Y+145226X0198Y0197R090 S1      
327m1685            R118  -1          A01X+163959Y+144223X0198Y0197     S1      
317m1685            VIA   -    M      A01X+164117Y+144675X0200Y         S2      
017m1685            VIA   -    M      A18X+164117Y+144675X0260Y         S2      
017m1685                  -    MD0100PA00X+164117Y+144675                       
327m1685            R351  -2          A01X+128468Y+143400X0198Y0197     S1      
317m1685            VIA   -    MD0100PA00X+129170Y+143170X0200Y         S0      
317m1686            VIA   -    MD0100PA00X+119400Y+144750X0200Y         S0      
317m1686            VIA   -    M      A01X+127952Y+143200X0200Y         S2      
017m1686            VIA   -    M      A18X+127952Y+143200X0260Y         S2      
017m1686                  -    MD0100PA00X+127952Y+143200                       
327m1686            R350  -2          A01X+063500Y+140458X0198Y0197R090 S1      
327m1686            R352  -1          A01X+128152Y+143000X0198Y0197     S1      
317m1686            VIA   -    MD0100PA00X+118020Y+145710X0200Y         S0      
327m1686            R8072 -1          A01X+119692Y+144750X0198Y0197     S1      
317m1687            VIA   -    M      A01X+119400Y+144250X0200Y         S2      
017m1687            VIA   -    M      A18X+119400Y+144250X0260Y         S2      
017m1687                  -    MD0100PA00X+119400Y+144250                       
317m1687            VIA   -    MD0100PA00X+127650Y+143200X0200Y         S0      
327m1687            R349  -2          A01X+063000Y+140458X0198Y0197R090 S1      
327m1687            R351  -1          A01X+128152Y+143400X0198Y0197     S1      
317m1687            VIA   -    MD0100PA00X+117650Y+145707X0200Y         S0      
327m1687            R8071 -1          A01X+119692Y+144250X0198Y0197     S1      
327m1688            R86   -2   M      A01X+124999Y+045318X0198Y0197R180 S1      
327m1688            R43   -2          A01X+125894Y+045437X0198Y0197R180 S1      
327m1688            VIA   -    M      A01X+124519Y+045318X0300Y         S1      
327m1688            U64   -5          A01X+123834Y+045538X0350Y0500R270 S1      
327m1689            R85   -2   M      A01X+124999Y+045818X0198Y0197R180 S1      
327m1689            R26   -2          A01X+125887Y+045918X0198Y0197R180 S1      
327m1689            VIA   -    M      A01X+124519Y+045818X0300Y         S1      
327m1689            U64   -6          A01X+123834Y+046038X0350Y0500R270 S1      
327m1690            R24   -2   M      A01X+123688Y+043126X0198Y0197R180 S1      
327m1690            R125  -2          A01X+123688Y+042726X0198Y0197R180 S1      
327m1690            VIA   -    M      A01X+123215Y+043188X0300Y         S1      
327m1690            U1    -5          A01X+122565Y+043188X0350Y0500R270 S1      
327m1691            R4    -2   M      A01X+123688Y+043526X0198Y0197R180 S1      
327m1691            R121  -2          A01X+123688Y+043926X0198Y0197R180 S1      
327m1691            VIA   -    M      A01X+123215Y+043688X0300Y         S1      
327m1691            U1    -6          A01X+122565Y+043688X0350Y0500R270 S1      
327m1692            R326  -2          A18X+090750Y+095922X0180Y0200R090 S2      
317m1692            VIA   -    M      A01X+090750Y+096331X0200Y         S2      
017m1692            VIA   -    M      A18X+090750Y+096331X0260Y         S2      
017m1692                  -    MD0100PA00X+090750Y+096331                       
327m1692            U4    -7          A18X+091424Y+097749X0100Y0210R270 S2      
317m1692            VIA   -    MD0100PA00X+090900Y+097749X0200Y         S0      
327m1693            R325  -2          A18X+091250Y+095922X0180Y0200R090 S2      
327m1693            U4    -8          A18X+091424Y+097946X0100Y0210R270 S2      
317m1693            VIA   -    MD0100PA00X+091104Y+097946X0200Y         S0      
317m1693            VIA   -    M      A01X+091250Y+096331X0200Y         S2      
017m1693            VIA   -    M      A18X+091250Y+096331X0260Y         S2      
017m1693                  -    MD0100PA00X+091250Y+096331                       
327m1694            R323  -2          A18X+090750Y+095292X0180Y0200R270 S2      
327m1694            R147  -1          A18X+090100Y+091242X0198Y0197R270 S2      
317m1694            VIA   -    MD0100PA00X+090100Y+090900X0200Y         S0      
317m1694            VIA   -    MD0100PA00X+090708Y+094850X0200Y         S0      
327m1694            R143  -1   M      A18X+090708Y+094500X0198Y0197     S2      
327m1694            VIA   -    M      A18X+090700Y+094150X0260Y         S2      
327m1694            U213  -2          A18X+090901Y+093484X0100Y0220R180 S2      
327m1695            R324  -2          A18X+091250Y+095292X0180Y0200R270 S2      
317m1695            VIA   -    MD0100PA00X+091242Y+094850X0200Y         S0      
327m1695            VIA   -    M      A18X+091242Y+094150X0260Y         S2      
327m1695            U213  -3          A18X+091098Y+093484X0100Y0220R180 S2      
327m1695            R142  -1   M      A18X+091242Y+094500X0198Y0197R180 S2      
317m1695            VIA   -    MD0100PA00X+091700Y+090900X0200Y         S0      
327m1695            R146  -1          A18X+091700Y+091242X0198Y0197R270 S2      
327m1696            R281  -1          A18X+092081Y+083960X0180Y0200     S2      
327m1696            VIA   -    M      A18X+090701Y+084956X0260Y         S2      
327m1696            R206  -2          A18X+090550Y+085692X0198Y0197R090 S2      
327m1696            R290  -2   M      A18X+090558Y+085300X0198Y0197R180 S2      
327m1697            U2    -3          A18X+090680Y+086956X0170Y0460R180 S2      
327m1697            R206  -1          A18X+090550Y+086008X0198Y0197R090 S2      
327m1697            VIA   -    M      A18X+090550Y+086350X0260Y    R090 S2      
327m1698            R162  -2          A18X+091842Y+089800X0180Y0200R180 S2      
327m1698            VIA   -    M      A18X+091500Y+089800X0260Y         S2      
327m1698            U2    -6          A18X+090680Y+088668X0170Y0460R180 S2      
327m1699            R274  -1          A18X+092092Y+084719X0180Y0200     S2      
327m1699            VIA   -    M      A18X+091384Y+084666X0260Y         S2      
327m1699            R202  -2          A18X+091050Y+085692X0198Y0197R090 S2      
327m1699            R322  -2   M      A18X+091092Y+085300X0198Y0197     S2      
327m1700            R202  -1          A18X+091050Y+086008X0198Y0197R090 S2      
327m1700            VIA   -    M      A18X+091050Y+086350X0260Y    R090 S2      
327m1700            U2    -2          A18X+090936Y+086956X0170Y0460R180 S2      
327m1701            R151  -2          A18X+091842Y+089300X0180Y0200R180 S2      
327m1701            VIA   -    M      A18X+091500Y+089300X0260Y         S2      
327m1701            U2    -7          A18X+090936Y+088668X0170Y0460R180 S2      
327m1702            R257  -1          A18X+092711Y+083960X0180Y0200R180 S2      
327m1702            VIA   -    M      A18X+094103Y+084661X0260Y         S2      
327m1702            R365  -2   M      A18X+094292Y+085050X0198Y0197     S2      
327m1702            R1152 -2          A18X+094300Y+085542X0198Y0197R090 S2      
327m1703            R150  -2          A18X+092472Y+089800X0180Y0200     S2      
327m1703            VIA   -    M      A18X+092800Y+089800X0260Y         S2      
327m1703            R790  -1   M      A18X+094192Y+089450X0198Y0197R180 S2      
327m1703            U5    -3          A18X+094120Y+088692X0170Y0460     S2      
327m1704            R256  -1          A18X+092722Y+084719X0180Y0200R180 S2      
327m1704            VIA   -    M      A18X+093413Y+084450X0260Y         S2      
327m1704            R361  -2   M      A18X+093808Y+085050X0198Y0197R180 S2      
327m1704            R1151 -2          A18X+093800Y+085542X0198Y0197R090 S2      
327m1705            R140  -2          A18X+092472Y+089300X0180Y0200     S2      
327m1705            VIA   -    M      A18X+092800Y+089300X0260Y         S2      
327m1705            U5    -2          A18X+093864Y+088692X0170Y0460     S2      
327m1705            R789  -1   M      A18X+093808Y+089450X0198Y0197     S2      
327m1706            R338  -1          A18X+092350Y+095122X0180Y0200R270 S2      
327m1706            U4    -4          A18X+091928Y+097552X0120Y0210R270 S2      
327m1706            VIA   -    M      A18X+092350Y+095630X0260Y    R090 S2      
327m1707            R337  -1          A18X+092850Y+095122X0180Y0200R270 S2      
327m1707            U4    -3          A18X+091928Y+097749X0100Y0210R270 S2      
327m1707            VIA   -    M      A18X+092850Y+095634X0260Y    R090 S2      
327m1708            R328  -1          A18X+093078Y+097750X0180Y0200     S2      
327m1708            VIA   -    M      A18X+092700Y+097750X0260Y    R090 S2      
327m1708            U4    -2          A18X+091928Y+097946X0100Y0210R270 S2      
327m1709            R327  -1          A18X+093078Y+098250X0180Y0200     S2      
327m1709            U4    -1          A18X+091928Y+098143X0120Y0210R270 S2      
327m1709            VIA   -    M      A18X+092700Y+098250X0260Y    R090 S2      
327m1710            U252  -3          A01X+019876Y+171244X0160Y0200R270 S1      
317m1710            VIA   -    MD0100PA00X+019676Y+171044X0200Y         S0      
317m1710            VIA   -    M      A01X+084166Y+055820X0200Y         S2      
017m1710            VIA   -    M      A18X+084166Y+055820X0260Y         S2      
017m1710                  -    MD0100PA00X+084166Y+055820                       
327m1710            R2    -2          A18X+079340Y+045652X0198Y0197R180 S2      
317m1710            VIA   -    MD0100PA00X+084282Y+045274X0200Y         S0      
327m1711            R3    -1          A18X+079025Y+046052X0198Y0197R180 S2      
327m1711            R2    -1   M      A18X+079025Y+045652X0198Y0197R180 S2      
327m1711            U18   -V11        A01X+075087Y+045139X0160Y    R090 S1      
327m1711            VIA   -    M      A18X+076606Y+045138X0260Y    R090 S2      
317m1711            VIA   -    MD0100PA00X+075241Y+044985X0180Y    R090 S0      
327PU_U2_EN         R201  -2          A18X+090384Y+089663X0198Y0197R090 S2      
327PU_U2_EN         VIA   -    M      A18X+090394Y+089300X0260Y    R090 S2      
327PU_U2_EN         U2    -5          A18X+090394Y+088668X0240Y0460R180 S2      
327PD_CPU_FRU_WP    R44   -1          A01X+123688Y+044326X0198Y0197     S1      
327PD_CPU_FRU_WP    VIA   -    M      A01X+123215Y+044188X0300Y         S1      
327PD_CPU_FRU_WP    U1    -7          A01X+122565Y+044188X0350Y0500R270 S1      
327m1712            R133  -2          A01X+083698Y+046358X0198Y0197R180 S1      
317m1712            VIA   -    MD0100PA00X+083375Y+046358X0200Y         S0      
327m1712            U18   -P5         A01X+073828Y+043249X0160Y    R090 S1      
317m1712            VIA   -    MD0100PA00X+073981Y+043096X0180Y    R090 S2      
327m1713            U4    -9          A18X+091424Y+098143X0120Y0210R270 S2      
317m1713            VIA   -    M      A01X+090900Y+098200X0200Y    R180 S2      
017m1713            VIA   -    M      A18X+090900Y+098200X0260Y    R180 S2      
017m1713                  -    MD0100PA00X+090900Y+098200                       
317m1713            VIA   -    MD0100PA00X+090454Y+074464X0200Y    R270 S0      
327m1713            R133  -1   M      A01X+084013Y+046358X0198Y0197R180 S1      
327m1713            R135  -1          A01X+084013Y+045558X0198Y0197R180 S1      
327m1713            R136  -1   M      A01X+084013Y+045958X0198Y0197R180 S1      
317m1713            VIA   -    MD0100PA00X+083920Y+046790X0200Y         S0      
317m1713            VIA   -    MD0100PA00X+090721Y+066765X0200Y         S0      
317m1714            VIA   -    MD0100PA00X+083380Y+044470X0200Y         S2      
327m1714            R132  -2          A01X+083698Y+044355X0198Y0197R180 S1      
327m1714            U18   -P6         A01X+073828Y+043564X0160Y    R090 S1      
317m1714            VIA   -    MD0100PA00X+073981Y+043411X0180Y    R090 S0      
327m1715            U4    -6          A18X+091424Y+097552X0120Y0210R270 S2      
317m1715            VIA   -    M      A01X+090900Y+097400X0200Y         S2      
017m1715            VIA   -    M      A18X+090900Y+097400X0260Y         S2      
017m1715                  -    MD0100PA00X+090900Y+097400                       
317m1715            VIA   -    MD0100PA00X+090634Y+074241X0200Y    R270 S0      
327m1715            R132  -1   M      A01X+084013Y+044355X0198Y0197R180 S1      
327m1715            R134  -1   M      A01X+084013Y+043955X0198Y0197R180 S1      
327m1715            R126  -1          A01X+084013Y+043555X0198Y0197R180 S1      
317m1715            VIA   -    MD0100PA00X+084510Y+044010X0200Y         S0      
317m1715            VIA   -    MD0100PA00X+090932Y+066393X0200Y         S0      
327CPU_FRU_ADDR2    R52   -2          A01X+119150Y+043620X0198Y0197     S1      
327CPU_FRU_ADDR2    R54   -1   M      A01X+119150Y+043220X0198Y0197R180 S1      
327CPU_FRU_ADDR2    U1    -3          A01X+120518Y+043688X0350Y0500R270 S1      
327CPU_FRU_ADDR2    VIA   -    M      A01X+119623Y+043220X0300Y         S1      
327CPU_FRU_ADDR1    R60   -2          A01X+119150Y+044420X0198Y0197     S1      
327CPU_FRU_ADDR1    R62   -1   M      A01X+119150Y+044020X0198Y0197R180 S1      
327CPU_FRU_ADDR1    U1    -2          A01X+120518Y+044188X0350Y0500R270 S1      
327CPU_FRU_ADDR1    VIA   -    M      A01X+119623Y+044020X0300Y         S1      
327CPU_FRU_ADDR0    R68   -2          A01X+119150Y+045220X0198Y0197     S1      
327CPU_FRU_ADDR0    R69   -1   M      A01X+119150Y+044820X0198Y0197R180 S1      
327CPU_FRU_ADDR0    U1    -1          A01X+120518Y+044688X0350Y0500R270 S1      
327CPU_FRU_ADDR0    VIA   -    M      A01X+119623Y+044820X0300Y         S1      
327m1716            U6002 -61         A01X+042677Y+011515X0094Y0236R090 S1      
317m1716            VIA   -    M      A01X+041410Y+009662X0200Y         S2      
017m1716            VIA   -    M      A18X+041410Y+009662X0260Y         S2      
017m1716                  -    MD0100PA00X+041410Y+009662                       
327m1716            C6090 -1   M      A01X+041628Y+009915X0198Y0197R180 S1      
327m1716            R6257 -1   M      A01X+041668Y+010415X0198Y0197     S1      
327m1716            Y6000 -3          A01X+041496Y+009201X0480Y0560R180 S1      
327m1717            U6002 -62         A01X+042677Y+011318X0094Y0236R090 S1      
317m1717            VIA   -    M      A01X+041990Y+009662X0200Y         S2      
017m1717            VIA   -    M      A18X+041990Y+009662X0260Y         S2      
017m1717                  -    MD0100PA00X+041990Y+009662                       
327m1717            C6091 -1   M      A01X+042023Y+009915X0198Y0197     S1      
327m1717            R6257 -2   M      A01X+041983Y+010415X0198Y0197     S1      
327m1717            Y6000 -1          A01X+042166Y+008335X0480Y0560R180 S1      
327m1718            U6002 -28         A01X+046141Y+013090X0094Y0236R090 S1      
327m1718            VIA   -    M      A01X+046668Y+012425X0300Y         S1      
327m1718            R6267 -1          A01X+047362Y+011564X0198Y0197     S1      
327m1719            U6002 -21         A01X+046141Y+011712X0094Y0236R090 S1      
327m1719            VIA   -    M      A01X+046835Y+011201X0300Y         S1      
327m1719            R6265 -1          A01X+047355Y+010557X0198Y0197     S1      
327m1720            U6002 -5          A01X+043720Y+010668X0094Y0236     S1      
327m1720            VIA   -    M      A01X+043648Y+009817X0300Y         S1      
327m1720            R6260 -1          A01X+043867Y+008028X0198Y0197R270 S1      
327m1721            U6002 -31         A01X+046141Y+013680X0094Y0236R090 S1      
327m1721            VIA   -    M      A01X+046660Y+013800X0300Y         S1      
327m1721            R6269 -1          A01X+047362Y+012364X0198Y0197     S1      
327m1722            U6002 -8          A01X+044311Y+010668X0094Y0236     S1      
327m1722            VIA   -    M      A01X+044019Y+009339X0300Y         S1      
327m1722            R6262 -1          A01X+044267Y+008728X0198Y0197R270 S1      
327m1723            U6002 -34         A01X+045688Y+014133X0094Y0236     S1      
327m1723            VIA   -    M      A01X+048600Y+015575X0300Y         S1      
327m1723            R6275 -1          A01X+049000Y+016055X0198Y0197R090 S1      
327m1723            R6276 -1   M      A01X+048600Y+016055X0198Y0197R090 S1      
327m1724            U6002 -16         A01X+045885Y+010668X0094Y0236     S1      
327m1724            VIA   -    M      A01X+046640Y+009590X0300Y         S1      
327m1724            R6274 -1          A01X+047355Y+009057X0198Y0197     S1      
327m1725            U6002 -48         A01X+042933Y+014133X0094Y0236     S1      
327m1725            VIA   -    M      A01X+040730Y+020150X0300Y         S1      
327m1725            R6316 -2   M      A01X+040730Y+020654X0198Y0197R270 S1      
327m1725            R6317 -2          A01X+040330Y+020654X0198Y0197R270 S1      
327m1726            R6316 -1          A01X+040730Y+020970X0198Y0197R270 S1      
317m1726            VIA   -    M      A01X+041130Y+021210X0200Y         S2      
017m1726            VIA   -    M      A18X+041130Y+021210X0260Y         S2      
017m1726                  -    MD0100PA00X+041130Y+021210                       
327m1726            R6319 -1          A01X+041130Y+021450X0198Y0197R090 S1      
327m1726            R6318 -2   M      A01X+041130Y+020970X0198Y0197R090 S1      
327m1727            U6002 -6          A01X+043917Y+010668X0094Y0236     S1      
327m1727            VIA   -    M      A01X+044222Y+010093X0300Y         S1      
327m1727            R6261 -1          A01X+043867Y+008728X0198Y0197R270 S1      
327m1728            U6002 -30         A01X+046141Y+013483X0094Y0236R090 S1      
327m1728            VIA   -    M      A01X+046660Y+013300X0300Y         S1      
327m1728            R6268 -1          A01X+047362Y+011964X0198Y0197     S1      
327m1729            U6002 -23         A01X+046141Y+012105X0094Y0236R090 S1      
327m1729            VIA   -    M      A01X+046660Y+011800X0300Y         S1      
327m1729            R6266 -1          A01X+047355Y+011057X0198Y0197     S1      
327m1730            U6002 -64         A01X+042677Y+010924X0094Y0236R090 S1      
327m1730            VIA   -    M      A01X+042808Y+009888X0300Y         S1      
327m1730            R6331 -1   M      A01X+042968Y+009423X0198Y0197R270 S1      
327m1730            R6332 -1          A01X+043368Y+009423X0198Y0197R270 S1      
327m1731            U6002 -17         A01X+046141Y+010924X0094Y0236R090 S1      
327m1731            VIA   -    M      A01X+046987Y+010087X0300Y         S1      
327m1731            R6263 -1          A01X+047355Y+009557X0198Y0197     S1      
327m1732            U6002 -1          A01X+042933Y+010668X0094Y0236     S1      
327m1732            VIA   -    M      A01X+043220Y+010180X0300Y         S1      
327m1732            R6271 -1          A01X+043367Y+008728X0198Y0197R270 S1      
327m1733            U6002 -18         A01X+046141Y+011121X0094Y0236R090 S1      
327m1733            VIA   -    M      A01X+046569Y+010594X0300Y         S1      
327m1733            R6264 -1          A01X+047355Y+010057X0198Y0197     S1      
327m1734            U6002 -49         A01X+042677Y+013877X0094Y0236R090 S1      
327m1734            VIA   -    M      A01X+042053Y+014423X0300Y         S1      
327m1734            R6324 -2          A01X+041572Y+014830X0198Y0197     S1      
327m1734            R6323 -2   M      A01X+041572Y+014430X0198Y0197     S1      
327m1735            U6002 -39         A01X+044704Y+014133X0094Y0236     S1      
327m1735            VIA   -    M      A01X+046200Y+015575X0300Y         S1      
327m1735            R6282 -2   M      A01X+046200Y+016055X0198Y0197R270 S1      
327m1735            R6281 -1          A01X+046600Y+016055X0198Y0197R090 S1      
327m1736            U6002 -37         A01X+045098Y+014133X0094Y0236     S1      
327m1736            VIA   -    M      A01X+047400Y+015575X0300Y         S1      
327m1736            R6279 -2          A01X+047400Y+016055X0198Y0197R270 S1      
327m1737            U6002 -38         A01X+044901Y+014133X0094Y0236     S1      
327m1737            VIA   -    M      A01X+046900Y+015575X0300Y         S1      
327m1737            R6280 -2          A01X+047000Y+016055X0198Y0197R270 S1      
327m1738            U6002 -41         A01X+044311Y+014133X0094Y0236     S1      
327m1738            VIA   -    M      A01X+044680Y+014850X0300Y         S1      
327m1738            R6285 -2   M      A01X+044600Y+015355X0198Y0197R270 S1      
327m1738            R6286 -2          A01X+045000Y+015355X0198Y0197R270 S1      
327m1739            VIA   -    M      A01X+044124Y+014932X0300Y         S1      
327m1739            R6288 -1   M      A01X+044200Y+016055X0198Y0197R090 S1      
327m1739            R6287 -2          A01X+044600Y+016055X0198Y0197R270 S1      
327m1739            R6285 -1          A01X+044600Y+015670X0198Y0197R270 S1      
327m1740            U6002 -33         A01X+045885Y+014133X0094Y0236     S1      
327m1740            VIA   -    M      A01X+046264Y+014617X0300Y         S1      
327m1740            R6270 -2          A01X+046660Y+014595X0198Y0197R090 S1      
327m1741            U6002 -35         A01X+045492Y+014133X0094Y0236     S1      
327m1741            VIA   -    M      A01X+047900Y+015575X0300Y         S1      
327m1741            R6258 -2   M      A01X+047800Y+016055X0198Y0197R270 S1      
327m1741            R6259 -2          A01X+048200Y+016055X0198Y0197R270 S1      
327m1742            U6002 -43         A01X+043917Y+014133X0094Y0236     S1      
327m1742            VIA   -    M      A01X+045122Y+020182X0300Y         S1      
327m1742            R6296 -2          A01X+045122Y+021062X0198Y0197R180 S1      
327m1742            R6295 -2   M      A01X+045122Y+020662X0198Y0197R180 S1      
327m1743            U6002 -44         A01X+043720Y+014133X0094Y0236     S1      
327m1743            VIA   -    M      A01X+044330Y+020174X0300Y         S1      
327m1743            R6300 -2          A01X+044730Y+020654X0198Y0197R270 S1      
327m1743            R6299 -2   M      A01X+044330Y+020654X0198Y0197R270 S1      
317m1744            VIA   -    M      A01X+044330Y+021210X0200Y         S2      
017m1744            VIA   -    M      A18X+044330Y+021210X0260Y         S2      
017m1744                  -    MD0100PA00X+044330Y+021210                       
327m1744            R6299 -1          A01X+044330Y+020970X0198Y0197R270 S1      
327m1744            R6301 -2          A01X+044330Y+021450X0198Y0197R270 S1      
327m1745            U6002 -47         A01X+043130Y+014133X0094Y0236     S1      
327m1745            VIA   -    M      A01X+041930Y+020100X0300Y         S1      
327m1745            R6313 -2          A01X+041530Y+020654X0198Y0197R270 S1      
327m1745            R6314 -2   M      A01X+041930Y+020654X0198Y0197R270 S1      
327m1746            R6313 -1          A01X+041530Y+020970X0198Y0197R270 S1      
327m1746            VIA   -    M      A01X+042000Y+021994X0300Y         S1      
327m1746            R6315 -2          A01X+041530Y+021450X0198Y0197R270 S1      
327m1747            U6002 -46         A01X+043326Y+014133X0094Y0236     S1      
327m1747            VIA   -    M      A01X+042730Y+019950X0300Y         S1      
327m1747            R6311 -2          A01X+042330Y+020654X0198Y0197R270 S1      
327m1747            R6310 -2   M      A01X+042730Y+020654X0198Y0197R270 S1      
327m1748            R6310 -1          A01X+042730Y+020970X0198Y0197R270 S1      
327m1748            VIA   -    M      A01X+042230Y+021493X0300Y         S1      
327m1748            R6312 -2          A01X+042730Y+021450X0198Y0197R270 S1      
327m1749            VIA   -    M      A01X+045917Y+020462X0300Y    R090 S1      
327m1749            R6295 -1          A01X+045437Y+020662X0198Y0197R180 S1      
327m1749            R6297 -2          A01X+046542Y+020662X0198Y0197R180 S1      
327m1750            U6002 -60         A01X+042677Y+011712X0094Y0236R090 S1      
327m1750            VIA   -    M      A01X+041440Y+011077X0300Y         S1      
327m1750            R6330 -2          A01X+040624Y+010565X0198Y0197R090 S1      
327m1751            U6002 -45         A01X+043523Y+014133X0094Y0236     S1      
327m1751            VIA   -    M      A01X+043530Y+020174X0300Y         S1      
327m1751            R6305 -2          A01X+043930Y+020654X0198Y0197R270 S1      
327m1751            R6304 -2   M      A01X+043530Y+020654X0198Y0197R270 S1      
317m1752            VIA   -    M      A01X+043130Y+021210X0200Y         S2      
017m1752            VIA   -    M      A18X+043130Y+021210X0260Y         S2      
017m1752                  -    MD0100PA00X+043130Y+021210                       
327m1752            R6306 -2          A01X+043130Y+021450X0198Y0197R270 S1      
327m1752            R6304 -1          A01X+043530Y+020970X0198Y0197R270 S1      
327m1752            R6307 -1   M      A01X+043130Y+020970X0198Y0197R270 S1      
327m1753            U6002 -50         A01X+042677Y+013680X0094Y0236R090 S1      
327m1753            VIA   -    M      A01X+040388Y+013398X0300Y         S1      
327m1753            R6328 -2   M      A01X+039926Y+012672X0198Y0197R090 S1      
327m1753            C6089 -1          A01X+038670Y+012691X0198Y0197R270 S1      
327m1753            R6329 -2   M      A01X+039505Y+012675X0198Y0197R090 S1      
327m1753            R6333 -1   M      A01X+039086Y+012696X0198Y0197R270 S1      
327m1754            U6002 -42         A01X+044114Y+014133X0094Y0236     S1      
327m1754            VIA   -    M      A01X+043538Y+014985X0300Y         S1      
327m1754            R6290 -1          A01X+043400Y+015355X0198Y0197R090 S1      
327m1754            R6291 -1   M      A01X+043800Y+015355X0198Y0197R090 S1      
327m1755            VIA   -    M      A01X+042920Y+015589X0300Y         S1      
327m1755            R6293 -1   M      A01X+043000Y+016055X0198Y0197R090 S1      
327m1755            R6292 -2          A01X+043400Y+016055X0198Y0197R270 S1      
327m1755            R6290 -2          A01X+043400Y+015670X0198Y0197R090 S1      
327m1756            U6002 -40         A01X+044507Y+014133X0094Y0236     S1      
327m1756            VIA   -    M      A01X+045500Y+015575X0300Y         S1      
327m1756            R6283 -2          A01X+045400Y+016055X0198Y0197R270 S1      
327m1756            R6284 -1   M      A01X+045800Y+016055X0198Y0197R090 S1      
327m1757            R6286 -1          A01X+045000Y+015670X0198Y0197R270 S1      
317m1757            VIA   -    M      A01X+044804Y+015866X0200Y         S2      
017m1757            VIA   -    M      A18X+044804Y+015866X0260Y         S2      
017m1757                  -    MD0100PA00X+044804Y+015866                       
327m1757            R6289 -2          A01X+045000Y+016055X0198Y0197R270 S1      
327m1758            R6317 -1   M      A01X+040330Y+020970X0198Y0197R270 S1      
327m1758            VIA   -    M      A01X+039860Y+020970X0300Y    R270 S1      
327m1758            C6088 -1          A01X+039215Y+020970X0400Y0500R270 S1      
327m1758            R6321 -1          A01X+039930Y+021450X0198Y0197R090 S1      
327m1758            R6320 -2          A01X+040730Y+021450X0198Y0197R270 S1      
327m1758            R6322 -2   M      A01X+040330Y+021450X0198Y0197R270 S1      
327m1759            R6278 -1          A01X+048992Y+017162X0198Y0197     S1      
327m1759            R6277 -2   M      A01X+048992Y+016762X0198Y0197R180 S1      
327m1759            VIA   -    M      A01X+048526Y+016839X0300Y    R180 S1      
327m1759            R6276 -2          A01X+048600Y+016370X0198Y0197R090 S1      
327m1760            R6324 -1          A01X+041257Y+014830X0198Y0197     S1      
327m1760            VIA   -    M      A01X+041342Y+015315X0300Y    R090 S1      
327m1760            R6326 -1          A01X+040872Y+014430X0198Y0197R180 S1      
327m1760            R6327 -2   M      A01X+040872Y+014830X0198Y0197     S1      
327m1761            VIA   -    M      A01X+045917Y+020962X0300Y    R090 S1      
327m1761            R6296 -1          A01X+045437Y+021062X0198Y0197R180 S1      
327m1761            R6298 -2          A01X+046542Y+021062X0198Y0197R180 S1      
317m1762            VIA   -    M      A01X+043610Y+015859X0200Y         S2      
017m1762            VIA   -    M      A18X+043610Y+015859X0260Y         S2      
017m1762                  -    MD0100PA00X+043610Y+015859                       
327m1762            R6294 -2          A01X+043800Y+016055X0198Y0197R270 S1      
327m1762            R6291 -2          A01X+043800Y+015670X0198Y0197R090 S1      
317m1763            VIA   -    M      A01X+043136Y+008259X0200Y         S2      
017m1763            VIA   -    M      A18X+043136Y+008259X0260Y         S2      
017m1763                  -    MD0100PA00X+043136Y+008259                       
327m1763            R6271 -2          A01X+043367Y+008412X0198Y0197R270 S1      
327m1763            R6272 -1          A01X+042967Y+008028X0198Y0197R270 S1      
327m1763            R6273 -2   M      A01X+043367Y+008028X0198Y0197R090 S1      
317m1764            VIA   -    M      A01X+043820Y+021210X0200Y         S2      
017m1764            VIA   -    M      A18X+043820Y+021210X0260Y         S2      
017m1764                  -    MD0100PA00X+043820Y+021210                       
327m1764            R6305 -1          A01X+043930Y+020970X0198Y0197R270 S1      
327m1764            R6309 -1   M      A01X+043930Y+021450X0198Y0197R090 S1      
327m1764            R6308 -2          A01X+043530Y+021450X0198Y0197R270 S1      
317m1765            VIA   -    M      A01X+044850Y+021204X0200Y         S2      
017m1765            VIA   -    M      A18X+044850Y+021204X0260Y         S2      
017m1765                  -    MD0100PA00X+044850Y+021204                       
327m1765            R6300 -1          A01X+044730Y+020970X0198Y0197R270 S1      
327m1765            R6302 -1          A01X+045130Y+021450X0198Y0197R090 S1      
327m1765            R6303 -2   M      A01X+044730Y+021450X0198Y0197R270 S1      
317m1766            VIA   -    MD0100PA00X+144100Y+161450X0200Y         S0      
327m1766            R6253 -2          A01X+144050Y+161742X0198Y0197R270 S1      
317m1766            VIA   -    MD0100PA00X+168550Y+166360X0200Y         S0      
327m1766            U6005 -4          A01X+169203Y+168073X0090Y0240     S1      
327m1766            R6254 -2          A01X+168401Y+166617X0198Y0197R270 S1      
317m1766            VIA   -    M      A01X+169599Y+167162X0200Y    R270 S2      
017m1766            VIA   -    M      A18X+169599Y+167162X0260Y    R270 S2      
017m1766                  -    MD0100PA00X+169599Y+167162                       
317m1767            VIA   -    M      A01X+170198Y+167162X0200Y    R090 S2      
017m1767            VIA   -    M      A18X+170198Y+167162X0260Y    R090 S2      
017m1767                  -    MD0100PA00X+170198Y+167162                       
327m1767            U6005 -5          A01X+169458Y+168329X0090Y0240R090 S1      
327m1767            R6252 -2          A01X+144550Y+161742X0198Y0197R270 S1      
317m1767            VIA   -    MD0100PA00X+144550Y+161450X0200Y         S0      
327m1768            U6002 -52         A01X+042677Y+013286X0094Y0236R090 S1      
327m1768            U6002 -63         A01X+042677Y+011121X0094Y0236R090 S1      
327m1768            R6275 -2          A01X+049000Y+016370X0198Y0197R090 S1      
317m1768            VIA   -    MD0100PA00X+049268Y+016099X0200Y         S0      
317m1768            VIA   -    MD0100PA00X+047001Y+014107X0200Y         S0      
317m1768            VIA   -    MD0100PA00X+042409Y+013326X0200Y    R180 S0      
327m1768            C6092 -1          A18X+042973Y+012830X0198Y0197R180 S2      
327m1768            C6093 -1          A18X+042973Y+012421X0198Y0197R180 S2      
327m1768            C6095 -1          A18X+042973Y+013230X0198Y0197R180 S2      
327m1768            R6264 -2          A01X+047670Y+010057X0198Y0197     S1      
317m1768            VIA   -    MD0100PA00X+047940Y+009757X0200Y         S0      
317m1768            VIA   -    M      A01X+047940Y+009057X0200Y         S2      
017m1768            VIA   -    M      A18X+047940Y+009057X0260Y         S2      
017m1768                  -    MD0100PA00X+047940Y+009057                       
327m1768            R6274 -2          A01X+047670Y+009057X0198Y0197     S1      
327m1768            C6094 -1          A18X+044087Y+010769X0198Y0197R090 S2      
327m1768            C6098 -1          A18X+043687Y+010769X0198Y0197R090 S2      
327m1768            C6103 -1          A18X+043287Y+010769X0198Y0197R090 S2      
327m1768            C6097 -1          A18X+042887Y+010769X0198Y0197R090 S2      
327m1768            C6096 -1          A18X+042973Y+011143X0198Y0197R270 S2      
327m1768            C6104 -1          A18X+043323Y+011143X0198Y0197R270 S2      
317m1768            VIA   -    MD0100PA00X+042408Y+011084X0200Y    R180 S0      
327m1768            L6003 -2          A18X+041517Y+011319X0440Y0540R090 S2      
327m1768            C6100 -1          A18X+042487Y+010769X0198Y0197R090 S2      
327m1768            C6101 -1          A18X+042087Y+010769X0198Y0197R090 S2      
327m1768            C6102 -1          A18X+042205Y+011478X0198Y0197R270 S2      
327m1768            C6099 -1          A18X+042555Y+011478X0198Y0197R270 S2      
327m1768            R6270 -1          A01X+046660Y+014280X0198Y0197R090 S1      
327m1769            U6002 -13         A01X+045295Y+010668X0094Y0236     S1      
327m1769            U6002 -51         A01X+042677Y+013483X0094Y0236R090 S1      
327m1769            U6002 -57         A01X+042677Y+012302X0094Y0236R090 S1      
327m1769            L6004 -2          A18X+045553Y+013854X0440Y0540R270 S2      
327m1769            C6105 -1          A18X+044809Y+013874X0400Y0500R270 S2      
327m1769            C6110 -1          A18X+044279Y+013972X0198Y0197R090 S2      
327m1769            C6111 -1          A18X+043889Y+013972X0198Y0197R090 S2      
327m1769            C6109 -1          A18X+042719Y+013972X0198Y0197R090 S2      
327m1769            C6114 -1          A18X+043109Y+013972X0198Y0197R090 S2      
327m1769            C6115 -1          A18X+043499Y+013972X0198Y0197R090 S2      
327m1769            R6269 -2          A01X+047676Y+012364X0198Y0197     S1      
317m1769            VIA   -    MD0100PA00X+047946Y+012364X0200Y         S0      
317m1769            VIA   -    MD0100PA00X+042289Y+013670X0200Y    R180 S0      
317m1769            VIA   -    MD0100PA00X+043400Y+017070X0200Y         S0      
327m1769            R6259 -1          A01X+048200Y+016370X0198Y0197R270 S1      
317m1769            VIA   -    MD0100PA00X+042409Y+012302X0200Y    R180 S0      
327m1769            C6112 -1          A18X+042075Y+012494X0198Y0197R090 S2      
317m1769            VIA   -    MD0100PA00X+047946Y+011564X0200Y         S0      
327m1769            R6268 -2          A01X+047676Y+011964X0198Y0197     S1      
317m1769            VIA   -    MD0100PA00X+047946Y+011964X0200Y         S0      
327m1769            R6266 -2   M      A01X+047670Y+011057X0198Y0197     S1      
317m1769            VIA   -    MD0100PA00X+047940Y+011093X0200Y         S0      
327m1769            C6118 -1          A18X+045860Y+012001X0400Y0500R180 S2      
327m1769            C6117 -1          A18X+045946Y+010804X0198Y0197R180 S2      
327m1769            C6119 -1          A18X+045946Y+011204X0198Y0197R180 S2      
327m1769            C6108 -1          A18X+045289Y+011043X0198Y0197R270 S2      
327m1769            C6107 -1          A18X+044889Y+011043X0198Y0197R270 S2      
327m1769            C6121 -1          A18X+042973Y+012021X0198Y0197R180 S2      
317m1769            VIA   -    MD0100PA00X+047940Y+009457X0200Y         S0      
327m1769            R6263 -2          A01X+047670Y+009557X0198Y0197     S1      
327m1769            C6116 -1          A18X+045546Y+010404X0198Y0197R090 S2      
327m1769            C6120 -1          A18X+045946Y+010404X0198Y0197R090 S2      
317m1769            VIA   -    MD0100PA00X+045295Y+010400X0200Y    R270 S0      
327m1769            C6106 -1          A18X+044977Y+010249X0198Y0197     S2      
327m1769            C6113 -1          A18X+044977Y+010649X0198Y0197     S2      
327m1769            R6260 -2          A01X+043867Y+007712X0198Y0197R270 S1      
317m1769            VIA   -    MD0100PA00X+044118Y+007712X0200Y    R270 S0      
327m1769            R6262 -2   M      A01X+044267Y+008412X0198Y0197R270 S1      
327m1769            R6261 -2          A01X+043867Y+008412X0198Y0197R270 S1      
317m1769            VIA   -    M      A01X+044527Y+008212X0200Y    R270 S2      
017m1769            VIA   -    M      A18X+044527Y+008212X0260Y    R270 S2      
017m1769                  -    MD0100PA00X+044527Y+008212                       
327m1769            R6267 -2          A01X+047676Y+011564X0198Y0197     S1      
327m1769            R6265 -2          A01X+047670Y+010557X0198Y0197     S1      
327m1770            VIA   -           A01X+167640Y+169482X0300Y    R270 S1      
327m1770            U6005 -13         A01X+168356Y+168920X0090Y0240R090 S1      
327m1771            VIA   -           A01X+167640Y+169982X0300Y    R270 S1      
327m1771            U6005 -12         A01X+168612Y+169176X0090Y0240     S1      
327m1772            VIA   -           A01X+167793Y+167930X0300Y    R270 S1      
327m1772            U6005 -16         A01X+168356Y+168329X0090Y0240R090 S1      
327m1773            VIA   -           A01X+167640Y+168482X0300Y    R270 S1      
327m1773            U6005 -15         A01X+168356Y+168526X0090Y0240R090 S1      
327m1774            VIA   -           A01X+167640Y+168982X0300Y    R270 S1      
327m1774            U6005 -14         A01X+168356Y+168723X0090Y0240R090 S1      
327m1775            VIA   -           A01X+170062Y+169274X0300Y    R270 S1      
327m1775            U6005 -8          A01X+169458Y+168920X0090Y0240R090 S1      
327m1776            VIA   -           A01X+170062Y+168774X0300Y    R270 S1      
327m1776            U6005 -7          A01X+169458Y+168723X0090Y0240R090 S1      
327m1777            VIA   -    M      A01X+168982Y+167432X0300Y    R270 S1      
327m1777            R6247 -2          A01X+169242Y+166932X0198Y0197R090 S1      
327m1777            U6005 -3          A01X+169006Y+168073X0090Y0240     S1      
327m1778            VIA   -    M      A01X+167982Y+167432X0300Y    R270 S1      
327m1778            R6250 -2          A01X+167982Y+166938X0198Y0197R090 S1      
327m1778            U6005 -1          A01X+168612Y+168073X0090Y0240     S1      
327m1779            VIA   -    M      A01X+168482Y+167432X0300Y    R270 S1      
327m1779            U6005 -2          A01X+168809Y+168073X0090Y0240     S1      
327m1779            R6251 -2   M      A01X+168824Y+166938X0198Y0197R090 S1      
327m1779            R6254 -1          A01X+168401Y+166932X0198Y0197R270 S1      
327m1780            U6001 -54         A01X+051297Y+013001X0070Y0520R180 S1      
327m1780            Y9    -3          A01X+048695Y+011724X0360Y0400R180 S1      
317m1780            VIA   -    M      A01X+050067Y+011626X0200Y         S2      
017m1780            VIA   -    M      A18X+050067Y+011626X0260Y         S2      
017m1780                  -    MD0100PA00X+050067Y+011626                       
327m1780            C93   -1   M      A01X+049831Y+011534X0198Y0197R090 S1      
327m1781            U6001 -55         A01X+051454Y+013001X0070Y0520R180 S1      
317m1781            VIA   -    M      A01X+050275Y+011128X0200Y         S2      
017m1781            VIA   -    M      A18X+050275Y+011128X0260Y         S2      
017m1781                  -    MD0100PA00X+050275Y+011128                       
327m1781            Y9    -1          A01X+049305Y+010996X0360Y0400R180 S1      
327m1781            C91   -1   M      A01X+049838Y+011127X0198Y0197R270 S1      
327m1782            U6001 -17         A01X+053817Y+015777X0070Y0400R270 S1      
327m1782            R6209 -1          A01X+055126Y+015274X0198Y0197     S1      
327m1782            R6208 -2   M      A01X+055126Y+015667X0198Y0197R180 S1      
327m1782            VIA   -    M      A01X+054646Y+015667X0300Y         S1      
327m1783            U6001 -18         A01X+053502Y+016092X0070Y0400R180 S1      
327m1783            R4450 -1          A01X+055420Y+018468X0198Y0197R090 S1      
327m1783            VIA   -    M      A01X+055420Y+017988X0300Y         S1      
327m1784            U6001 -2          A01X+053758Y+013415X0070Y0520R270 S1      
327m1784            VIA   -    M      A01X+054460Y+013106X0300Y         S1      
327m1784            R6203 -2          A01X+054313Y+012640X0198Y0197R090 S1      
327m1785            U6001 -26         A01X+052242Y+016033X0070Y0520R180 S1      
327m1785            VIA   -    M      A01X+050646Y+019032X0300Y         S1      
327m1785            R6202 -2          A01X+050081Y+018952X0198Y0197     S1      
327m1786            U6001 -24         A01X+052557Y+016033X0070Y0520R180 S1      
327m1786            VIA   -    M      A01X+051079Y+019442X0300Y         S1      
327m1786            R6214 -1          A01X+050081Y+019752X0198Y0197R180 S1      
327m1786            R6213 -2   M      A01X+050081Y+019352X0198Y0197     S1      
327m1787            U6001 -23         A01X+052714Y+016033X0070Y0520R180 S1      
327m1787            VIA   -    M      A01X+053682Y+019526X0300Y    R270 S1      
327m1787            R6215 -2          A01X+054162Y+019926X0198Y0197R180 S1      
327m1787            R6216 -1   M      A01X+054162Y+019526X0198Y0197     S1      
327m1788            U6003 -3          A01X+043052Y+025377X0350Y0500R270 S1      
327m1788            R6220 -2          A01X+041829Y+025016X0198Y0197     S1      
327m1788            R6221 -1   M      A01X+041829Y+025416X0198Y0197R180 S1      
327m1788            VIA   -    M      A01X+042422Y+025377X0300Y         S1      
327m1789            U6003 -2          A01X+043052Y+025877X0350Y0500R270 S1      
327m1789            R6219 -1          A01X+041829Y+026216X0198Y0197R180 S1      
327m1789            R6218 -2   M      A01X+041829Y+025816X0198Y0197     S1      
327m1789            VIA   -    M      A01X+042422Y+025877X0300Y         S1      
327m1790            U6003 -1          A01X+043052Y+026377X0350Y0500R270 S1      
327m1790            VIA   -    M      A01X+042422Y+026377X0300Y         S1      
327m1790            R6217 -1          A01X+041829Y+027016X0198Y0197R180 S1      
327m1790            R6222 -2   M      A01X+041829Y+026616X0198Y0197     S1      
327m1791            C6013 -2          A01X+057336Y+011964X0180Y0200R090 S1      
317m1791            VIA   -    MD0100PA01X+055907Y+010198X0200Y         S0      
327m1791            U6002 -58         A01X+042677Y+012105X0094Y0236R090 S1      
317m1791            VIA   -    MD0100PA01X+040043Y+011622X0200Y         S0      
327m1791            R344  -1   M      A01X+040624Y+011635X0120Y0150R090 S1      
327m1792            C6014 -2          A01X+056836Y+011964X0180Y0200R090 S1      
317m1792            VIA   -    MD0100PA01X+055907Y+010538X0200Y         S0      
327m1792            U6002 -59         A01X+042677Y+011909X0094Y0236R090 S1      
317m1792            VIA   -    MD0100PA01X+040043Y+011282X0200Y         S0      
327m1792            R346  -1   M      A01X+040624Y+011295X0120Y0150R270 S1      
327m1793            C6003 -2          A01X+057336Y+012594X0180Y0200R270 S1      
327m1793            U6001 -9          A01X+053758Y+014517X0070Y0520R270 S1      
327m1794            C6004 -2          A01X+056836Y+012594X0180Y0200R270 S1      
327m1794            U6001 -8          A01X+053758Y+014360X0070Y0520R270 S1      
317m1795            VIA   -    MD0080PA01X+145691Y+088600X0160Y    R180 S0      
327m1795            C6017 -2          A01X+055628Y+012294X0180Y0200R270 S1      
327m1795            U25   -E27        A01X+145507Y+088705X0177Y    R180 S1      
317m1795            VIA   -    MD0100PA01X+055378Y+012124X0200Y         S0      
327m1795            C6015 -2   M      A01X+055628Y+012294X0180Y0200R090 S1      
317m1796            VIA   -    MD0080PA01X+146061Y+088600X0160Y    R180 S0      
327m1796            C6018 -2          A01X+055128Y+012294X0180Y0200R270 S1      
327m1796            U25   -E26        A01X+145877Y+088705X0177Y    R180 S1      
317m1796            VIA   -    MD0100PA01X+055378Y+012464X0200Y         S0      
327m1796            C6016 -2   M      A01X+055128Y+012294X0180Y0200R090 S1      
327m1797            C6017 -1          A01X+055628Y+011979X0180Y0200R270 S1      
317m1797            VIA   -    MD0100PA01X+055550Y+011220X0200Y         S0      
327m1797            U6002 -55         A01X+042677Y+012696X0094Y0236R090 S1      
317m1797            VIA   -    MD0100PA01X+041749Y+012758X0200Y         S0      
327m1798            C6018 -1          A01X+055128Y+011979X0180Y0200R270 S1      
317m1798            VIA   -    MD0100PA01X+055210Y+011220X0200Y         S0      
327m1798            U6002 -56         A01X+042677Y+012499X0094Y0236R090 S1      
317m1798            VIA   -    MD0100PA01X+041749Y+012418X0200Y         S0      
327m1799            U6001 -6          A01X+053758Y+014045X0070Y0520R270 S1      
327m1799            C6015 -1          A01X+055628Y+012609X0180Y0200R090 S1      
327m1800            U6001 -5          A01X+053758Y+013887X0070Y0520R270 S1      
327m1800            C6016 -1          A01X+055128Y+012609X0180Y0200R090 S1      
327m1801            U6002 -14         A01X+045492Y+010668X0094Y0236     S1      
317m1801            VIA   -    MD0100PA01X+048226Y+012982X0200Y         S0      
317m1801            VIA   -    MD0100PA01X+045906Y+009510X0200Y         S0      
327m1801            C6021 -2          A01X+048893Y+012894X0180Y0200     S1      
327m1802            U6002 -15         A01X+045688Y+010668X0094Y0236     S1      
317m1802            VIA   -    MD0100PA01X+048226Y+013322X0200Y         S0      
317m1802            VIA   -    MD0100PA01X+046246Y+009510X0200Y         S0      
327m1802            C6022 -2          A01X+048893Y+013394X0180Y0200     S1      
327m1803            U6001 -51         A01X+050667Y+013257X0070Y0400R270 S1      
327m1803            C6019 -2          A01X+049523Y+012894X0180Y0200R180 S1      
327m1804            U6001 -50         A01X+050726Y+013415X0070Y0520R270 S1      
327m1804            C6020 -2          A01X+049523Y+013394X0180Y0200R180 S1      
327m1805            C6025 -1          A01X+048093Y+014439X0180Y0200R180 S1      
327m1805            U6002 -11         A01X+044901Y+010668X0094Y0236     S1      
317m1805            VIA   -    MD0100PA01X+045210Y+008871X0200Y    R090 S0      
317m1805            VIA   -    MD0100PA01X+047290Y+013002X0200Y         S0      
327m1806            C6026 -1          A01X+048093Y+013949X0180Y0200R180 S1      
327m1806            U6002 -12         A01X+045098Y+010668X0094Y0236     S1      
317m1806            VIA   -    MD0100PA01X+047630Y+013002X0200Y         S0      
317m1806            VIA   -    MD0100PA01X+045550Y+008871X0200Y    R090 S0      
327m1807            C6023 -1          A01X+048723Y+014439X0180Y0200     S1      
327m1807            U6001 -47         A01X+050726Y+013887X0070Y0520R270 S1      
327m1808            C6024 -1          A01X+048723Y+013949X0180Y0200     S1      
327m1808            U6001 -48         A01X+050726Y+013730X0070Y0520R270 S1      
327m1809            J41   -B56        A01X+054389Y+006516X0150Y0570R180 S1      
317m1809            VIA   -    MD0100PA00X+053517Y+011513X0200Y         S2      
327m1809            R6196 -2   M      A01X+053742Y+011318X0120Y0150R270 S1      
327m1809            R6194 -2          A01X+053742Y+011318X0120Y0150R090 S1      
317m1809            VIA   -    MD0100PA00X+054440Y+007144X0200Y    R180 S0      
327m1810            J41   -B57        A01X+054152Y+006516X0150Y0570R180 S1      
317m1810            VIA   -    MD0100PA00X+053517Y+011123X0200Y         S2      
317m1810            VIA   -    MD0100PA00X+054100Y+007144X0200Y    R180 S0      
327m1810            R6197 -2   M      A01X+053292Y+011318X0120Y0150R270 S1      
327m1810            R6195 -2          A01X+053292Y+011318X0120Y0150R090 S1      
327m1811            U6002 -53         A01X+042677Y+013090X0094Y0236R090 S1      
317m1811            VIA   -    MD0100PA01X+040561Y+012972X0200Y         S0      
317m1811            VIA   -    MD0100PA01X+051424Y+009715X0200Y         S0      
327m1811            R343  -1   M      A01X+040944Y+012960X0120Y0150R090 S1      
327m1811            R6192 -2          A01X+051377Y+010522X0120Y0150R090 S1      
327m1812            U6002 -54         A01X+042677Y+012893X0094Y0236R090 S1      
317m1812            VIA   -    MD0100PA01X+040561Y+012582X0200Y         S0      
317m1812            VIA   -    MD0100PA01X+051764Y+009715X0200Y         S0      
327m1812            R345  -1   M      A01X+040944Y+012620X0120Y0150R270 S1      
327m1812            R6193 -2          A01X+051827Y+010522X0120Y0150R090 S1      
327m1813            U6001 -57         A01X+051769Y+013001X0070Y0520R180 S1      
327m1813            VIA   -    M      A01X+051538Y+011530X0160Y0041R090 S1      
327m1813            R6190 -2          A01X+051377Y+010942X0120Y0150R270 S1      
327m1814            U6001 -58         A01X+051927Y+013001X0070Y0520R180 S1      
327m1814            VIA   -    M      A01X+051912Y+012420X0160Y0041R270 S1      
327m1814            R6191 -2          A01X+051827Y+010942X0120Y0150R270 S1      
327m1815            U6002 -9          A01X+044507Y+010668X0094Y0236     S1      
317m1815            VIA   -    MD0100PA01X+052646Y+009750X0200Y         S0      
317m1815            VIA   -    MD0100PA01X+044501Y+009468X0200Y    R090 S0      
327m1815            R6196 -1          A01X+053742Y+011108X0120Y0150R090 S1      
327m1816            U6002 -10         A01X+044704Y+010668X0094Y0236     S1      
317m1816            VIA   -    MD0100PA01X+052646Y+010090X0200Y         S0      
317m1816            VIA   -    MD0100PA01X+044841Y+009468X0200Y    R090 S0      
327m1816            R6197 -1          A01X+053292Y+011108X0120Y0150R090 S1      
327m1817            U6001 -60         A01X+052242Y+013001X0070Y0520R180 S1      
327m1817            VIA   -    M      A01X+053352Y+012220X0160Y0041     S1      
327m1817            R6194 -1          A01X+053742Y+011528X0120Y0150R270 S1      
327m1818            U6001 -59         A01X+052084Y+013001X0070Y0520R180 S1      
327m1818            VIA   -    M      A01X+052728Y+012093X0160Y0041     S1      
327m1818            R6195 -1          A01X+053292Y+011528X0120Y0150R270 S1      
327m1819            U6001 -20         A01X+053187Y+016033X0070Y0520R180 S1      
327m1819            VIA   -           A01X+053385Y+016902X0300Y         S1      
327m1820            VIA   -           A01X+170062Y+168274X0300Y    R270 S1      
327m1820            U6005 -6          A01X+169458Y+168526X0090Y0240R090 S1      
327SW_P1V8_AUX_PH   VIA   -           A01X+057580Y+031633X0300Y         S1      
327SW_P1V8_AUX_PH   PC641 -2          A01X+057554Y+031078X0198Y0197R090 S1      
327SW_P1V8_AUX_PH   PL6000-1          A01X+058369Y+030611X0848Y1300     S1      
327SW_P1V8_AUX_PH   PU6000-11         A01X+056816Y+031019X0100Y0360R090 S1      
327SW_P1V8_AUX_PH   PU6000-2          A01X+056146Y+031019X0100Y0360R090 S1      
327SW_P1V8_AUX_BT   PR8003-1          A01X+057557Y+030109X0198Y0197R090 S1      
327SW_P1V8_AUX_BT   PU6000-10         A01X+056816Y+030822X0100Y0360R090 S1      
327SW_P1V2_AUX_PH   VIA   -           A01X+048880Y+030738X0300Y         S1      
327SW_P1V2_AUX_PH   PC6017-2          A01X+048854Y+030178X0198Y0197R090 S1      
327SW_P1V2_AUX_PH   PL6001-1          A01X+049669Y+029711X0848Y1300     S1      
327SW_P1V2_AUX_PH   PU6001-11         A01X+048116Y+030119X0100Y0360R090 S1      
327SW_P1V2_AUX_PH   PU6001-2          A01X+047446Y+030119X0100Y0360R090 S1      
327SW_P1V2_AUX_BT   PR8004-1          A01X+048854Y+029195X0198Y0197R090 S1      
327SW_P1V2_AUX_BT   PU6001-10         A01X+048116Y+029922X0100Y0360R090 S1      
327m1821            PC6010-1          A01X+055604Y+030956X0198Y0197R090 S1      
327m1821            PU6000-3          A01X+056225Y+030822X0100Y0520R090 S1      
327m1821            PC6014-1          A01X+055075Y+030860X0400Y0500R270 S1      
327m1821            PL6002-2          A01X+054321Y+030307X0280Y0320     S1      
327m1821            PC6012-1          A01X+054387Y+030866X0400Y0500R270 S1      
327m1821            VIA   -           A01X+054894Y+030278X0300Y    R270 S1      
327m1822            PC6011-1          A01X+046904Y+030056X0198Y0197R090 S1      
327m1822            PU6001-3          A01X+047525Y+029922X0100Y0520R090 S1      
327m1822            PC6013-1          A01X+046375Y+029960X0400Y0500R270 S1      
327m1822            PC6015-1          A01X+045687Y+029966X0400Y0500R270 S1      
327m1822            PL6003-2          A01X+045597Y+029406X0280Y0320     S1      
327m1822            VIA   -           A01X+046154Y+029386X0300Y    R270 S1      
327m1823            U6003 -5          A01X+045099Y+024877X0350Y0500R270 S1      
327m1823            R6227 -2          A18X+045171Y+024474X0198Y0197R270 S2      
327m1823            R6225 -2   M      A18X+044771Y+024474X0198Y0197R270 S2      
317m1823            VIA   -    M      A01X+044671Y+024934X0200Y    R180 S2      
017m1823            VIA   -    M      A18X+044671Y+024934X0260Y    R180 S2      
017m1823                  -    MD0100PA00X+044671Y+024934                       
327m1824            R6200 -1          A01X+110202Y+047536X0198Y0197R180 S1      
327m1824            VIA   -    M      A01X+111100Y+047836X0300Y         S1      
327m1824            U36   -4          A01X+111861Y+047572X0120Y0630R270 S1      
327m1825            U6001 -33         A01X+051139Y+016033X0070Y0520R180 S1      
327m1825            R6311 -1          A01X+042330Y+020970X0198Y0197R270 S1      
317m1825            VIA   -    M      A01X+044271Y+023799X0200Y         S2      
017m1825            VIA   -    M      A18X+044271Y+023799X0260Y         S2      
017m1825                  -    MD0100PA00X+044271Y+023799                       
327m1825            R6225 -1          A18X+044771Y+024159X0198Y0197R270 S2      
317m1825            VIA   -    MD0100PA00X+042330Y+021210X0200Y         S0      
317m1825            VIA   -    MD0100PA00X+045000Y+017070X0200Y         S0      
327m1825            R6279 -1          A01X+047400Y+016370X0198Y0197R270 S1      
317m1825            VIA   -    MD0100PA00X+048020Y+019190X0200Y         S0      
317m1825            VIA   -    MD0100PA00X+109000Y+047750X0200Y         S0      
327m1825            R6200 -2          A01X+109887Y+047536X0198Y0197R180 S1      
327m1825            R6212 -2   M      A01X+109295Y+047628X0198Y0197R270 S1      
317m1825            VIA   -    MD0100PA00X+044132Y+031317X0200Y         S0      
327m1826            U6003 -6          A01X+045099Y+025377X0350Y0500R270 S1      
327m1826            R6224 -2          A18X+043771Y+024574X0198Y0197R270 S2      
327m1826            R6226 -2   M      A18X+044171Y+024574X0198Y0197R270 S2      
317m1826            VIA   -    M      A01X+044071Y+025034X0200Y    R180 S2      
017m1826            VIA   -    M      A18X+044071Y+025034X0260Y    R180 S2      
017m1826                  -    MD0100PA00X+044071Y+025034                       
327m1827            R6201 -1          A01X+109351Y+047210X0198Y0197R180 S1      
327m1827            VIA   -    M      A01X+110700Y+047536X0300Y         S1      
327m1827            U36   -5          A01X+111861Y+047316X0120Y0630R270 S1      
327m1828            U6001 -32         A01X+051297Y+016033X0070Y0520R180 S1      
317m1828            VIA   -    M      A01X+043744Y+023727X0200Y         S2      
017m1828            VIA   -    M      A18X+043744Y+023727X0260Y         S2      
017m1828                  -    MD0100PA00X+043744Y+023727                       
327m1828            R6224 -1          A18X+043771Y+024259X0198Y0197R270 S2      
317m1828            VIA   -    MD0100PA00X+041930Y+021210X0200Y         S0      
317m1828            VIA   -    MD0100PA00X+044200Y+017070X0200Y         S0      
327m1828            R6280 -1          A01X+047000Y+016370X0198Y0197R270 S1      
317m1828            VIA   -    MD0100PA00X+048380Y+018940X0200Y         S0      
327m1828            R6211 -2   M      A01X+108651Y+047210X0198Y0197     S1      
327m1828            R6201 -2          A01X+109036Y+047210X0198Y0197R180 S1      
317m1828            VIA   -    MD0100PA00X+108400Y+047750X0200Y         S0      
317m1828            VIA   -    MD0100PA00X+044132Y+030717X0200Y         S0      
327m1828            R6314 -1          A01X+041930Y+020970X0198Y0197R270 S1      
327m1829            R6228 -1          A01X+107464Y+045796X0198Y0197     S1      
327m1829            VIA   -    M      A01X+106032Y+046025X0300Y         S1      
327m1829            U39   -15         A01X+105108Y+046036X0120Y0630R270 S1      
327m1830            R6229 -1          A01X+106572Y+046252X0198Y0197     S1      
327m1830            VIA   -    M      A01X+105822Y+046494X0300Y         S1      
327m1830            U39   -16         A01X+105108Y+046292X0120Y0630R270 S1      
327m1831            U6001 -31         A01X+051454Y+016033X0070Y0520R180 S1      
327m1831            VIA   -    M      A01X+050220Y+017908X0300Y         S1      
327m1831            R4451 -2   M      A01X+049226Y+018952X0198Y0197     S1      
327m1831            R4453 -1   M      A01X+049226Y+019752X0198Y0197R180 S1      
327m1831            R4452 -2   M      A01X+049226Y+019352X0198Y0197     S1      
327m1831            C2317 -1          A01X+049226Y+020152X0198Y0197R180 S1      
317m1832            VIA   -    M      A01X+121409Y+028795X0300Y         S1      
017m1832            VIA   -    M      A18X+121409Y+028795X0200Y         S1      
017m1832                  -    MD0100PA00X+121409Y+028795                       
327m1832            Q6000 -2          A18X+121666Y+028951X0170Y0200R270 S2      
317m1832            VIA   -    MD0100PA00X+121932Y+043815X0200Y         S0      
317m1832            VIA   -    MD0100PA00X+078088Y+043137X0200Y         S0      
327m1832            U18   -Y9         A01X+075717Y+044509X0160Y    R090 S1      
317m1832            VIA   -    MD0100PA00X+075871Y+044356X0180Y         S0      
327m1832            R6241 -2          A18X+049157Y+028589X0198Y0197R180 S2      
317m1832            VIA   -    MD0100PA00X+072415Y+034529X0200Y         S0      
327PWRGD_P1V2_AUX   VIA   -    M      A18X+048923Y+029042X0260Y         S2      
327PWRGD_P1V2_AUX   R6244 -2          A01X+048711Y+028830X0198Y0197R090 S1      
327PWRGD_P1V2_AUX   R6241 -1          A18X+048842Y+028589X0198Y0197R180 S2      
327PWRGD_P1V2_AUX   PU6001-9          A01X+048116Y+029725X0100Y0360R090 S1      
317PWRGD_P1V2_AUX   VIA   -    MD0100PA00X+048596Y+029068X0200Y    R270 S0      
327m1833            U6001 -22         A01X+052872Y+016033X0070Y0520R180 S1      
327m1833            VIA   -    M      A01X+053682Y+019026X0300Y    R270 S1      
327m1833            R6206 -2          A01X+054162Y+019026X0198Y0197R180 S1      
327m1834            U6001 -21         A01X+053029Y+016033X0070Y0520R180 S1      
327m1834            R6207 -2          A01X+055020Y+018468X0198Y0197R270 S1      
327m1834            VIA   -    M      A01X+054540Y+018468X0300Y    R270 S1      
327m1835            U6001 -29         A01X+051769Y+016033X0070Y0520R180 S1      
327m1835            VIA   -    M      A01X+051220Y+017908X0300Y         S1      
327m1835            R6204 -2          A01X+050908Y+018552X0198Y0197     S1      
327m1836            U6001 -30         A01X+051612Y+016033X0070Y0520R180 S1      
327m1836            VIA   -    M      A01X+050720Y+017908X0300Y         S1      
327m1836            R6205 -2          A01X+050081Y+018552X0198Y0197     S1      
327PD_USB_CPU0_WP   U6003 -7          A01X+045099Y+025877X0350Y0500R270 S1      
327PD_USB_CPU0_WP   R6223 -1          A18X+043371Y+024574X0198Y0197R090 S2      
317PD_USB_CPU0_WP   VIA   -    M      A01X+043571Y+025034X0200Y    R180 S2      
017PD_USB_CPU0_WP   VIA   -    M      A18X+043571Y+025034X0260Y    R180 S2      
017PD_USB_CPU0_WP         -    MD0100PA00X+043571Y+025034                       
327m1837            U6001 -4          A01X+053758Y+013730X0070Y0520R270 S1      
327m1837            VIA   -           A18X+055850Y+013888X0260Y    R180 S2      
327m1837            C6045 -1          A18X+054868Y+013742X0198Y0197R270 S2      
327m1837            C6042 -1          A18X+055338Y+013809X0280Y0320     S2      
317m1837            VIA   -    MD0100PA00X+054168Y+013717X0200Y    R090 S0      
327m1837            C6044 -1          A18X+054468Y+013742X0198Y0197R270 S2      
327m1837            L6000 -2          A18X+055348Y+013179X0440Y0540R180 S2      
327m1837            C6043 -1          A18X+054838Y+013357X0198Y0197R090 S2      
327P1V8_AUX_VCC     VIA   -    M      A18X+056440Y+031726X0260Y         S2      
327P1V8_AUX_VCC     PC6008-1          A01X+056638Y+031881X0198Y0197R180 S1      
327P1V8_AUX_VCC     R6242 -2          A18X+056300Y+032199X0198Y0197     S2      
327P1V8_AUX_VCC     PU6000-13         A01X+056579Y+031393X0098Y0276R180 S1      
317P1V8_AUX_VCC     VIA   -    MD0100PA00X+056777Y+031615X0200Y    R270 S0      
327P1V8_AUX_REF     PC384 -1          A01X+057038Y+029747X0198Y0197R180 S1      
327P1V8_AUX_REF     PU6000-8          A01X+056855Y+030428X0098Y0276R090 S1      
317P1V8_AUX_REF     VIA   -    MD0100PA00X+056989Y+030029X0200Y    R270 S2      
327P1V8_AUX_MODE    PR6006-2          A01X+057106Y+031740X0198Y0197R270 S1      
327P1V8_AUX_MODE    PU6000-12         A01X+056855Y+031216X0098Y0276R090 S1      
317P1V8_AUX_MODE    VIA   -    MD0100PA00X+057106Y+031467X0200Y    R270 S2      
327P1V8_AUX_FB      PC6019-1   M      A01X+056035Y+029374X0198Y0197     S1      
327P1V8_AUX_FB      PR6010-1   M      A01X+056035Y+029757X0198Y0197R360 S1      
327P1V8_AUX_FB      PR6007-1          A01X+056035Y+028986X0198Y0197     S1      
317P1V8_AUX_FB      VIA   -    MD0100PA00X+056181Y+030049X0200Y    R270 S2      
327P1V8_AUX_FB      PU6000-6          A01X+056383Y+030251X0098Y0276     S1      
317m1838            VIA   -    M      A01X+086299Y+050730X0300Y         S1      
017m1838            VIA   -    M      A18X+086299Y+050730X0200Y         S1      
017m1838                  -    MD0100PA00X+086299Y+050730                       
327m1838            R6119 -2          A01X+085269Y+052441X0198Y0197R180 S1      
327m1838            C345  -1   M      A01X+084876Y+052441X0198Y0197R090 S1      
327m1838            PU6000-5          A01X+056107Y+030428X0098Y0276R270 S1      
317m1838            VIA   -    MD0100PA00X+055724Y+029469X0200Y    R270 S0      
327P1V8_AUX_CS      VIA   -    M      A01X+055576Y+030248X0300Y         S1      
327P1V8_AUX_CS      PR6003-1          A01X+055270Y+029764X0198Y0197R270 S1      
327P1V8_AUX_CS      PU6000-4          A01X+056146Y+030625X0100Y0360R090 S1      
327m1839            U6001 -1          A01X+053817Y+013257X0070Y0400R270 S1      
327m1839            U6001 -3          A01X+053758Y+013572X0070Y0520R270 S1      
327m1839            U6001 -19         A01X+053344Y+016033X0070Y0520R180 S1      
327m1839            U6001 -27         A01X+052084Y+016033X0070Y0520R180 S1      
327m1839            VIA   -           A18X+052440Y+016768X0260Y    R180 S2      
317m1839            VIA   -    MD0100PA00X+053817Y+013070X0200Y    R270 S0      
317m1839            VIA   -    MD0100PA00X+054341Y+013391X0200Y    R090 S0      
327m1839            C6036 -1          A18X+053717Y+014521X0198Y0197     S2      
327m1839            C6037 -1          A18X+053717Y+014121X0198Y0197     S2      
327m1839            C6039 -1          A18X+053717Y+013721X0198Y0197     S2      
327m1839            C6038 -1          A18X+053717Y+013321X0198Y0197     S2      
327m1839            L6001 -2          A18X+053757Y+017076X0440Y0540R180 S2      
327m1839            C6030 -1          A18X+053724Y+016443X0280Y0320R180 S2      
327m1839            C6031 -1          A18X+053244Y+016694X0198Y0197     S2      
317m1839            VIA   -    MD0100PA00X+053344Y+016443X0200Y    R180 S0      
327m1839            C6035 -1          A18X+053244Y+015792X0198Y0197     S2      
327m1839            C6034 -1          A18X+053244Y+016192X0198Y0197     S2      
317m1839            VIA   -    MD0100PA00X+052162Y+016543X0200Y    R180 S0      
327m1839            C6032 -1          A18X+052562Y+016302X0198Y0197R090 S2      
327m1839            C6033 -1          A18X+052162Y+016302X0198Y0197R090 S2      
327P1V2_AUX_VCC     R6245 -2          A18X+047664Y+031235X0198Y0197R090 S2      
327P1V2_AUX_VCC     VIA   -    M      A18X+048124Y+031235X0260Y         S2      
317P1V2_AUX_VCC     VIA   -    MD0100PA00X+048077Y+030715X0200Y    R270 S0      
327P1V2_AUX_VCC     PC6009-1          A01X+047938Y+030981X0198Y0197R180 S1      
327P1V2_AUX_VCC     PU6001-13         A01X+047879Y+030493X0098Y0276R180 S1      
327P1V2_AUX_REF     PC6016-1          A01X+048338Y+028847X0198Y0197R180 S1      
327P1V2_AUX_REF     PU6001-8          A01X+048155Y+029528X0098Y0276R090 S1      
317P1V2_AUX_REF     VIA   -    MD0100PA00X+048289Y+029129X0200Y    R270 S2      
327P1V2_AUX_MODE    PR6005-2          A01X+048406Y+030840X0198Y0197R270 S1      
317P1V2_AUX_MODE    VIA   -    M      A01X+048406Y+030567X0200Y    R270 S2      
017P1V2_AUX_MODE    VIA   -    M      A18X+048406Y+030567X0260Y    R270 S2      
017P1V2_AUX_MODE          -    MD0100PA00X+048406Y+030567                       
327P1V2_AUX_MODE    PU6001-12         A01X+048155Y+030316X0098Y0276R090 S1      
327P1V2_AUX_FB      PC852 -1   M      A01X+047335Y+028474X0198Y0197     S1      
327P1V2_AUX_FB      PR6011-1   M      A01X+047335Y+028857X0198Y0197R360 S1      
327P1V2_AUX_FB      PR6008-1          A01X+047335Y+028086X0198Y0197     S1      
327P1V2_AUX_FB      PU6001-6          A01X+047683Y+029351X0098Y0276     S1      
317P1V2_AUX_FB      VIA   -    MD0100PA00X+047481Y+029149X0200Y    R270 S2      
317m1840            VIA   -    M      A01X+047024Y+028569X0200Y    R270 S2      
017m1840            VIA   -    M      A18X+047024Y+028569X0260Y    R270 S2      
017m1840                  -    MD0100PA00X+047024Y+028569                       
327m1840            R6240 -2          A18X+047484Y+028569X0198Y0197     S2      
327m1840            PU6001-5          A01X+047407Y+029528X0098Y0276R270 S1      
327P1V2_AUX_CS      VIA   -    M      A01X+046854Y+029327X0300Y         S1      
327P1V2_AUX_CS      PR6004-1          A01X+046570Y+028864X0198Y0197R270 S1      
327P1V2_AUX_CS      PU6001-4          A01X+047446Y+029725X0100Y0360R090 S1      
327P1V2_AUX         U6001 -34         A01X+050982Y+016092X0070Y0400R180 S1      
327P1V2_AUX         U6001 -52         A01X+050982Y+012942X0070Y0400R180 S1      
327P1V2_AUX         U6001 -53         A01X+051139Y+013001X0070Y0520R180 S1      
327P1V2_AUX         U6001 -49         A01X+050726Y+013572X0070Y0520R270 S1      
327P1V2_AUX         U6001 -46         A01X+050726Y+014045X0070Y0520R270 S1      
327P1V2_AUX         U6001 -43         A01X+050726Y+014517X0070Y0520R270 S1      
327P1V2_AUX         U6001 -37         A01X+050726Y+015462X0070Y0520R270 S1      
327P1V2_AUX         U6001 -13         A01X+053758Y+015147X0070Y0520R270 S1      
327P1V2_AUX         U6001 -10         A01X+053758Y+014675X0070Y0520R270 S1      
327P1V2_AUX         U6001 -7          A01X+053758Y+014202X0070Y0520R270 S1      
327P1V2_AUX         U6001 -16         A01X+053758Y+015620X0070Y0520R270 S1      
327P1V2_AUX         VIA   -           A18X+052480Y+030904X0260Y    R090 S2      
327P1V2_AUX         VIA   -           A18X+052480Y+029904X0260Y    R090 S2      
327P1V2_AUX         VIA   -           A18X+047200Y+014709X0260Y    R180 S2      
327P1V2_AUX         VIA   -           A18X+046200Y+014709X0260Y    R180 S2      
327P1V2_AUX         VIA   -           A18X+048200Y+014709X0260Y    R180 S2      
317P1V2_AUX         VIA   -    MD0100PA00X+052177Y+028072X0200Y    R270 S0      
317P1V2_AUX         VIA   -    MD0100PA00X+052280Y+028904X0200Y    R270 S0      
317P1V2_AUX         VIA   -    MD0100PA00X+050935Y+012584X0200Y         S0      
327P1V2_AUX         C6064 -1          A18X+051185Y+012450X0198Y0197R180 S2      
327P1V2_AUX         C6066 -1          A18X+050416Y+012307X0280Y0320R090 S2      
327P1V2_AUX         C6080 -1          A18X+051065Y+013250X0198Y0197     S2      
327P1V2_AUX         C6081 -1          A18X+051065Y+013650X0198Y0197     S2      
327P1V2_AUX         C6082 -1          A18X+051065Y+012850X0198Y0197     S2      
327P1V2_AUX         C6065 -1          A18X+051458Y+012842X0198Y0197R270 S2      
327P1V2_AUX         C6076 -1          A18X+050358Y+012782X0198Y0197R270 S2      
327P1V2_AUX         C6075 -1          A18X+049958Y+012782X0198Y0197R270 S2      
317P1V2_AUX         VIA   -    MD0100PA00X+049770Y+015720X0200Y    R270 S0      
317P1V2_AUX         VIA   -    MD0100PA00X+050060Y+015710X0200Y    R270 S0      
327P1V2_AUX         L6001 -1          A18X+054505Y+017076X0440Y0540R180 S2      
317P1V2_AUX         VIA   -    MD0100PA00X+054168Y+015620X0200Y    R090 S0      
317P1V2_AUX         VIA   -    MD0100PA00X+054168Y+014202X0200Y    R090 S0      
317P1V2_AUX         VIA   -    MD0100PA00X+054168Y+015147X0200Y    R090 S0      
317P1V2_AUX         VIA   -    MD0100PA00X+054168Y+014687X0200Y    R090 S0      
327P1V2_AUX         C6068 -1          A18X+053717Y+015321X0198Y0197     S2      
327P1V2_AUX         C6067 -1          A18X+053717Y+014921X0198Y0197     S2      
327P1V2_AUX         C6058 -1          A18X+054430Y+015249X0198Y0197R180 S2      
327P1V2_AUX         C6059 -1          A18X+054430Y+015649X0198Y0197R180 S2      
327P1V2_AUX         C6069 -1          A18X+054430Y+016449X0198Y0197R180 S2      
327P1V2_AUX         C6070 -1          A18X+054430Y+016049X0198Y0197R180 S2      
327P1V2_AUX         C6056 -1          A18X+054430Y+014849X0198Y0197R180 S2      
327P1V2_AUX         C6057 -1          A18X+054430Y+014449X0198Y0197R180 S2      
327P1V2_AUX         PC6022-1   M      A01X+051430Y+028072X0198Y0197R180 S1      
327P1V2_AUX         PC852 -2          A01X+047650Y+028474X0198Y0197     S1      
327P1V2_AUX         PR6008-2   M      A01X+047650Y+028086X0198Y0197     S1      
317P1V2_AUX         VIA   -    MD0100PA00X+051775Y+030514X0200Y    R270 S0      
317P1V2_AUX         VIA   -    MD0100PA00X+052027Y+030514X0200Y    R270 S0      
317P1V2_AUX         VIA   -    MD0100PA00X+051775Y+031320X0200Y    R270 S0      
317P1V2_AUX         VIA   -    MD0100PA00X+052027Y+031320X0200Y    R270 S0      
317P1V2_AUX         VIA   -    MD0100PA00X+051522Y+030514X0200Y    R270 S0      
317P1V2_AUX         VIA   -    MD0100PA00X+051522Y+031320X0200Y    R270 S0      
317P1V2_AUX         VIA   -    MD0100PA00X+051775Y+028904X0200Y    R270 S0      
317P1V2_AUX         VIA   -    MD0100PA00X+052027Y+028904X0200Y    R270 S0      
317P1V2_AUX         VIA   -    MD0100PA00X+051522Y+028904X0200Y    R270 S0      
317P1V2_AUX         VIA   -    MD0100PA00X+051672Y+028072X0200Y    R270 S0      
317P1V2_AUX         VIA   -    MD0100PA00X+051925Y+028072X0200Y    R270 S0      
327P1V2_AUX         PL6001-2          A01X+051972Y+029711X0848Y1300     S1      
327P1V2_AUX         PC6025-1          A18X+051572Y+030917X0400Y0500R180 S2      
327P1V2_AUX         PC6018-1          A18X+051572Y+029306X0400Y0500R180 S2      
327P1V2_AUX         PC6024-1          A18X+051572Y+030112X0400Y0500R180 S2      
327P1V2_AUX         PC6026-1          A18X+051572Y+028501X0400Y0500R180 S2      
327P1V2_AUX         L6004 -1          A18X+045553Y+014602X0440Y0540R270 S2      
317P1V2_AUX         VIA   -    MD0100PA00X+050316Y+015462X0200Y    R270 S0      
327P1V2_AUX         C6072 -1          A18X+050556Y+015390X0198Y0197R180 S2      
327P1V2_AUX         C6061 -1          A18X+049565Y+015462X0198Y0197R090 S2      
327P1V2_AUX         C6060 -1          A18X+049965Y+015462X0198Y0197R090 S2      
317P1V2_AUX         VIA   -    MD0100PA00X+050794Y+016092X0200Y    R180 S0      
327P1V2_AUX         C6078 -1          A18X+050862Y+016357X0198Y0197R270 S2      
327P1V2_AUX         C6077 -1          A18X+050462Y+016357X0198Y0197R270 S2      
327P1V2_AUX         C6071 -1          A18X+050556Y+015790X0198Y0197R180 S2      
327P1V2_AUX         C6079 -1          A18X+049959Y+016152X0280Y0320     S2      
317P1V2_AUX         VIA   -    MD0100PA00X+050300Y+013560X0200Y    R270 S0      
327P1V2_AUX         C6063 -1          A18X+050867Y+014447X0198Y0197R270 S2      
327P1V2_AUX         C6062 -1          A18X+050467Y+014447X0198Y0197R270 S2      
327P1V2_AUX         C6054 -1          A18X+050435Y+014050X0198Y0197R180 S2      
317P1V2_AUX         VIA   -    MD0100PA00X+050014Y+014106X0200Y    R270 S0      
327P1V2_AUX         C6074 -1          A18X+049912Y+014754X0198Y0197     S2      
327P1V2_AUX         C6073 -1          A18X+049912Y+014354X0198Y0197     S2      
327P1V2_AUX         C6055 -1          A18X+049912Y+013860X0198Y0197     S2      
317P1V2_AUX         VIA   -    MD0100PA00X+078914Y+061710X0200Y         S0      
317P1V2_AUX         VIA   -    MD0100PA00X+086655Y+074803X0200Y         S0      
317P1V2_AUX         VIA   -    MD0100PA00X+097923Y+129792X0200Y         S0      
327P1V2_AUX         R1232 -1          A18X+093828Y+127396X0198Y0197     S2      
317P1V2_AUX         VIA   -    MD0100PA00X+094714Y+128740X0200Y    R180 S0      
317P1V2_AUX         VIA   -    MD0100PA00X+097356Y+085977X0200Y         S0      
317P1V2_AUX         VIA   -    MD0100PA00X+054062Y+046349X0200Y         S0      
317P1V2_AUX         VIA   -    MD0100PA00X+053321Y+035084X0200Y         S0      
327m1841            Q6000 -6          A18X+120918Y+029207X0170Y0200R270 S2      
327m1841            D6000 -C          A01X+121409Y+027785X0240Y0280R090 S1      
317m1841            VIA   -    M      A01X+121409Y+028295X0300Y         S1      
017m1841            VIA   -    M      A18X+121409Y+028295X0200Y         S1      
017m1841                  -    MD0100PA00X+121409Y+028295                       
327m1842            R6246 -1          A18X+121409Y+026421X0198Y0197R090 S2      
327m1842            D6000 -A          A01X+121409Y+027411X0240Y0280R090 S1      
317m1842            VIA   -    M      A01X+121409Y+026901X0200Y         S2      
017m1842            VIA   -    M      A18X+121409Y+026901X0260Y         S2      
017m1842                  -    MD0100PA00X+121409Y+026901                       
327A_HSC_LOW_GATE   R8110 -2          A18X+072554Y+168566X0198Y0197     S2      
327A_HSC_LOW_GATE   U142  -1   M      A18X+070163Y+167994X0250Y0480     S2      
327A_HSC_LOW_GATE   R8111 -2   M      A18X+068924Y+168474X0198Y0197     S2      
327A_HSC_LOW_GATE   R6237 -1   M      A18X+068234Y+168476X0198Y0197R180 S2      
327A_HSC_LOW_GATE   U6004 -G          A18X+068676Y+167894X0320Y0360R180 S2      
327A_HSC_LOW_GATE   VIA   -    M      A18X+068008Y+167894X0260Y         S2      
327A_HSC_LOW_GATE   R6236 -2   M      A18X+067865Y+168474X0198Y0197R180 S2      
327m1843            VIA   -    M      A18X+068940Y+166568X0260Y         S2      
327m1843            U6004 -D          A18X+069050Y+167106X0320Y0360R180 S2      
327m1843            R6238 -1          A18X+068940Y+166234X0198Y0197R180 S2      
327A_HSC_LOW        VIA   -    M      A18X+072163Y+168066X0260Y         S2      
327A_HSC_LOW        R6232 -2          A18X+072163Y+167746X0198Y0197R270 S2      
327A_HSC_LOW        R6233 -1   M      A18X+071593Y+167913X0198Y0197R270 S2      
327A_HSC_LOW        U142  -3          A18X+070911Y+167994X0250Y0480     S2      
327A_HSC_HIGH       U142  -4          A18X+070911Y+166963X0250Y0480     S2      
327A_HSC_HIGH       R6234 -2   M      A18X+071843Y+167083X0198Y0197     S2      
327A_HSC_HIGH       R6235 -1          A18X+071775Y+166053X0198Y0197R090 S2      
327A_HSC_HIGH       VIA   -    M      A18X+071836Y+166620X0260Y         S2      
327m1844            VIA   -    M      A18X+094250Y+092650X0260Y         S2      
327m1844            R1160 -1          A18X+094650Y+092308X0198Y0197R090 S2      
327m1844            R144  -2   M      A18X+094250Y+092308X0198Y0197R270 S2      
327m1844            U6    -2          A18X+094063Y+093146X0100Y0210R180 S2      
317PU_U212_EN_N     JP6000-1    D0410PA00X+009973Y+028982X0610Y0610R270 S3      
327PU_U212_EN_N     VIA   -    M      A01X+011502Y+028982X0300Y         S1      
327PU_U212_EN_N     R6181 -2          A01X+011502Y+029462X0198Y0197R270 S1      
317PU_U160_EN_N     JP6001-1    D0410PA00X+009973Y+031026X0610Y0610R270 S3      
327PU_U160_EN_N     VIA   -    M      A01X+011502Y+031026X0300Y         S1      
327PU_U160_EN_N     R6182 -2          A01X+011502Y+031506X0198Y0197R270 S1      
317PD_U212_EN_N     JP6000-3    D0410PA00X+007973Y+028982X0610Y    R270 S3      
327PD_U212_EN_N     VIA   -    M      A01X+012002Y+028982X0300Y         S1      
327PD_U212_EN_N     R1318 -1          A01X+012002Y+029462X0198Y0197R090 S1      
317PD_U160_EN_N     JP6001-3    D0410PA00X+007973Y+031026X0610Y    R270 S3      
327PD_U160_EN_N     VIA   -    M      A01X+012002Y+031026X0300Y         S1      
327PD_U160_EN_N     R1313 -1          A01X+012002Y+031506X0198Y0197R090 S1      
317FM_SEC_MUX_SEL   VIA   -    MD0100PA00X+090627Y+065492X0200Y         S0      
317FM_SEC_MUX_SEL   VIA   -    M      A01X+065352Y+039999X0200Y         S2      
017FM_SEC_MUX_SEL   VIA   -    M      A18X+065352Y+039999X0260Y         S2      
017FM_SEC_MUX_SEL         -    MD0100PA00X+065352Y+039999                       
327FM_SEC_MUX_SEL   R6188 -1          A01X+064566Y+040158X0198Y0197R180 S1      
327FM_SEC_MUX_SEL   R6187 -1   M      A01X+066695Y+040126X0198Y0197R270 S1      
327FM_SEC_MUX_SEL   R6184 -1          A01X+067247Y+040157X0198Y0197     S1      
317FM_SEC_MUX_SEL   VIA   -    MD0100PA00X+061646Y+050231X0200Y         S0      
317FM_SEC_MUX_SEL   VIA   -    MD0100PA00X+094452Y+093985X0200Y         S0      
327FM_SEC_MUX_SEL   U6    -9          A18X+094260Y+093650X0120Y0210R180 S2      
327m1845            R6184 -2          A01X+067562Y+040157X0198Y0197     S1      
317m1845            VIA   -    M      A01X+068927Y+041042X0200Y         S2      
017m1845            VIA   -    M      A18X+068927Y+041042X0260Y         S2      
017m1845                  -    MD0100PA00X+068927Y+041042                       
327m1845            U18   -K1         A01X+072568Y+041989X0160Y    R090 S1      
317m1845            VIA   -    MD0100PA00X+072414Y+041836X0180Y    R090 S0      
327m1846            R6183 -2          A01X+067562Y+040549X0198Y0197     S1      
317m1846            VIA   -    M      A01X+069430Y+041311X0200Y         S2      
017m1846            VIA   -    M      A18X+069430Y+041311X0260Y         S2      
017m1846                  -    MD0100PA00X+069430Y+041311                       
327m1846            U18   -K2         A01X+072568Y+042304X0160Y    R090 S1      
317m1846            VIA   -    MD0100PA00X+072414Y+042151X0180Y    R090 S0      
317m1847            VIA   -    MD0100PA00X+090882Y+065512X0200Y         S0      
317m1847            VIA   -    M      A01X+065128Y+040446X0200Y         S2      
017m1847            VIA   -    M      A18X+065128Y+040446X0260Y         S2      
017m1847                  -    MD0100PA00X+065128Y+040446                       
327m1847            R6186 -1          A01X+064560Y+040545X0198Y0197R180 S1      
327m1847            R6185 -1   M      A01X+066688Y+040518X0198Y0197R090 S1      
327m1847            R6183 -1          A01X+067247Y+040549X0198Y0197     S1      
317m1847            VIA   -    MD0100PA00X+061896Y+050231X0200Y         S0      
317m1847            VIA   -    MD0100PA00X+093537Y+093918X0200Y         S0      
327m1847            U6    -6          A18X+093669Y+093650X0120Y0210R180 S2      
327BUF2_VDD         VIA   -    M      A01X+007912Y+166686X0300Y    R090 S1      
327BUF2_VDD         C6011 -1   M      A01X+008387Y+166713X0198Y0197     S1      
327BUF2_VDD         U6000 -21         A01X+007293Y+166490X0098Y0236R270 S1      
327BUF2_VDD         C6012 -1   M      A01X+008391Y+166314X0198Y0197     S1      
327BUF2_VDD         U6000 -22         A01X+007293Y+166686X0098Y0236R270 S1      
317m1848            VIA   -    MD0100PA00X+108045Y+045796X0200Y         S0      
317m1848            VIA   -    M      A01X+176804Y+055654X0200Y         S2      
017m1848            VIA   -    M      A18X+176804Y+055654X0260Y         S2      
017m1848                  -    MD0100PA00X+176804Y+055654                       
327m1848            R6228 -2          A01X+107778Y+045796X0198Y0197     S1      
327m1848            R6230 -2   M      A01X+110875Y+153196X0198Y0197R090 S1      
327m1848            R2627 -2          A01X+110875Y+153580X0198Y0197R270 S1      
327m1849            R6229 -2          A01X+106887Y+046252X0198Y0197     S1      
317m1849            VIA   -    M      A01X+107787Y+046344X0200Y         S2      
017m1849            VIA   -    M      A18X+107787Y+046344X0260Y         S2      
017m1849                  -    MD0100PA00X+107787Y+046344                       
317m1849            VIA   -    MD0100PA00X+177396Y+055754X0200Y         S0      
327m1849            R6231 -2   M      A01X+111462Y+153196X0198Y0197R090 S1      
327m1849            R2626 -2          A01X+111412Y+153580X0198Y0197R270 S1      
327m1850            U6000 -3          A01X+006643Y+167336X0098Y0236R180 S1      
327m1850            R6160 -1          A01X+007413Y+168181X0198Y0197R090 S1      
327m1850            VIA   -    M      A01X+007024Y+167836X0300Y    R090 S1      
327m1851            R6154 -2          A01X+015791Y+166166X0120Y0150R180 S1      
317m1851            VIA   -    MD0100PA00X+016549Y+166218X0200Y    R090 S0      
317m1851            VIA   -    MD0100PA00X+008789Y+167452X0200Y    R090 S0      
327m1851            U6000 -24         A01X+007293Y+167080X0098Y0236R270 S1      
327m1852            R6155 -2          A01X+015791Y+166621X0120Y0150R180 S1      
317m1852            VIA   -    MD0100PA00X+016549Y+166558X0200Y    R090 S0      
317m1852            VIA   -    MD0100PA00X+008789Y+167112X0200Y    R090 S0      
327m1852            U6000 -23         A01X+007293Y+166883X0098Y0236R270 S1      
327m1853            U237  -2          A01X+013977Y+166658X0070Y0240R090 S1      
327m1853            R6152 -2          A01X+015371Y+166166X0120Y0150     S1      
327m1854            U237  -3          A01X+013977Y+166815X0070Y0240R090 S1      
327m1854            R6153 -2          A01X+015371Y+166621X0120Y0150     S1      
327m1855            C6005 -1          A01X+010762Y+165775X0180Y0200R180 S1      
317m1855            VIA   -    MD0100PA01X+009944Y+165853X0200Y    R090 S0      
317m1855            VIA   -    MD0100PA01X+004168Y+167672X0200Y    R090 S0      
327m1855            U6000 -7          A01X+005797Y+167080X0098Y0236R270 S1      
327m1856            C6006 -1          A01X+010762Y+166272X0180Y0200R180 S1      
317m1856            VIA   -    MD0100PA01X+009944Y+166193X0200Y    R090 S0      
317m1856            VIA   -    MD0100PA01X+004168Y+167332X0200Y    R090 S0      
327m1856            U6000 -8          A01X+005797Y+166883X0098Y0236R270 S1      
317m1857            VIA   -    MD0100PA01X+010044Y+168746X0200Y    R090 S0      
317m1857            VIA   -    MD0100PA01X+004092Y+165827X0200Y    R090 S0      
327m1857            R6158 -2          A01X+010717Y+168801X0120Y0150     S1      
327m1857            U6000 -11         A01X+005797Y+166293X0098Y0236R270 S1      
317m1858            VIA   -    MD0100PA01X+010044Y+168406X0200Y    R090 S0      
317m1858            VIA   -    MD0100PA01X+004092Y+165487X0200Y    R090 S0      
327m1858            R6159 -2          A01X+010717Y+168351X0120Y0150     S1      
327m1858            U6000 -12         A01X+005797Y+166096X0098Y0236R270 S1      
327m1859            U237  -17         A01X+012993Y+167760X0070Y0240R270 S1      
327m1859            R6156 -2          A01X+011137Y+168801X0120Y0150R180 S1      
327m1860            U237  -18         A01X+012993Y+167602X0070Y0240R270 S1      
327m1860            R6157 -2          A01X+011137Y+168351X0120Y0150R180 S1      
327m1861            C6007 -1          A01X+015886Y+167938X0180Y0200     S1      
317m1861            VIA   -    MD0100PA00X+008584Y+165854X0200Y    R090 S0      
327m1861            U6000 -20         A01X+007293Y+166293X0098Y0236R270 S1      
317m1861            VIA   -    MD0100PA00X+016534Y+167848X0200Y    R090 S0      
327m1862            C6008 -1          A01X+015886Y+167424X0180Y0200     S1      
317m1862            VIA   -    MD0100PA00X+016534Y+167508X0200Y    R090 S0      
317m1862            VIA   -    MD0100PA00X+008584Y+165514X0200Y    R090 S0      
327m1862            U6000 -19         A01X+007293Y+166096X0098Y0236R270 S1      
317P12V_MAIN_R_0    VIA   -    MD0100PA00X+109330Y+153266X0200Y    R090 S0      
317P12V_MAIN_R_0    VIA   -    MD0100PA00X+109630Y+153266X0200Y    R090 S0      
317P12V_MAIN_R_0    VIA   -    MD0100PA00X+108730Y+153266X0200Y    R090 S0      
317P12V_MAIN_R_0    VIA   -    MD0100PA00X+109030Y+153266X0200Y    R090 S0      
327P12V_MAIN_R_0    PR6002-2A         A01X+109143Y+153888X0770Y1580R270 S1      
327P12V_MAIN_R_0    VIA   -           A01X+110311Y+153352X0300Y    R180 S1      
327P12V_MAIN_R_0    PPQ9  -5          A01X+109160Y+152048X1850Y1811     S1      
327P12V_MAIN_R      VIA   -           A01X+107560Y+153370X0300Y    R180 S1      
327P12V_MAIN_R      PR2532-2A         A01X+105590Y+154198X1260Y2700R090 S1      
327P12V_MAIN_R      PR2534-2A         A01X+102430Y+154198X1260Y2700R090 S1      
327P12V_MAIN_R      PR2533-2A         A01X+099270Y+154198X1260Y2700R090 S1      
327P12V_MAIN_R      PR6001-2A         A01X+096108Y+154197X1260Y2700R090 S1      
327P12V_MAIN_R      PPQ8  -5          A01X+106823Y+152048X1850Y1811     S1      
327P12V_MAIN_R      PPQ7  -5          A01X+104487Y+152048X1850Y1811     S1      
327P12V_MAIN_R      PPQ6  -5          A01X+102150Y+152048X1850Y1811     S1      
327P12V_MAIN_R      PPQ5  -5          A01X+099813Y+152048X1850Y1811     S1      
327P12V_MAIN_R      PPQ2  -5          A01X+097477Y+152048X1850Y1811     S1      
327P12V_MAIN_R      PPQ1  -5          A01X+095140Y+152048X1850Y1811     S1      
317P12V_MAIN_R      VIA   -    MD0100PA00X+106011Y+153285X0200Y    R090 S0      
317P12V_MAIN_R      VIA   -    MD0100PA00X+106311Y+153285X0200Y    R090 S0      
317P12V_MAIN_R      VIA   -    MD0100PA00X+105658Y+152608X0200Y         S0      
317P12V_MAIN_R      VIA   -    MD0100PA00X+105411Y+153285X0200Y    R090 S0      
317P12V_MAIN_R      VIA   -    MD0100PA00X+105711Y+153285X0200Y    R090 S0      
317P12V_MAIN_R      VIA   -    MD0100PA00X+105111Y+153285X0200Y    R090 S0      
317P12V_MAIN_R      VIA   -    MD0100PA00X+102844Y+153293X0200Y    R090 S0      
317P12V_MAIN_R      VIA   -    MD0100PA00X+103144Y+153293X0200Y    R090 S0      
317P12V_MAIN_R      VIA   -    MD0100PA00X+103322Y+152608X0200Y         S0      
317P12V_MAIN_R      VIA   -    MD0100PA00X+102244Y+153293X0200Y    R090 S0      
317P12V_MAIN_R      VIA   -    MD0100PA00X+102544Y+153293X0200Y    R090 S0      
317P12V_MAIN_R      VIA   -    MD0100PA00X+101944Y+153293X0200Y    R090 S0      
317P12V_MAIN_R      VIA   -    MD0100PA00X+100985Y+152608X0200Y         S0      
317P12V_MAIN_R      VIA   -    MD0100PA00X+100028Y+153276X0200Y    R090 S0      
317P12V_MAIN_R      VIA   -    MD0100PA00X+098828Y+153276X0200Y    R090 S0      
317P12V_MAIN_R      VIA   -    MD0100PA00X+099728Y+153276X0200Y    R090 S0      
317P12V_MAIN_R      VIA   -    MD0100PA00X+099128Y+153276X0200Y    R090 S0      
317P12V_MAIN_R      VIA   -    MD0100PA00X+099428Y+153276X0200Y    R090 S0      
317P12V_MAIN_R      VIA   -    MD0100PA00X+098649Y+152608X0200Y         S0      
317P12V_MAIN_R      VIA   -    MD0100PA00X+096312Y+152608X0200Y         S0      
317P12V_MAIN_R      VIA   -    MD0100PA00X+095835Y+153276X0200Y    R090 S0      
317P12V_MAIN_R      VIA   -    MD0100PA00X+096135Y+153276X0200Y    R090 S0      
317P12V_MAIN_R      VIA   -    MD0100PA00X+096435Y+153276X0200Y    R090 S0      
317P12V_MAIN_R      VIA   -    MD0100PA00X+096735Y+153276X0200Y    R090 S0      
317P12V_MAIN_R      VIA   -    MD0100PA00X+095535Y+153276X0200Y    R090 S0      
317P12V_MAIN_R      VIA   -    MD0100PA00X+094441Y+153279X0200Y         S0      
317P12V_MAIN_R      VIA   -    MD0100PA00X+105658Y+152008X0200Y         S0      
317P12V_MAIN_R      VIA   -    MD0100PA00X+105658Y+152308X0200Y         S0      
317P12V_MAIN_R      VIA   -    MD0100PA00X+103322Y+152008X0200Y         S0      
317P12V_MAIN_R      VIA   -    MD0100PA00X+103322Y+152308X0200Y         S0      
317P12V_MAIN_R      VIA   -    MD0100PA00X+100985Y+152008X0200Y         S0      
317P12V_MAIN_R      VIA   -    MD0100PA00X+100985Y+152308X0200Y         S0      
317P12V_MAIN_R      VIA   -    MD0100PA00X+098649Y+152008X0200Y         S0      
317P12V_MAIN_R      VIA   -    MD0100PA00X+098649Y+152308X0200Y         S0      
317P12V_MAIN_R      VIA   -    MD0100PA00X+096312Y+152308X0200Y         S0      
317P12V_MAIN_R      VIA   -    MD0100PA00X+096312Y+152008X0200Y         S0      
327m1863            VIA   -    M      A01X+111766Y+153988X0300Y         S1      
327m1863            U143  -7          A01X+112419Y+154673X0170Y0590R180 S1      
327m1863            R2627 -1          A01X+110875Y+153896X0198Y0197R270 S1      
327m1864            VIA   -    M      A01X+111913Y+153485X0300Y         S1      
327m1864            R2626 -1          A01X+111412Y+153896X0198Y0197R270 S1      
327m1864            U143  -8          A01X+112674Y+154673X0170Y0590R180 S1      
327m1865            VIA   -    M      A01X+112576Y+159750X0300Y    R270 S1      
327m1865            R2625 -1          A01X+112501Y+159197X0198Y0197R270 S1      
327m1865            Q6001 -C   M      A01X+112625Y+160693X0400Y0500R180 S1      
327m1865            Q6001 -B          A01X+113025Y+161573X0400Y0500R180 S1      
327m1866            Q6001 -E          A01X+112225Y+161573X0400Y0500R180 S1      
327m1866            VIA   -    M      A01X+112015Y+159750X0300Y    R270 S1      
327m1866            R2624 -1          A01X+112101Y+159197X0198Y0197R270 S1      
327m1867            VIA   -    M      A01X+112066Y+157344X0300Y    R270 S1      
327m1867            C1786 -2          A01X+112011Y+158030X0280Y0320R090 S1      
327m1867            U143  -3          A01X+112163Y+156524X0170Y0590R180 S1      
327m1867            R2624 -2          A01X+112101Y+158882X0198Y0197R270 S1      
327m1868            VIA   -    M      A01X+112516Y+157344X0300Y    R270 S1      
327m1868            C1786 -1          A01X+112591Y+158030X0280Y0320R090 S1      
327m1868            U143  -2          A01X+112419Y+156524X0170Y0590R180 S1      
327m1868            R2625 -2          A01X+112501Y+158882X0198Y0197R270 S1      
317m1869            VIA   -    MD0100PA00X+081669Y+150678X0200Y         S0      
327m1869            PR2513-2          A18X+081914Y+150628X0198Y0197     S2      
327m1869            PR2523-2          A18X+081429Y+150628X0198Y0197R180 S2      
327m1869            PR2534-1B         A01X+102430Y+155390X0100Y0200R270 S1      
317m1869            VIA   -    M      A01X+102280Y+155084X0200Y         S2      
017m1869            VIA   -    M      A18X+102280Y+155084X0260Y         S2      
017m1869                  -    MD0100PA00X+102280Y+155084                       
317m1870            VIA   -    MD0100PA00X+081669Y+150980X0200Y         S0      
327m1870            PR2518-2          A18X+081914Y+151028X0198Y0197     S2      
327m1870            PR2527-2          A18X+081429Y+151028X0198Y0197R180 S2      
317m1870            VIA   -    MD0100PA00X+102580Y+155084X0200Y         S0      
327m1870            PR2534-2B         A01X+102430Y+154778X0100Y0200R270 S1      
317m1871            VIA   -    MD0100PA00X+081673Y+149736X0200Y         S0      
327m1871            PR2512-2          A18X+081914Y+149688X0198Y0197     S2      
327m1871            PR2522-2          A18X+081429Y+149688X0198Y0197R180 S2      
317m1871            VIA   -    M      A01X+099120Y+155084X0200Y         S2      
017m1871            VIA   -    M      A18X+099120Y+155084X0260Y         S2      
017m1871                  -    MD0100PA00X+099120Y+155084                       
327m1871            PR2533-1B         A01X+099270Y+155390X0100Y0200R270 S1      
317m1872            VIA   -    MD0100PA00X+081672Y+150039X0200Y         S0      
327m1872            PR2517-2          A18X+081914Y+150088X0198Y0197     S2      
327m1872            PR2526-2          A18X+081429Y+150088X0198Y0197R180 S2      
317m1872            VIA   -    MD0100PA00X+099420Y+155084X0200Y         S0      
327m1872            PR2533-2B         A01X+099270Y+154778X0100Y0200R270 S1      
317m1873            VIA   -    M      A01X+105440Y+155084X0200Y         S2      
017m1873            VIA   -    M      A18X+105440Y+155084X0260Y         S2      
017m1873                  -    MD0100PA00X+105440Y+155084                       
327m1873            PR2532-1B         A01X+105590Y+155390X0100Y0200R270 S1      
317m1873            VIA   -    MD0100PA00X+081669Y+151678X0200Y         S0      
327m1873            PR2511-2          A18X+081914Y+151628X0198Y0197     S2      
327m1873            PR2521-2          A18X+081429Y+151628X0198Y0197R180 S2      
317m1874            VIA   -    MD0100PA00X+105740Y+155084X0200Y         S0      
327m1874            PR2532-2B         A01X+105590Y+154778X0100Y0200R270 S1      
317m1874            VIA   -    MD0100PA00X+081671Y+151982X0200Y         S0      
327m1874            PR2516-2          A18X+081914Y+152028X0198Y0197     S2      
327m1874            PR2525-2          A18X+081429Y+152028X0198Y0197R180 S2      
317m1875            VIA   -    MD0100PA00X+081669Y+148738X0200Y         S0      
327m1875            PR2510-2          A18X+081914Y+148688X0198Y0197     S2      
327m1875            PR2520-2          A18X+081429Y+148688X0198Y0197R180 S2      
327m1875            PR6001-1B         A01X+096108Y+155388X0100Y0200R270 S1      
317m1875            VIA   -    M      A01X+095958Y+155082X0200Y         S2      
017m1875            VIA   -    M      A18X+095958Y+155082X0260Y         S2      
017m1875                  -    MD0100PA00X+095958Y+155082                       
317m1876            VIA   -    MD0100PA00X+081669Y+149038X0200Y         S0      
327m1876            PR2515-2          A18X+081914Y+149088X0198Y0197     S2      
327m1876            PR2524-2          A18X+081429Y+149088X0198Y0197R180 S2      
317m1876            VIA   -    MD0100PA00X+096258Y+155082X0200Y         S0      
327m1876            PR6001-2B         A01X+096108Y+154777X0100Y0200R270 S1      
327m1877            PJ38  -4          A01X+077953Y+150063X0240Y0650R270 S1      
317m1877            VIA   -    MD0100PA00X+078428Y+150063X0200Y    R090 S0      
327m1877            PR2522-1          A18X+081114Y+149688X0198Y0197R180 S2      
327m1877            PR2520-1          A18X+081114Y+148688X0198Y0197R180 S2      
317m1877            VIA   -    MD0100PA00X+080871Y+148738X0200Y    R090 S0      
327m1877            PR2523-1          A18X+081114Y+150628X0198Y0197R180 S2      
317m1877            VIA   -    MD0100PA00X+080871Y+150678X0200Y    R090 S0      
327m1877            PR2521-1          A18X+081114Y+151628X0198Y0197R180 S2      
317m1877            VIA   -    MD0100PA00X+080871Y+151678X0200Y    R090 S0      
327m1878            PJ38  -5          A01X+077953Y+150457X0240Y0650R270 S1      
317m1878            VIA   -    MD0100PA00X+078428Y+150457X0200Y    R090 S0      
327m1878            PR2527-1          A18X+081114Y+151028X0198Y0197R180 S2      
317m1878            VIA   -    MD0100PA00X+080871Y+150978X0200Y    R090 S0      
327m1878            PR2526-1          A18X+081114Y+150088X0198Y0197R180 S2      
317m1878            VIA   -    MD0100PA00X+080871Y+149038X0200Y    R090 S0      
327m1878            PR2524-1          A18X+081114Y+149088X0198Y0197R180 S2      
327m1878            PR2525-1          A18X+081114Y+152028X0198Y0197R180 S2      
317m1878            VIA   -    MD0100PA00X+080871Y+151978X0200Y    R090 S0      
327m1879            PR6002-1B         A01X+109143Y+155934X0100Y0200R270 S1      
317m1879            VIA   -    MD0100PA00X+109293Y+155078X0200Y    R270 S0      
327m1879            PR2514-2          A18X+081914Y+152628X0198Y0197     S2      
317m1879            VIA   -    MD0100PA00X+081671Y+152678X0200Y    R090 S0      
327m1879            PJ38  -2          A01X+077953Y+149276X0240Y0650R270 S1      
327m1880            PR6002-2B         A01X+109143Y+154222X0100Y0200R270 S1      
317m1880            VIA   -    M      A01X+108993Y+155078X0200Y    R270 S2      
017m1880            VIA   -    M      A18X+108993Y+155078X0260Y    R270 S2      
017m1880                  -    MD0100PA00X+108993Y+155078                       
327m1880            PR2519-2          A18X+081914Y+153028X0198Y0197     S2      
317m1880            VIA   -    MD0100PA00X+081671Y+152978X0200Y    R090 S0      
327m1880            PJ38  -3          A01X+077953Y+149670X0240Y0650R270 S1      
327m1881            PC1751-1          A18X+096102Y+150920X0198Y0197R090 S2      
327m1881            PR2537-2          A18X+095710Y+150978X0198Y0197R180 S2      
327m1882            PPQ2  -4          A01X+098227Y+150503X0280Y0460     S1      
327m1882            PR2536-1          A01X+098227Y+149870X0198Y0197     S1      
317m1882            VIA   -           A01X+098177Y+150120X0200Y         S2      
017m1882            VIA   -           A18X+098177Y+150120X0260Y         S2      
017m1882                  -     D0100PA00X+098177Y+150120                       
327m1883            PPQ1  -4          A01X+095890Y+150503X0280Y0460     S1      
327m1883            PR2535-1          A01X+095890Y+149870X0198Y0197     S1      
317m1883            VIA   -           A01X+095840Y+150120X0200Y         S2      
017m1883            VIA   -           A18X+095840Y+150120X0260Y         S2      
017m1883                  -     D0100PA00X+095840Y+150120                       
327m1884            PR2531-1          A01X+107573Y+149870X0198Y0197     S1      
327m1884            PPQ8  -4          A01X+107573Y+150503X0280Y0460     S1      
317m1884            VIA   -           A01X+107523Y+150120X0200Y         S2      
017m1884            VIA   -           A18X+107523Y+150120X0260Y         S2      
017m1884                  -     D0100PA00X+107523Y+150120                       
327m1885            PR2530-1          A01X+105237Y+149870X0198Y0197     S1      
327m1885            PPQ7  -4          A01X+105237Y+150503X0280Y0460     S1      
317m1885            VIA   -           A01X+105187Y+150120X0200Y         S2      
017m1885            VIA   -           A18X+105187Y+150120X0260Y         S2      
017m1885                  -     D0100PA00X+105187Y+150120                       
327m1886            PPQ6  -4          A01X+102900Y+150503X0280Y0460     S1      
327m1886            PR2529-1          A01X+102900Y+149870X0198Y0197     S1      
317m1886            VIA   -           A01X+102850Y+150120X0200Y         S2      
017m1886            VIA   -           A18X+102850Y+150120X0260Y         S2      
017m1886                  -     D0100PA00X+102850Y+150120                       
327m1887            PPQ5  -4          A01X+100563Y+150503X0280Y0460     S1      
327m1887            PR2528-1          A01X+100563Y+149870X0198Y0197     S1      
317m1887            VIA   -           A01X+100513Y+150120X0200Y         S2      
017m1887            VIA   -           A18X+100513Y+150120X0260Y         S2      
017m1887                  -     D0100PA00X+100513Y+150120                       
317P12V_HSC_GATE2   VIA   -    MD0100PA00X+077462Y+152036X0200Y    R270 S0      
317P12V_HSC_GATE2   VIA   -    MD0100PA00X+077291Y+152290X0200Y    R270 S0      
327P12V_HSC_GATE2   PJ38  -9          A01X+077953Y+152032X0240Y0650R270 S1      
317P12V_HSC_GATE2   VIA   -    MD0100PA00X+108023Y+150120X0200Y    R180 S0      
327P12V_HSC_GATE2   PR2531-2          A01X+107888Y+149870X0198Y0197     S1      
317P12V_HSC_GATE2   VIA   -    MD0100PA00X+105687Y+150120X0200Y    R180 S0      
327P12V_HSC_GATE2   PR2530-2          A01X+105552Y+149870X0198Y0197     S1      
317P12V_HSC_GATE2   VIA   -    MD0100PA00X+103350Y+150120X0200Y    R180 S0      
327P12V_HSC_GATE2   PR2529-2          A01X+103215Y+149870X0198Y0197     S1      
327P12V_HSC_GATE2   PR2528-2          A01X+100878Y+149870X0198Y0197     S1      
317P12V_HSC_GATE2   VIA   -    MD0100PA00X+101013Y+150120X0200Y    R180 S0      
317P12V_HSC_GATE2   VIA   -    MD0100PA00X+098677Y+150120X0200Y    R180 S0      
327P12V_HSC_GATE2   PR2536-2          A01X+098542Y+149870X0198Y0197     S1      
327P12V_HSC_GATE2   PC1751-2          A18X+096102Y+150605X0198Y0197R090 S2      
327P12V_HSC_GATE2   PC1750-2          A18X+095710Y+150578X0198Y0197R180 S2      
327P12V_HSC_GATE2   PR2535-2          A01X+096205Y+149870X0198Y0197     S1      
317P12V_HSC_GATE2   VIA   -    M      A01X+096340Y+150120X0200Y    R180 S2      
017P12V_HSC_GATE2   VIA   -    M      A18X+096340Y+150120X0260Y    R180 S2      
017P12V_HSC_GATE2         -    MD0100PA00X+096340Y+150120                       
327P12V_HSC_GATE1   PJ38  -8          A01X+077953Y+151638X0240Y0650R270 S1      
317P12V_HSC_GATE1   VIA   -    MD0100PA00X+077465Y+151644X0200Y    R270 S0      
317P12V_HSC_GATE1   VIA   -    M      A01X+110225Y+149619X0200Y         S2      
017P12V_HSC_GATE1   VIA   -    M      A18X+110225Y+149619X0260Y         S2      
017P12V_HSC_GATE1         -    MD0100PA00X+110225Y+149619                       
327P12V_HSC_GATE1   PR2538-2          A01X+110225Y+149870X0198Y0197     S1      
327P12V_HSC_ADC_P   PR2510-1          A18X+082229Y+148688X0198Y0197     S2      
317P12V_HSC_ADC_P   VIA   -    MD0100PA00X+082471Y+148738X0200Y    R090 S0      
327P12V_HSC_ADC_P   PR2513-1          A18X+082229Y+150628X0198Y0197     S2      
317P12V_HSC_ADC_P   VIA   -    MD0100PA00X+082471Y+150678X0200Y    R090 S0      
317P12V_HSC_ADC_P   VIA   -    MD0100PA00X+078428Y+151244X0200Y    R270 S0      
317P12V_HSC_ADC_P   VIA   -    MD0100PA00X+082471Y+152678X0200Y    R090 S0      
327P12V_HSC_ADC_P   PR2514-1          A18X+082229Y+152628X0198Y0197     S2      
327P12V_HSC_ADC_P   PJ38  -7          A01X+077953Y+151244X0240Y0650R270 S1      
327P12V_HSC_ADC_P   PR2512-1          A18X+082229Y+149688X0198Y0197     S2      
317P12V_HSC_ADC_P   VIA   -    MD0100PA00X+082471Y+149738X0200Y    R090 S0      
327P12V_HSC_ADC_P   PR2511-1          A18X+082229Y+151628X0198Y0197     S2      
317P12V_HSC_ADC_P   VIA   -    MD0100PA00X+082471Y+151678X0200Y    R090 S0      
327P12V_HSC_ADC_N   PR2515-1          A18X+082229Y+149088X0198Y0197     S2      
317P12V_HSC_ADC_N   VIA   -    MD0100PA00X+082471Y+149038X0200Y    R090 S0      
327P12V_HSC_ADC_N   PR2518-1          A18X+082229Y+151028X0198Y0197     S2      
317P12V_HSC_ADC_N   VIA   -    MD0100PA00X+082471Y+150978X0200Y    R090 S0      
317P12V_HSC_ADC_N   VIA   -    MD0100PA00X+078428Y+150851X0200Y    R270 S0      
317P12V_HSC_ADC_N   VIA   -    MD0100PA00X+082471Y+152978X0200Y    R090 S0      
327P12V_HSC_ADC_N   PR2519-1          A18X+082229Y+153028X0198Y0197     S2      
327P12V_HSC_ADC_N   PJ38  -6          A01X+077953Y+150851X0240Y0650R270 S1      
327P12V_HSC_ADC_N   PR2517-1          A18X+082229Y+150088X0198Y0197     S2      
317P12V_HSC_ADC_N   VIA   -    MD0100PA00X+082471Y+150038X0200Y    R090 S0      
327P12V_HSC_ADC_N   PR2516-1          A18X+082229Y+152028X0198Y0197     S2      
317P12V_HSC_ADC_N   VIA   -    MD0100PA00X+082471Y+151978X0200Y    R090 S0      
327NC_RES           VIA   -           A01X+005682Y+165353X0300Y    R090 S1      
327NC_RES           U6000 -13         A01X+006052Y+165840X0098Y0236R180 S1      
317MB0_CM_GATE_G0   VIA   -    M      A01X+109910Y+150120X0200Y         S2      
017MB0_CM_GATE_G0   VIA   -    M      A18X+109910Y+150120X0260Y         S2      
017MB0_CM_GATE_G0         -    MD0100PA00X+109910Y+150120                       
327MB0_CM_GATE_G0   PR2538-1   M      A01X+109910Y+149870X0198Y0197     S1      
327MB0_CM_GATE_G0   PPQ9  -4   M      A01X+109910Y+150503X0280Y0460     S1      
317HSC_TYPE_ADC     VIA   -    M      A01X+168918Y+170210X0200Y         S2      
017HSC_TYPE_ADC     VIA   -    M      A18X+168918Y+170210X0260Y         S2      
017HSC_TYPE_ADC           -    MD0100PA00X+168918Y+170210                       
317HSC_TYPE_ADC     VIA   -    MD0100PA00X+115518Y+165553X0200Y         S0      
317HSC_TYPE_ADC     VIA   -    MD0100PA00X+115525Y+155918X0200Y         S0      
327HSC_TYPE_ADC     PJ38  -17         A01X+076291Y+151047X0240Y0650R090 S1      
317HSC_TYPE_ADC     VIA   -    MD0100PA00X+075816Y+151047X0200Y    R090 S0      
327HSC_TYPE_ADC     U6005 -11         A01X+168809Y+169176X0090Y0240     S1      
327HSC_TYPE_ADC     C6086 -1   M      A01X+168788Y+169643X0198Y0197R180 S1      
317HSC_CSOUT        VIA   -    MD0100PA00X+072248Y+165762X0200Y         S0      
327HSC_CSOUT        R6232 -1          A18X+072163Y+167431X0198Y0197R270 S2      
327HSC_CSOUT        R6210 -1          A18X+069952Y+165834X0198Y0197     S2      
327HSC_CSOUT        R6234 -1   M      A18X+072158Y+167083X0198Y0197     S2      
317HSC_CSOUT        VIA   -    MD0100PA00X+069104Y+162551X0200Y         S0      
317HSC_CSOUT        VIA   -    M      A01X+075816Y+150654X0200Y    R090 S2      
017HSC_CSOUT        VIA   -    M      A18X+075816Y+150654X0260Y    R090 S2      
017HSC_CSOUT              -    MD0100PA00X+075816Y+150654                       
327HSC_CSOUT        PJ38  -16         A01X+076291Y+150654X0240Y0650R090 S1      
327HSC_CSOUT        R8108 -1   M      A18X+072263Y+166697X0198Y0197R090 S2      
327FM_P2E_EN2_N     U6000 -6          A01X+006052Y+167336X0098Y0236R180 S1      
327FM_P2E_EN2_N     R6162 -1          A01X+004820Y+168164X0198Y0197R180 S1      
327FM_P2E_EN2_N     VIA   -    M      A01X+004907Y+167815X0300Y    R090 S1      
327m1888            R6179 -2          A01X+006443Y+164996X0198Y0197R090 S1      
327m1888            R6180 -1   M      A01X+006843Y+164996X0198Y0197R270 S1      
327m1888            VIA   -    M      A01X+006840Y+165338X0300Y    R090 S1      
327m1888            U6000 -17         A01X+006840Y+165840X0098Y0236R180 S1      
327m1889            U6000 -5          A01X+006249Y+167336X0098Y0236R180 S1      
327m1889            R6168 -1   M      A01X+005520Y+168149X0198Y0197R180 S1      
327m1889            R6167 -2          A01X+005905Y+168202X0198Y0197R180 S1      
327m1889            VIA   -    M      A01X+005669Y+167792X0300Y    R090 S1      
327m1890            VIA   -    M      A01X+006446Y+167840X0300Y    R090 S1      
327m1890            R6169 -2   M      A01X+006613Y+168181X0198Y0197R270 S1      
327m1890            R6170 -1          A01X+007013Y+168181X0198Y0197R090 S1      
327m1890            U6000 -4          A01X+006446Y+167336X0098Y0236R180 S1      
327m1891            R6177 -2          A01X+005543Y+164996X0198Y0197R090 S1      
327m1891            R6178 -1   M      A01X+005943Y+164996X0198Y0197R270 S1      
327m1891            VIA   -    M      A01X+006215Y+165345X0300Y    R090 S1      
327m1891            U6000 -14         A01X+006249Y+165840X0098Y0236R180 S1      
327m1892            R6175 -2          A01X+007743Y+164996X0198Y0197R090 S1      
327m1892            VIA   -    M      A01X+007340Y+165341X0300Y    R090 S1      
327m1892            U6000 -18         A01X+007037Y+165840X0098Y0236R180 S1      
327m1892            R6176 -1   M      A01X+007343Y+164996X0198Y0197R270 S1      
327m1893            VIA   -    M      A01X+007647Y+167841X0300Y    R090 S1      
327m1893            R6164 -1   M      A01X+007813Y+168181X0198Y0197R090 S1      
327m1893            R6163 -2          A01X+008213Y+168181X0198Y0197R270 S1      
327m1893            U6000 -2          A01X+006840Y+167336X0098Y0236R180 S1      
327m1894            U6000 -1          A01X+007037Y+167336X0098Y0236R180 S1      
327m1894            VIA   -    M      A01X+008263Y+167832X0300Y    R090 S1      
327m1894            R6166 -1   M      A01X+008613Y+168181X0198Y0197R090 S1      
327m1894            R6165 -2          A01X+009013Y+168181X0198Y0197R270 S1      
327m1895            VIA   -    M      A01X+005093Y+166859X0300Y    R090 S1      
327m1895            R6172 -1   M      A01X+004750Y+166859X0198Y0197R180 S1      
327m1895            U6000 -9          A01X+005797Y+166686X0098Y0236R270 S1      
327m1895            R6171 -2          A01X+003850Y+166859X0198Y0197     S1      
327m1896            R6173 -2          A01X+003850Y+166359X0198Y0197     S1      
327m1896            R6174 -1   M      A01X+004750Y+166359X0198Y0197R180 S1      
327m1896            VIA   -    M      A01X+005093Y+166359X0300Y    R090 S1      
327m1896            U6000 -10         A01X+005797Y+166490X0098Y0236R270 S1      
327m1897            U224  -1          A01X+180507Y+037117X0170Y0240R270 S1      
327m1897            R3231 -2          A01X+179535Y+036787X0198Y0197     S1      
327m1897            VIA   -    M      A01X+179535Y+037273X0300Y         S1      
327m1898            R6120 -2          A18X+159966Y+137642X0198Y0197R270 S2      
327m1898            U25   -DH4        A01X+154322Y+116094X0177Y    R180 S1      
317m1898            VIA   -    MD0100PA00X+152442Y+118524X0200Y         S0      
327m1898            R6125 -1          A18X+159767Y+139386X0198Y0197R270 S2      
317m1898            VIA   -    M      A01X+159723Y+138269X0200Y         S2      
017m1898            VIA   -    M      A18X+159723Y+138269X0260Y         S2      
017m1898                  -    MD0100PA00X+159723Y+138269                       
317m1899            VIA   -    MD0080PA00X+144329Y+115880X0160Y         S0      
327m1899            U25   -DG31       A01X+144145Y+115776X0177Y    R180 S1      
327m1899            R6121 -2          A18X+159072Y+137644X0198Y0197R270 S2      
327m1899            R6126 -1          A18X+158810Y+139386X0198Y0197R270 S2      
317m1899            VIA   -    M      A01X+159072Y+138159X0200Y         S2      
017m1899            VIA   -    M      A18X+159072Y+138159X0260Y         S2      
017m1899                  -    MD0100PA00X+159072Y+138159                       
317m1900            VIA   -    MD0080PA00X+144514Y+115561X0160Y         S0      
327m1900            U25   -DF31       A01X+144330Y+115457X0177Y    R180 S1      
317m1900            VIA   -    M      A01X+159279Y+138832X0200Y         S2      
017m1900            VIA   -    M      A18X+159279Y+138832X0260Y         S2      
017m1900                  -    MD0100PA00X+159279Y+138832                       
327m1900            R6127 -1          A18X+159279Y+139386X0198Y0197R270 S2      
327m1900            R6122 -2          A18X+159544Y+137636X0198Y0197R270 S2      
317m1901            VIA   -    MD0080PA00X+143959Y+115242X0160Y         S0      
327m1901            U25   -DE32       A01X+143775Y+115138X0177Y    R180 S1      
327m1901            R6128 -1          A18X+158341Y+139386X0198Y0197R270 S2      
327m1901            R6123 -2          A18X+158600Y+137645X0198Y0197R270 S2      
317m1901            VIA   -    M      A01X+158600Y+138764X0200Y         S2      
017m1901            VIA   -    M      A18X+158600Y+138764X0260Y         S2      
017m1901                  -    MD0100PA00X+158600Y+138764                       
317m1902            VIA   -    MD0080PA00X+143774Y+115561X0160Y         S0      
327m1902            U25   -DF33       A01X+143590Y+115457X0177Y    R180 S1      
327m1902            R6129 -1          A18X+157860Y+139386X0198Y0197R270 S2      
327m1902            R6124 -2          A18X+158118Y+137645X0198Y0197R270 S2      
317m1902            VIA   -    M      A01X+158416Y+138142X0200Y         S2      
017m1902            VIA   -    M      A18X+158416Y+138142X0260Y         S2      
017m1902                  -    MD0100PA00X+158416Y+138142                       
327m1903            VIA   -    M      A01X+065080Y+045624X0300Y         S1      
327m1903            R6141 -1          A01X+064609Y+045775X0198Y0197R180 S1      
327m1903            U18   -A11        A01X+069733Y+045139X0160Y    R090 S1      
317m1903            VIA   -    MD0100PA00X+069580Y+044985X0180Y    R090 S0      
327m1903            R6136 -2   M      A01X+065950Y+045776X0198Y0197     S1      
317m1903            VIA   -    MD0100PA00X+066257Y+045776X0200Y         S0      
317m1904            VIA   -    MD0100PA00X+069895Y+044985X0180Y    R090 S2      
327m1904            R6142 -1          A01X+064620Y+046185X0198Y0197R180 S1      
327m1904            U18   -B11        A01X+070048Y+045139X0160Y    R090 S1      
327m1904            R6137 -2   M      A01X+065952Y+046182X0198Y0197     S1      
317m1904            VIA   -    MD0100PA00X+066257Y+046155X0200Y         S0      
317m1905            VIA   -    MD0100PA00X+068019Y+049124X0200Y         S0      
327m1905            VIA   -    M      A01X+066866Y+048610X0300Y         S1      
327m1905            R6138 -2          A01X+066453Y+048694X0198Y0197     S1      
327m1905            R6143 -1   M      A01X+067561Y+048694X0198Y0197R180 S1      
327m1905            U18   -F10        A01X+071308Y+044824X0160Y    R090 S1      
317m1905            VIA   -    MD0100PA00X+071154Y+044670X0180Y    R090 S0      
327m1906            R6139 -2          A01X+066439Y+049513X0198Y0197     S1      
317m1906            VIA   -    M      A01X+068121Y+049566X0200Y         S2      
017m1906            VIA   -    M      A18X+068121Y+049566X0260Y         S2      
017m1906                  -    MD0100PA00X+068121Y+049566                       
327m1906            R6144 -1   M      A01X+067586Y+049508X0198Y0197R180 S1      
327m1906            U18   -G9         A01X+071623Y+044509X0160Y    R090 S1      
317m1906            VIA   -    MD0100PA00X+071469Y+044356X0180Y    R090 S0      
327m1907            R6145 -1          A18X+064868Y+044494X0198Y0197     S2      
327m1907            U18   -C5         A01X+070363Y+043249X0160Y    R090 S1      
317m1907            VIA   -    MD0100PA00X+070210Y+043096X0180Y    R090 S0      
327m1907            R6140 -2   M      A18X+064742Y+043952X0198Y0197R180 S2      
317m1907            VIA   -    M      A01X+065185Y+043952X0200Y         S2      
017m1907            VIA   -    M      A18X+065185Y+043952X0260Y         S2      
017m1907                  -    MD0100PA00X+065185Y+043952                       
327FAB_REV_ID2      U25   -A13        A01X+150688Y+087429X0177Y    R180 S1      
317FAB_REV_ID2      VIA   -    MD0100PA00X+150502Y+081711X0200Y         S0      
327FAB_REV_ID2      VIA   -    M      A18X+154839Y+079809X0260Y         S2      
317FAB_REV_ID2      VIA   -    MD0100PA00X+154756Y+080727X0200Y         S0      
327FAB_REV_ID2      R6130 -2   M      A18X+154717Y+080413X0198Y0197     S2      
327FAB_REV_ID2      R6133 -1          A18X+155043Y+079190X0198Y0197R090 S2      
317FAB_REV_ID1      VIA   -    MD0080PA00X+150502Y+087962X0160Y    R180 S0      
327FAB_REV_ID1      U25   -C14        A01X+150318Y+088067X0177Y    R180 S1      
327FAB_REV_ID1      VIA   -    M      A18X+156003Y+079642X0260Y         S2      
317FAB_REV_ID1      VIA   -    MD0100PA00X+155636Y+080727X0200Y         S0      
327FAB_REV_ID1      R6134 -1          A18X+155962Y+079195X0198Y0197R090 S2      
327FAB_REV_ID1      R6131 -2   M      A18X+155992Y+080425X0198Y0197R270 S2      
327FAB_REV_ID0      U25   -A14        A01X+150318Y+087429X0177Y    R180 S1      
317FAB_REV_ID0      VIA   -    MD0100PA00X+150164Y+082880X0200Y         S0      
327FAB_REV_ID0      VIA   -    M      A18X+155364Y+079654X0260Y         S2      
327FAB_REV_ID0      R6135 -1          A18X+155560Y+079198X0198Y0197R090 S2      
327FAB_REV_ID0      R6132 -2   M      A18X+155611Y+080426X0198Y0197R270 S2      
317FAB_REV_ID0      VIA   -    MD0100PA00X+155196Y+080727X0200Y         S0      
327m1908            U18   -K6         A01X+072568Y+043564X0160Y    R090 S1      
317m1908            VIA   -    M      A01X+070750Y+036886X0200Y         S2      
017m1908            VIA   -    M      A18X+070750Y+036886X0260Y         S2      
017m1908                  -    MD0100PA00X+070750Y+036886                       
317m1908            VIA   -    MD0100PA00X+072414Y+043411X0180Y    R090 S0      
327m1908            R6146 -2   M      A01X+070754Y+036640X0198Y0197R090 S1      
327m1908            R6149 -1          A01X+071146Y+036644X0198Y0197R270 S1      
327m1909            R6147 -2          A18X+067557Y+040465X0198Y0197R180 S2      
327m1909            R6150 -1   M      A18X+067245Y+040922X0198Y0197R180 S2      
327m1909            U18   -K7         A01X+072568Y+043879X0160Y    R090 S1      
317m1909            VIA   -    M      A01X+069300Y+041836X0200Y    R270 S2      
017m1909            VIA   -    M      A18X+069300Y+041836X0260Y    R270 S2      
017m1909                  -    MD0100PA00X+069300Y+041836                       
317m1909            VIA   -    MD0100PA00X+072414Y+043726X0180Y    R090 S0      
327m1910            U18   -J1         A01X+072253Y+041989X0160Y    R090 S1      
317m1910            VIA   -    M      A01X+071550Y+036886X0200Y         S2      
017m1910            VIA   -    M      A18X+071550Y+036886X0260Y         S2      
017m1910                  -    MD0100PA00X+071550Y+036886                       
317m1910            VIA   -    MD0100PA00X+072099Y+041836X0180Y    R090 S0      
327m1910            R6148 -2   M      A01X+071540Y+036643X0198Y0197R090 S1      
327m1910            R6151 -1          A01X+071933Y+036644X0198Y0197R270 S1      
317m1911            VIA   -    MD0080PA00X+046344Y+115243X0160Y         S0      
327m1911            U26   -DE32       A01X+046161Y+115138X0177Y    R180 S1      
327m1911            VIA   -           A18X+063298Y+129715X0260Y         S2      
317m1912            VIA   -    MD0080PA00X+046159Y+115562X0160Y         S0      
327m1912            U26   -DF33       A01X+045976Y+115457X0177Y    R180 S1      
327m1912            VIA   -           A18X+062611Y+130192X0260Y         S2      
327m1913            J41   -A8         A01X+068766Y+005354X0150Y0570R180 S1      
327m1913            R4507 -2          A18X+069440Y+005261X0198Y0197R090 S2      
317m1913            VIA   -    M      A01X+068734Y+004694X0200Y         S2      
017m1913            VIA   -    M      A18X+068734Y+004694X0260Y         S2      
017m1913                  -    MD0100PA00X+068734Y+004694                       
327m1914            J41   -A7         A01X+069003Y+005354X0150Y0570R180 S1      
327m1914            R4506 -2          A18X+069860Y+005261X0198Y0197R090 S2      
317m1914            VIA   -    M      A01X+068784Y+003785X0200Y         S2      
017m1914            VIA   -    M      A18X+068784Y+003785X0260Y         S2      
017m1914                  -    MD0100PA00X+068784Y+003785                       
327m1915            C8005 -1          A01X+082084Y+042310X0198Y0197     S1      
317m1915            VIA   -    MD0100PA00X+074926Y+042781X0180Y         S2      
327m1915            R6118 -1   M      A01X+082084Y+041934X0198Y0197     S1      
317m1915            VIA   -    MD0100PA00X+081750Y+041934X0200Y         S0      
327m1915            U18   -U4         A01X+074772Y+042934X0160Y    R090 S1      
327m1916            R6117 -2          A18X+067560Y+047336X0198Y0197R180 S2      
327m1916            U18   -D15        A01X+070678Y+046399X0160Y    R090 S1      
327m1916            VIA   -    M      A18X+069032Y+046858X0260Y    R090 S2      
317m1916            VIA   -    MD0100PA00X+070524Y+046552X0180Y    R090 S0      
327m1917            R2939 -2          A01X+082084Y+045934X0198Y0197R180 S1      
327m1917            U18   -T10        A01X+074458Y+044824X0160Y    R090 S1      
317m1917            VIA   -    MD0100PA00X+074611Y+044670X0180Y    R090 S0      
317m1917            VIA   -    M      A01X+081617Y+045852X0300Y         S1      
017m1917            VIA   -    M      A18X+081617Y+045852X0200Y         S1      
017m1917                  -    MD0100PA00X+081617Y+045852                       
317m1918            VIA   -    MD0100PA00X+014609Y+170560X0200Y         S0      
317m1918            VIA   -    MD0100PA00X+019876Y+171999X0200Y         S0      
327m1918            U252  -1          A01X+019876Y+171756X0160Y0200R270 S1      
317m1918            VIA   -    M      A01X+078336Y+049534X0200Y         S2      
017m1918            VIA   -    M      A18X+078336Y+049534X0260Y         S2      
017m1918                  -    MD0100PA00X+078336Y+049534                       
327m1918            R6113 -2          A18X+077823Y+049534X0198Y0197R180 S2      
317m1918            VIA   -    MD0100PA00X+079140Y+034226X0200Y         S0      
317m1918            VIA   -    MD0100PA00X+043623Y+047553X0200Y         S0      
317m1918            VIA   -    MD0100PA00X+063658Y+036694X0200Y         S0      
327m1919            R6115 -1          A18X+077538Y+049164X0198Y0197R180 S2      
327m1919            R6113 -1   M      A18X+077508Y+049534X0198Y0197R180 S2      
327m1919            U18   -U14        A01X+074772Y+046084X0160Y    R090 S1      
327m1919            VIA   -    M      A18X+076511Y+048430X0260Y    R090 S2      
317m1919            VIA   -    MD0100PA00X+074926Y+046237X0180Y    R090 S0      
317m1920            VIA   -    MD0100PA00X+080341Y+034157X0200Y         S0      
317m1920            VIA   -    M      A01X+063650Y+036036X0200Y         S2      
017m1920            VIA   -    M      A18X+063650Y+036036X0260Y         S2      
017m1920                  -    MD0100PA00X+063650Y+036036                       
317m1920            VIA   -    MD0100PA00X+079725Y+045534X0200Y         S0      
327m1920            R6112 -2          A01X+079273Y+045534X0198Y0197     S1      
317m1920            VIA   -    MD0100PA00X+042621Y+046898X0200Y         S0      
317m1920            VIA   -    MD0100PA00X+015526Y+172368X0200Y         S0      
327m1920            U256  -1          A01X+015526Y+172106X0160Y0200R270 S1      
327m1921            R6114 -1          A01X+080951Y+045534X0198Y0197R180 S1      
317m1921            VIA   -    M      A01X+081311Y+045534X0200Y    R180 S2      
017m1921            VIA   -    M      A18X+081311Y+045534X0260Y    R180 S2      
017m1921                  -    MD0100PA00X+081311Y+045534                       
327m1921            R6112 -1          A01X+078958Y+045534X0198Y0197     S1      
317m1921            VIA   -    MD0100PA00X+078676Y+045552X0200Y    R180 S0      
317m1921            VIA   -    MD0100PA00X+074611Y+046237X0180Y    R090 S0      
327m1921            U18   -T14        A01X+074458Y+046084X0160Y    R090 S1      
317m1922            VIA   -    MD0100PA00X+075871Y+043411X0180Y    R090 S2      
327m1922            U18   -Y6         A01X+075717Y+043564X0160Y    R090 S1      
317m1922            VIA   -    MD0100PA00X+081750Y+043106X0200Y         S0      
327m1922            R6055 -2          A01X+082084Y+043134X0198Y0197R180 S1      
327NC_Q83_S2        Q83   -4          A18X+131207Y+030318X0170Y0200R090 S2      
327NC_Q83_S2        VIA   -           A18X+131693Y+030318X0260Y    R270 S2      
327NC_Q83_G2        VIA   -           A18X+131693Y+029818X0260Y    R270 S2      
327NC_Q83_G2        Q83   -5          A18X+131207Y+030062X0170Y0200R090 S2      
327NC_Q83_D2        VIA   -           A18X+130459Y+030848X0260Y    R270 S2      
327NC_Q83_D2        Q83   -3          A18X+130459Y+030318X0170Y0200R090 S2      
327m1923            D93   -C          A01X+122209Y+027785X0240Y0280R090 S1      
317m1923            VIA   -    M      A01X+122209Y+028295X0300Y         S1      
017m1923            VIA   -    M      A18X+122209Y+028295X0200Y         S1      
017m1923                  -    MD0100PA00X+122209Y+028295                       
327m1923            Q87   -6          A18X+122518Y+029207X0170Y0200R270 S2      
317m1924            VIA   -    M      A01X+122209Y+026901X0200Y         S2      
017m1924            VIA   -    M      A18X+122209Y+026901X0260Y         S2      
017m1924                  -    MD0100PA00X+122209Y+026901                       
327m1924            D93   -A          A01X+122209Y+027411X0240Y0280R090 S1      
327m1924            R3074 -1          A18X+122209Y+026421X0198Y0197R090 S2      
327m1925            D83   -A          A01X+135009Y+027411X0240Y0280R090 S1      
317m1925            VIA   -    M      A01X+135009Y+026901X0200Y         S2      
017m1925            VIA   -    M      A18X+135009Y+026901X0260Y         S2      
017m1925                  -    MD0100PA00X+135009Y+026901                       
327m1925            R3095 -1          A18X+135009Y+026421X0198Y0197R090 S2      
327m1926            D83   -C          A01X+135009Y+027785X0240Y0280R090 S1      
327m1926            Q85   -3          A18X+135266Y+028695X0170Y0200R270 S2      
317m1926            VIA   -    M      A01X+135009Y+028295X0300Y         S1      
017m1926            VIA   -    M      A18X+135009Y+028295X0200Y         S1      
017m1926                  -    MD0100PA00X+135009Y+028295                       
327m1927            D77   -A          A01X+130209Y+027411X0240Y0280R090 S1      
317m1927            VIA   -    M      A01X+130209Y+026901X0200Y         S2      
017m1927            VIA   -    M      A18X+130209Y+026901X0260Y         S2      
017m1927                  -    MD0100PA00X+130209Y+026901                       
327m1927            R3092 -1          A18X+130209Y+026421X0198Y0197R090 S2      
327m1928            D77   -C          A01X+130209Y+027785X0240Y0280R090 S1      
317m1928            VIA   -    M      A01X+130209Y+028295X0300Y         S1      
017m1928            VIA   -    M      A18X+130209Y+028295X0200Y         S1      
017m1928                  -    MD0100PA00X+130209Y+028295                       
327m1928            Q81   -6          A18X+130518Y+029207X0170Y0200R270 S2      
327m1929            D81   -A          A01X+133409Y+027411X0240Y0280R090 S1      
317m1929            VIA   -    M      A01X+133409Y+026901X0200Y         S2      
017m1929            VIA   -    M      A18X+133409Y+026901X0260Y         S2      
017m1929                  -    MD0100PA00X+133409Y+026901                       
327m1929            R3094 -1          A18X+133409Y+026421X0198Y0197R090 S2      
327m1930            D81   -C          A01X+133409Y+027785X0240Y0280R090 S1      
327m1930            Q84   -3          A18X+133666Y+028695X0170Y0200R270 S2      
317m1930            VIA   -    M      A01X+133409Y+028295X0300Y         S1      
017m1930            VIA   -    M      A18X+133409Y+028295X0200Y         S1      
017m1930                  -    MD0100PA00X+133409Y+028295                       
327m1931            D75   -A          A01X+128609Y+027411X0240Y0280R090 S1      
317m1931            VIA   -    M      A01X+128609Y+026901X0200Y         S2      
017m1931            VIA   -    M      A18X+128609Y+026901X0260Y         S2      
017m1931                  -    MD0100PA00X+128609Y+026901                       
327m1931            R3089 -1          A18X+128609Y+026421X0198Y0197R090 S2      
327m1932            D75   -C          A01X+128609Y+027785X0240Y0280R090 S1      
317m1932            VIA   -    M      A01X+128609Y+028295X0300Y         S1      
017m1932            VIA   -    M      A18X+128609Y+028295X0200Y         S1      
017m1932                  -    MD0100PA00X+128609Y+028295                       
327m1932            Q80   -6          A18X+128918Y+029207X0170Y0200R270 S2      
327m1933            D82   -A          A01X+134209Y+027411X0240Y0280R090 S1      
317m1933            VIA   -    M      A01X+134209Y+026901X0200Y         S2      
017m1933            VIA   -    M      A18X+134209Y+026901X0260Y         S2      
017m1933                  -    MD0100PA00X+134209Y+026901                       
327m1933            R3096 -1          A18X+134209Y+026421X0198Y0197R090 S2      
327m1934            D82   -C          A01X+134209Y+027785X0240Y0280R090 S1      
317m1934            VIA   -    M      A01X+134209Y+028295X0300Y         S1      
017m1934            VIA   -    M      A18X+134209Y+028295X0200Y         S1      
017m1934                  -    MD0100PA00X+134209Y+028295                       
327m1934            Q85   -6          A18X+134518Y+029207X0170Y0200R270 S2      
327m1935            D76   -A          A01X+129409Y+027411X0240Y0280R090 S1      
317m1935            VIA   -    M      A01X+129409Y+026901X0200Y         S2      
017m1935            VIA   -    M      A18X+129409Y+026901X0260Y         S2      
017m1935                  -    MD0100PA00X+129409Y+026901                       
327m1935            R3088 -1          A18X+129409Y+026421X0198Y0197R090 S2      
327m1936            D76   -C          A01X+129409Y+027785X0240Y0280R090 S1      
327m1936            Q80   -3          A18X+129666Y+028695X0170Y0200R270 S2      
317m1936            VIA   -    M      A01X+129409Y+028295X0300Y         S1      
017m1936            VIA   -    M      A18X+129409Y+028295X0200Y         S1      
017m1936                  -    MD0100PA00X+129409Y+028295                       
327m1937            D80   -A          A01X+132609Y+027411X0240Y0280R090 S1      
317m1937            VIA   -    M      A01X+132609Y+026901X0200Y         S2      
017m1937            VIA   -    M      A18X+132609Y+026901X0260Y         S2      
017m1937                  -    MD0100PA00X+132609Y+026901                       
327m1937            R3093 -1          A18X+132609Y+026421X0198Y0197R090 S2      
327m1938            D80   -C          A01X+132609Y+027785X0240Y0280R090 S1      
317m1938            VIA   -    M      A01X+132609Y+028295X0300Y         S1      
017m1938            VIA   -    M      A18X+132609Y+028295X0200Y         S1      
017m1938                  -    MD0100PA00X+132609Y+028295                       
327m1938            Q84   -6          A18X+132918Y+029207X0170Y0200R270 S2      
327m1939            D74   -A          A01X+127809Y+027411X0240Y0280R090 S1      
317m1939            VIA   -    M      A01X+127809Y+026901X0200Y         S2      
017m1939            VIA   -    M      A18X+127809Y+026901X0260Y         S2      
017m1939                  -    MD0100PA00X+127809Y+026901                       
327m1939            R3087 -1          A18X+127809Y+026421X0198Y0197R090 S2      
327m1940            D74   -C          A01X+127809Y+027785X0240Y0280R090 S1      
327m1940            Q79   -3          A18X+128066Y+028695X0170Y0200R270 S2      
317m1940            VIA   -    M      A01X+127809Y+028295X0300Y         S1      
017m1940            VIA   -    M      A18X+127809Y+028295X0200Y         S1      
017m1940                  -    MD0100PA00X+127809Y+028295                       
317m1941            VIA   -    M      A01X+127009Y+026901X0200Y         S2      
017m1941            VIA   -    M      A18X+127009Y+026901X0260Y         S2      
017m1941                  -    MD0100PA00X+127009Y+026901                       
327m1941            D73   -A          A01X+127009Y+027411X0240Y0280R090 S1      
327m1941            R3086 -1          A18X+127009Y+026421X0198Y0197R090 S2      
327m1942            D73   -C          A01X+127009Y+027785X0240Y0280R090 S1      
317m1942            VIA   -    M      A01X+127009Y+028295X0300Y         S1      
017m1942            VIA   -    M      A18X+127009Y+028295X0200Y         S1      
017m1942                  -    MD0100PA00X+127009Y+028295                       
327m1942            Q79   -6          A18X+127318Y+029207X0170Y0200R270 S2      
327m1943            D85   -A          A01X+136609Y+027411X0240Y0280R090 S1      
317m1943            VIA   -    M      A01X+136609Y+026901X0200Y         S2      
017m1943            VIA   -    M      A18X+136609Y+026901X0260Y         S2      
017m1943                  -    MD0100PA00X+136609Y+026901                       
327m1943            R3097 -1          A18X+136609Y+026421X0198Y0197R090 S2      
327m1944            D85   -C          A01X+136609Y+027785X0240Y0280R090 S1      
327m1944            Q86   -3          A18X+136866Y+028695X0170Y0200R270 S2      
317m1944            VIA   -    M      A01X+136609Y+028295X0300Y         S1      
017m1944            VIA   -    M      A18X+136609Y+028295X0200Y         S1      
017m1944                  -    MD0100PA00X+136609Y+028295                       
327m1945            D79   -A          A01X+131809Y+027411X0240Y0280R090 S1      
317m1945            VIA   -    M      A01X+131809Y+026901X0200Y         S2      
017m1945            VIA   -    M      A18X+131809Y+026901X0260Y         S2      
017m1945                  -    MD0100PA00X+131809Y+026901                       
327m1945            R3091 -1          A18X+131809Y+026421X0198Y0197R090 S2      
327m1946            D79   -C          A01X+131809Y+027785X0240Y0280R090 S1      
327m1946            Q83   -6          A18X+131207Y+029807X0170Y0200R090 S2      
317m1946            VIA   -    M      A01X+131809Y+028295X0300Y         S1      
017m1946            VIA   -    M      A18X+131809Y+028295X0200Y         S1      
017m1946                  -    MD0100PA00X+131809Y+028295                       
327m1947            D84   -A          A01X+135809Y+027411X0240Y0280R090 S1      
317m1947            VIA   -    M      A01X+135809Y+026901X0200Y         S2      
017m1947            VIA   -    M      A18X+135809Y+026901X0260Y         S2      
017m1947                  -    MD0100PA00X+135809Y+026901                       
327m1947            R3099 -1          A18X+135809Y+026421X0198Y0197R090 S2      
327m1948            D84   -C          A01X+135809Y+027785X0240Y0280R090 S1      
317m1948            VIA   -    M      A01X+135809Y+028295X0300Y         S1      
017m1948            VIA   -    M      A18X+135809Y+028295X0200Y         S1      
017m1948                  -    MD0100PA00X+135809Y+028295                       
327m1948            Q86   -6          A18X+136118Y+029207X0170Y0200R270 S2      
327m1949            D78   -A          A01X+131009Y+027411X0240Y0280R090 S1      
317m1949            VIA   -    M      A01X+131009Y+026901X0200Y         S2      
017m1949            VIA   -    M      A18X+131009Y+026901X0260Y         S2      
017m1949                  -    MD0100PA00X+131009Y+026901                       
327m1949            R3090 -1          A18X+131009Y+026421X0198Y0197R090 S2      
327m1950            D78   -C          A01X+131009Y+027785X0240Y0280R090 S1      
327m1950            Q81   -3          A18X+131266Y+028695X0170Y0200R270 S2      
317m1950            VIA   -    M      A01X+131009Y+028295X0300Y         S1      
017m1950            VIA   -    M      A18X+131009Y+028295X0200Y         S1      
017m1950                  -    MD0100PA00X+131009Y+028295                       
327JTAG_TDO_R1      U147  -4          A01X+057234Y+022550X0070Y0320R270 S1      
317JTAG_TDO_R1      VIA   -    M      A01X+056900Y+022550X0200Y    R090 S2      
017JTAG_TDO_R1      VIA   -    M      A18X+056900Y+022550X0260Y    R090 S2      
017JTAG_TDO_R1            -    MD0100PA00X+056900Y+022550                       
327JTAG_TDO_R1      R6111 -1          A01X+049414Y+021565X0198Y0197R090 S1      
327JTAG_TDO_R1      U146  -4          A01X+048830Y+021565X0070Y0320R090 S1      
317JTAG_TDO_R1      VIA   -    MD0100PA00X+049164Y+021565X0200Y    R270 S0      
317m1951            VIA   -    MD0100PA00X+067461Y+034566X0200Y         S0      
317m1951            VIA   -    MD0100PA00X+068480Y+047786X0200Y         S0      
327m1951            U18   -A18        A01X+069733Y+047344X0160Y    R090 S1      
317m1951            VIA   -    M      A01X+134209Y+029207X0300Y         S1      
017m1951            VIA   -    M      A18X+134209Y+029207X0200Y         S1      
017m1951                  -    MD0100PA00X+134209Y+029207                       
327m1951            Q85   -5          A18X+134518Y+028951X0170Y0200R270 S2      
327m1952            U18   -Y11        A01X+075717Y+045139X0160Y    R090 S1      
317m1952            VIA   -    MD0100PA00X+075871Y+044985X0180Y    R090 S0      
317m1952            VIA   -    MD0100PA00X+082288Y+044642X0200Y         S0      
317m1952            VIA   -    MD0100PA00X+082829Y+040157X0200Y         S0      
327m1952            Q81   -2          A18X+131266Y+028951X0170Y0200R270 S2      
317m1952            VIA   -    M      A01X+131009Y+028795X0300Y         S1      
017m1952            VIA   -    M      A18X+131009Y+028795X0200Y         S1      
017m1952                  -    MD0100PA00X+131009Y+028795                       
317m1953            VIA   -    MD0100PA00X+067211Y+034566X0200Y         S0      
317m1953            VIA   -    MD0100PA00X+068480Y+048186X0200Y         S0      
327m1953            U18   -B18        A01X+070048Y+047344X0160Y    R090 S1      
327m1953            Q84   -5          A18X+132918Y+028951X0170Y0200R270 S2      
317m1953            VIA   -    M      A01X+132609Y+029207X0300Y         S1      
017m1953            VIA   -    M      A18X+132609Y+029207X0200Y         S1      
017m1953                  -    MD0100PA00X+132609Y+029207                       
327m1954            U18   -V4         A01X+075087Y+042934X0160Y    R090 S1      
317m1954            VIA   -    MD0100PA00X+075241Y+042781X0180Y    R090 S0      
317m1954            VIA   -    MD0100PA00X+081628Y+040381X0200Y         S0      
327m1954            Q80   -2          A18X+129666Y+028951X0170Y0200R270 S2      
317m1954            VIA   -    M      A01X+129409Y+028795X0300Y         S1      
017m1954            VIA   -    M      A18X+129409Y+028795X0200Y         S1      
017m1954                  -    MD0100PA00X+129409Y+028795                       
327m1955            U18   -E16        A01X+070993Y+046714X0160Y    R090 S1      
317m1955            VIA   -    MD0100PA00X+070840Y+046867X0180Y    R090 S0      
317m1955            VIA   -    M      A01X+135009Y+028795X0300Y         S1      
017m1955            VIA   -    M      A18X+135009Y+028795X0200Y         S1      
017m1955                  -    MD0100PA00X+135009Y+028795                       
327m1955            Q85   -2          A18X+135266Y+028951X0170Y0200R270 S2      
327m1956            U18   -R5         A01X+074143Y+043249X0160Y    R090 S1      
317m1956            VIA   -    MD0100PA00X+074296Y+043096X0180Y         S0      
317m1956            VIA   -    MD0100PA00X+081315Y+040391X0200Y         S0      
327m1956            Q80   -5          A18X+128918Y+028951X0170Y0200R270 S2      
317m1956            VIA   -    M      A01X+128609Y+029207X0300Y         S1      
017m1956            VIA   -    M      A18X+128609Y+029207X0200Y         S1      
017m1956                  -    MD0100PA00X+128609Y+029207                       
317m1957            VIA   -    MD0100PA00X+079831Y+037257X0200Y         S0      
327m1957            U18   -V10        A01X+075087Y+044824X0160Y    R090 S1      
317m1957            VIA   -    MD0100PA00X+075241Y+044670X0180Y    R090 S0      
317m1957            VIA   -    M      A01X+133409Y+028795X0300Y         S1      
017m1957            VIA   -    M      A18X+133409Y+028795X0200Y         S1      
017m1957                  -    MD0100PA00X+133409Y+028795                       
327m1957            Q84   -2          A18X+133666Y+028951X0170Y0200R270 S2      
327m1958            U18   -U5         A01X+074772Y+043249X0160Y    R090 S1      
317m1958            VIA   -    MD0100PA00X+074926Y+043096X0180Y    R090 S0      
317m1958            VIA   -    MD0100PA00X+082002Y+040371X0200Y         S0      
327m1958            Q79   -5          A18X+127318Y+028951X0170Y0200R270 S2      
317m1958            VIA   -    M      A01X+127009Y+029207X0300Y         S1      
017m1958            VIA   -    M      A18X+127009Y+029207X0200Y         S1      
017m1958                  -    MD0100PA00X+127009Y+029207                       
327m1959            Q79   -2          A18X+128066Y+028951X0170Y0200R270 S2      
317m1959            VIA   -    MD0100PA00X+127809Y+028795X0200Y         S0      
327m1959            U18   -T11        A01X+074458Y+045139X0160Y    R090 S1      
327m1959            VIA   -    M      A18X+076214Y+045563X0260Y    R090 S2      
317m1959            VIA   -    MD0100PA00X+074611Y+044985X0180Y    R090 S0      
317m1959            VIA   -    MD0100PA00X+083138Y+045517X0200Y         S0      
317m1959            VIA   -    MD0100PA00X+083443Y+040150X0200Y         S0      
327m1960            U18   -A19        A01X+069733Y+047659X0160Y    R090 S1      
317m1960            VIA   -    MD0100PA00X+068468Y+048594X0200Y         S0      
317m1960            VIA   -    MD0100PA00X+066355Y+034604X0200Y         S0      
327m1960            Q86   -5          A18X+136118Y+028951X0170Y0200R270 S2      
317m1960            VIA   -    M      A01X+135809Y+029207X0300Y         S1      
017m1960            VIA   -    M      A18X+135809Y+029207X0200Y         S1      
017m1960                  -    MD0100PA00X+135809Y+029207                       
317m1961            VIA   -    MD0100PA00X+121070Y+031367X0200Y         S0      
317m1961            VIA   -    MD0100PA00X+084803Y+033846X0200Y         S0      
317m1961            VIA   -    MD0100PA00X+085794Y+044858X0200Y         S0      
317m1961            VIA   -    MD0100PA00X+083222Y+045033X0200Y         S0      
327m1961            U18   -AB11       A01X+076347Y+045139X0160Y    R090 S1      
327m1961            VIA   -    M      A01X+080018Y+045338X0300Y    R090 S1      
317m1961            VIA   -    MD0100PA00X+130207Y+030318X0200Y         S0      
327m1961            Q83   -2          A18X+130459Y+030062X0170Y0200R090 S2      
317m1962            VIA   -    MD0100PA00X+067711Y+034566X0200Y         S0      
317m1962            VIA   -    MD0100PA00X+068747Y+048699X0200Y         S0      
327m1962            U18   -B19        A01X+070048Y+047659X0160Y    R090 S1      
327m1962            Q86   -2          A18X+136866Y+028951X0170Y0200R270 S2      
317m1962            VIA   -    M      A01X+136609Y+028795X0300Y         S1      
017m1962            VIA   -    M      A18X+136609Y+028795X0200Y         S1      
017m1962                  -    MD0100PA00X+136609Y+028795                       
327m1963            U18   -Y12        A01X+075717Y+045454X0160Y    R090 S1      
317m1963            VIA   -    MD0100PA00X+075871Y+045607X0180Y    R090 S0      
317m1963            VIA   -    MD0100PA00X+079700Y+040400X0200Y         S0      
327m1963            Q81   -5          A18X+130518Y+028951X0170Y0200R270 S2      
317m1963            VIA   -    M      A01X+130209Y+029207X0300Y         S1      
017m1963            VIA   -    M      A18X+130209Y+029207X0200Y         S1      
017m1963                  -    MD0100PA00X+130209Y+029207                       
327m1964            J41   -B40        A01X+059865Y+006516X0150Y0570R180 S1      
327m1964            R6026 -2          A01X+059050Y+009010X0198Y0197R270 S1      
317m1964            VIA   -    M      A01X+059050Y+008691X0200Y         S2      
017m1964            VIA   -    M      A18X+059050Y+008691X0260Y         S2      
017m1964                  -    MD0100PA00X+059050Y+008691                       
327NC_Q95_S2        Q95   -4          A01X+057339Y+041073X0170Y0200R090 S1      
317NC_Q95_S2        VIA   -           A01X+057086Y+041073X0200Y    R270 S2      
017NC_Q95_S2        VIA   -           A18X+057086Y+041073X0260Y    R270 S2      
017NC_Q95_S2              -     D0100PA00X+057086Y+041073                       
327NC_Q95_G2        Q95   -5          A01X+057339Y+041329X0170Y0200R090 S1      
317NC_Q95_G2        VIA   -           A01X+057591Y+041329X0200Y    R090 S2      
017NC_Q95_G2        VIA   -           A18X+057591Y+041329X0260Y    R090 S2      
017NC_Q95_G2              -     D0100PA00X+057591Y+041329                       
327NC_Q95_D2        Q95   -3          A01X+056591Y+041073X0170Y0200R090 S1      
327NC_Q95_D2        VIA   -           A01X+055372Y+040863X0300Y         S1      
317JTAG_TDO_R       VIA   -    M      A01X+051208Y+020640X0200Y    R090 S2      
017JTAG_TDO_R       VIA   -    M      A18X+051208Y+020640X0260Y    R090 S2      
017JTAG_TDO_R             -    MD0100PA00X+051208Y+020640                       
327JTAG_TDO_R       U152  -9          A01X+051208Y+020974X0070Y0320R180 S1      
327JTAG_TDO_R       R6109 -2          A01X+051135Y+020240X0198Y0197     S1      
327m1965            VIA   -    M      A01X+093968Y+062866X0300Y    R270 S1      
327m1965            R6110 -1          A01X+094448Y+062866X0198Y0197     S1      
327m1965            U154  -6          A01X+091689Y+063119X0140Y0520R090 S1      
327m1965            U154  -2   M      A01X+093146Y+062863X0140Y0520R090 S1      
327HDT_HDR_TDO_R    VIA   -    M      A01X+047558Y+021498X0300Y    R270 S1      
327HDT_HDR_TDO_R    R6108 -2          A01X+047544Y+020971X0198Y0197R090 S1      
327HDT_HDR_TDO_R    U146  -9          A01X+048121Y+021565X0070Y0320R090 S1      
317m1966            DB7   -2    D0670PA00X+186971Y+170901X0850Y    R180 S3      
317m1966            DB7   -3    D0670PA00X+185971Y+170901X0850Y    R180 S3      
317m1967            DB16  -3    D0670PA00X+207201Y+010831X0850Y         S3      
317m1967            DB16  -2    D0670PA00X+208201Y+010831X0850Y         S3      
317m1968            DB15  -3    D0670PA00X+188122Y+140447X0850Y         S3      
317m1968            DB15  -2    D0670PA00X+189122Y+140447X0850Y         S3      
317m1969            DB11  -3    D0670PA00X+189118Y+170932X0850Y    R180 S3      
317m1969            DB11  -2    D0670PA00X+188118Y+170932X0850Y    R180 S3      
317m1970            DB10  -3    D0670PA00X+188234Y+041083X0850Y    R180 S3      
317m1970            DB10  -2    D0670PA00X+189234Y+041083X0850Y    R180 S3      
317m1971            DB9   -2    D0670PA00X+188186Y+010729X0850Y         S3      
317m1971            DB9   -3    D0670PA00X+189186Y+010729X0850Y         S3      
317m1972            DB8   -2    D0670PA00X+185999Y+140342X0850Y         S3      
317m1972            DB8   -3    D0670PA00X+186999Y+140342X0850Y         S3      
317m1973            DB12  -3    D0670PA00X+208113Y+041083X0850Y    R180 S3      
317m1973            DB12  -2    D0670PA00X+207113Y+041083X0850Y    R180 S3      
317m1974            DB1   -2    D0670PA00X+188327Y+085082X0850Y         S3      
317m1974            DB1   -3    D0670PA00X+189327Y+085082X0850Y         S3      
317m1975            DB14  -3    D0670PA00X+186230Y+085077X0850Y         S3      
317m1975            DB14  -2    D0670PA00X+187230Y+085077X0850Y         S3      
317m1976            DB13  -3    D0670PA00X+187065Y+078373X0850Y    R180 S3      
317m1976            DB13  -2    D0670PA00X+186065Y+078373X0850Y    R180 S3      
317m1977            DB5   -3    D0670PA00X+186179Y+047657X0850Y         S3      
317m1977            DB5   -2    D0670PA00X+187179Y+047657X0850Y         S3      
317m1978            DB4   -3    D0670PA00X+188258Y+115835X0850Y    R180 S3      
317m1978            DB4   -2    D0670PA00X+189258Y+115835X0850Y    R180 S3      
317m1979            DB3   -2    D0670PA00X+189224Y+078347X0850Y    R180 S3      
317m1979            DB3   -3    D0670PA00X+188224Y+078347X0850Y    R180 S3      
317m1980            DB2   -3    D0670PA00X+189271Y+047686X0850Y         S3      
317m1980            DB2   -2    D0670PA00X+188271Y+047686X0850Y         S3      
317m1981            DB6   -2    D0670PA00X+186179Y+115807X0850Y    R180 S3      
317m1981            DB6   -3    D0670PA00X+187179Y+115807X0850Y    R180 S3      
317m1982            X8007 -4    D0098PA00X+205742Y+056253X0395Y    R090 S3      
317m1982            X8001 -1    D0098PA00X+205742Y-002967X0395Y    R270 S3      
317m1983            X8001 -4    D0098PA00X+204742Y-002967X0395Y    R270 S3      
317m1983            X8007 -1    D0098PA00X+204742Y+056253X0395Y    R090 S3      
317m1984            X9028 -4    D0098PA00X+192977Y+120816X0395Y    R090 S3      
317m1984            X9026 -1    D0098PA00X+192977Y+180036X0395Y    R270 S3      
317m1985            X9028 -1    D0098PA00X+191977Y+120816X0395Y    R090 S3      
317m1985            X9026 -4    D0098PA00X+191977Y+180036X0395Y    R270 S3      
317m1986            X9025 -1    D0098PA00X+196186Y+120817X0395Y    R090 S3      
317m1986            X9027 -4    D0098PA00X+196186Y+180037X0395Y    R270 S3      
317m1987            X9025 -4    D0098PA00X+197186Y+120817X0395Y    R090 S3      
317m1987            X9027 -1    D0098PA00X+197186Y+180037X0395Y    R270 S3      
317m1988            X9005 -1    D0098PA00X+200382Y+120831X0395Y    R090 S3      
317m1988            X9011 -4    D0098PA00X+200382Y+180051X0395Y    R270 S3      
317m1989            X9005 -4    D0098PA00X+201382Y+120831X0395Y    R090 S3      
317m1989            X9011 -1    D0098PA00X+201382Y+180051X0395Y    R270 S3      
317m1990            X9004 -1    D0098PA00X+189880Y+180040X0395Y    R090 S3      
317m1990            X9010 -4    D0098PA00X+189880Y+120820X0395Y    R270 S3      
317m1991            X9004 -4    D0098PA00X+190880Y+180040X0395Y    R090 S3      
317m1991            X9010 -1    D0098PA00X+190880Y+120820X0395Y    R270 S3      
317m1992            X9009 -4    D0098PA00X+195089Y+180037X0395Y    R090 S3      
317m1992            X9003 -1    D0098PA00X+195089Y+120817X0395Y    R270 S3      
317m1993            X9009 -1    D0098PA00X+194089Y+180037X0395Y    R090 S3      
317m1993            X9003 -4    D0098PA00X+194089Y+120817X0395Y    R270 S3      
317m1994            X9008 -4    D0098PA00X+199286Y+180055X0395Y    R090 S3      
317m1994            X9002 -1    D0098PA00X+199286Y+120835X0395Y    R270 S3      
317m1995            X9002 -4    D0098PA00X+198286Y+120835X0395Y    R270 S3      
317m1995            X9008 -1    D0098PA00X+198286Y+180055X0395Y    R090 S3      
317m1996            X8026 -1    D0098PA00X+194240Y-002978X0395Y    R090 S3      
317m1996            X8028 -4    D0098PA00X+194240Y+056242X0395Y    R270 S3      
317m1997            X8026 -4    D0098PA00X+195240Y-002978X0395Y    R090 S3      
317m1997            X8028 -1    D0098PA00X+195240Y+056242X0395Y    R270 S3      
317m1998            X8025 -1    D0098PA00X+198448Y-002981X0395Y    R090 S3      
317m1998            X8027 -4    D0098PA00X+198448Y+056239X0395Y    R270 S3      
317m1999            X8025 -4    D0098PA00X+199448Y-002981X0395Y    R090 S3      
317m1999            X8027 -1    D0098PA00X+199448Y+056239X0395Y    R270 S3      
317m2000            X8005 -1    D0098PA00X+202645Y-002963X0395Y    R090 S3      
317m2000            X8011 -4    D0098PA00X+202645Y+056257X0395Y    R270 S3      
317m2001            X8005 -4    D0098PA00X+203645Y-002963X0395Y    R090 S3      
317m2001            X8011 -1    D0098PA00X+203645Y+056257X0395Y    R270 S3      
317m2002            X8004 -1    D0098PA00X+193140Y-002996X0395Y    R270 S3      
317m2002            X8010 -4    D0098PA00X+193140Y+056224X0395Y    R090 S3      
317m2003            X8004 -4    D0098PA00X+192140Y-002996X0395Y    R270 S3      
317m2003            X8010 -1    D0098PA00X+192140Y+056224X0395Y    R090 S3      
317m2004            X8009 -4    D0098PA00X+196336Y-002982X0395Y    R270 S3      
317m2004            X8003 -1    D0098PA00X+196336Y+056238X0395Y    R090 S3      
317m2005            X8009 -1    D0098PA00X+197336Y-002982X0395Y    R270 S3      
317m2005            X8003 -4    D0098PA00X+197336Y+056238X0395Y    R090 S3      
317m2006            X8008 -4    D0098PA00X+201545Y+056239X0395Y    R090 S3      
317m2006            X8002 -1    D0098PA00X+201545Y-002981X0395Y    R270 S3      
317m2007            X8008 -1    D0098PA00X+200545Y+056239X0395Y    R090 S3      
317m2007            X8002 -4    D0098PA00X+200545Y-002981X0395Y    R270 S3      
317m2008            X8006 -1    D0098PA00X+190028Y-002997X0395Y    R090 S3      
317m2008            X8012 -4    D0098PA00X+190028Y+056223X0395Y    R270 S3      
317m2009            X8012 -1    D0098PA00X+191028Y+056223X0395Y    R270 S3      
317m2009            X8006 -4    D0098PA00X+191028Y-002997X0395Y    R090 S3      
317m2010            X1    -1    D0098PA00X+206854Y+117474X0395Y    R090 S3      
317m2010            X7    -4    D0098PA00X+206854Y+058254X0395Y    R270 S3      
317m2011            X1    -4    D0098PA00X+207854Y+117474X0395Y    R090 S3      
317m2011            X7    -1    D0098PA00X+207854Y+058254X0395Y    R270 S3      
317m2012            X26   -1    D0098PA00X+197336Y+117458X0395Y    R270 S3      
317m2012            X28   -4    D0098PA00X+197336Y+058238X0395Y    R090 S3      
317m2013            X26   -4    D0098PA00X+196336Y+117458X0395Y    R270 S3      
317m2013            X28   -1    D0098PA00X+196336Y+058238X0395Y    R090 S3      
317m2014            X27   -4    D0098PA00X+200545Y+117459X0395Y    R270 S3      
317m2014            X25   -1    D0098PA00X+200545Y+058239X0395Y    R090 S3      
317m2015            X27   -1    D0098PA00X+201545Y+117459X0395Y    R270 S3      
317m2015            X25   -4    D0098PA00X+201545Y+058239X0395Y    R090 S3      
317m2016            X11   -4    D0098PA00X+204742Y+117473X0395Y    R270 S3      
317m2016            X5    -1    D0098PA00X+204742Y+058253X0395Y    R090 S3      
317m2017            X11   -1    D0098PA00X+205742Y+117473X0395Y    R270 S3      
317m2017            X5    -4    D0098PA00X+205742Y+058253X0395Y    R090 S3      
317m2018            X10   -4    D0098PA00X+195240Y+117462X0395Y    R090 S3      
317m2018            X4    -1    D0098PA00X+195240Y+058242X0395Y    R270 S3      
317m2019            X10   -1    D0098PA00X+194240Y+117462X0395Y    R090 S3      
317m2019            X4    -4    D0098PA00X+194240Y+058242X0395Y    R270 S3      
317m2020            X3    -1    D0098PA00X+198448Y+117459X0395Y    R090 S3      
317m2020            X9    -4    D0098PA00X+198448Y+058239X0395Y    R270 S3      
317m2021            X3    -4    D0098PA00X+199448Y+117459X0395Y    R090 S3      
317m2021            X9    -1    D0098PA00X+199448Y+058239X0395Y    R270 S3      
317m2022            X8    -4    D0098PA00X+203645Y+117477X0395Y    R090 S3      
317m2022            X2    -1    D0098PA00X+203645Y+058257X0395Y    R270 S3      
317m2023            X8    -1    D0098PA00X+202645Y+117477X0395Y    R090 S3      
317m2023            X2    -4    D0098PA00X+202645Y+058257X0395Y    R270 S3      
317m2024            X12   -4    D0098PA00X+192140Y+117444X0395Y    R270 S3      
317m2024            X6    -1    D0098PA00X+192140Y+058224X0395Y    R090 S3      
317m2025            X12   -1    D0098PA00X+193140Y+117444X0395Y    R270 S3      
317m2025            X6    -4    D0098PA00X+193140Y+058224X0395Y    R090 S3      
317T1_GND           X9011 -2   MD0098PA00X+201382Y+181051X0785Y    R270 S3      
317T1_GND           X9011 -3   MD0098PA00X+200382Y+181051X0785Y    R270 S3      
317T1_GND           X9008 -2   MD0098PA00X+198286Y+181055X0785Y    R090 S3      
317T1_GND           X9008 -3   MD0098PA00X+199286Y+181055X0785Y    R090 S3      
317T1_GND           X9027 -2   MD0098PA00X+197186Y+181037X0785Y    R270 S3      
317T1_GND           X9027 -3   MD0098PA00X+196186Y+181037X0785Y    R270 S3      
317T1_GND           X9009 -3   MD0098PA00X+195089Y+181037X0785Y    R090 S3      
317T1_GND           X9009 -2   MD0098PA00X+194089Y+181037X0785Y    R090 S3      
317T1_GND           X9026 -2   MD0098PA00X+192977Y+181036X0785Y    R270 S3      
317T1_GND           X9026 -3   MD0098PA00X+191977Y+181036X0785Y    R270 S3      
317T1_GND           X9004 -3   MD0098PA00X+190880Y+181040X0785Y    R090 S3      
317T1_GND           X9004 -2   MD0098PA00X+189880Y+181040X0785Y    R090 S3      
317T1_GND           DB11  -1   MD0670PA00X+188618Y+172251X0850Y    R180 S3      
317T1_GND           DB7   -1   MD0670PA00X+186471Y+172220X0850Y    R180 S3      
317T1_GND           DB15  -1   MD0670PA00X+188622Y+139128X0850Y         S3      
317T1_GND           DB8   -1   MD0670PA00X+186499Y+139023X0850Y         S3      
317T1_GND           X9005 -3   MD0098PA00X+201382Y+119831X0785Y    R090 S3      
317T1_GND           X9005 -2   MD0098PA00X+200382Y+119831X0785Y    R090 S3      
317T1_GND           X9002 -2   MD0098PA00X+199286Y+119835X0785Y    R270 S3      
317T1_GND           X9002 -3   MD0098PA00X+198286Y+119835X0785Y    R270 S3      
317T1_GND           X9025 -3   MD0098PA00X+197186Y+119817X0785Y    R090 S3      
317T1_GND           X9025 -2   MD0098PA00X+196186Y+119817X0785Y    R090 S3      
317T1_GND           X9003 -2   MD0098PA00X+195089Y+119817X0785Y    R270 S3      
317T1_GND           X9003 -3   MD0098PA00X+194089Y+119817X0785Y    R270 S3      
317T1_GND           X9028 -2   MD0098PA00X+191977Y+119816X0785Y    R090 S3      
317T1_GND           X9028 -3   MD0098PA00X+192977Y+119816X0785Y    R090 S3      
317T1_GND           X9010 -2   MD0098PA00X+190880Y+119820X0785Y    R270 S3      
317T1_GND           X9010 -3   MD0098PA00X+189880Y+119820X0785Y    R270 S3      
317T1_GND           X1    -2   MD0098PA00X+206854Y+118474X0785Y    R090 S3      
317T1_GND           X1    -3   MD0098PA00X+207854Y+118474X0785Y    R090 S3      
317T1_GND           X11   -2   MD0098PA00X+205742Y+118473X0785Y    R270 S3      
317T1_GND           X11   -3   MD0098PA00X+204742Y+118473X0785Y    R270 S3      
317T1_GND           X8    -2   MD0098PA00X+202645Y+118477X0785Y    R090 S3      
317T1_GND           X8    -3   MD0098PA00X+203645Y+118477X0785Y    R090 S3      
317T1_GND           X27   -2   MD0098PA00X+201545Y+118459X0785Y    R270 S3      
317T1_GND           X27   -3   MD0098PA00X+200545Y+118459X0785Y    R270 S3      
317T1_GND           X3    -3   MD0098PA00X+199448Y+118459X0785Y    R090 S3      
317T1_GND           X3    -2   MD0098PA00X+198448Y+118459X0785Y    R090 S3      
317T1_GND           X26   -2   MD0098PA00X+197336Y+118458X0785Y    R270 S3      
317T1_GND           X26   -3   MD0098PA00X+196336Y+118458X0785Y    R270 S3      
317T1_GND           X10   -3   MD0098PA00X+195240Y+118462X0785Y    R090 S3      
317T1_GND           X10   -2   MD0098PA00X+194240Y+118462X0785Y    R090 S3      
317T1_GND           X12   -2   MD0098PA00X+193140Y+118444X0785Y    R270 S3      
317T1_GND           X12   -3   MD0098PA00X+192140Y+118444X0785Y    R270 S3      
317T1_GND           DB4   -1   MD0670PA00X+188758Y+117153X0850Y    R180 S3      
317T1_GND           DB6   -1   MD0670PA00X+186679Y+117126X0850Y    R180 S3      
317T1_GND           DB1   -1   MD0670PA00X+188827Y+083763X0850Y         S3      
317T1_GND           DB14  -1   MD0670PA00X+186730Y+083758X0850Y         S3      
317T1_GND           DB3   -1   MD0670PA00X+188724Y+079666X0850Y    R180 S3      
317T1_GND           DB13  -1   MD0670PA00X+186565Y+079691X0850Y    R180 S3      
317T1_GND           X7    -2   MD0098PA00X+207854Y+057254X0785Y    R270 S3      
317T1_GND           X7    -3   MD0098PA00X+206854Y+057254X0785Y    R270 S3      
317T1_GND           X8007 -3   MD0098PA00X+205742Y+057253X0785Y    R090 S3      
317T1_GND           X5    -3   MD0098PA00X+205742Y+057253X0785Y    R090 S3      
317T1_GND           X8007 -2   MD0098PA00X+204742Y+057253X0785Y    R090 S3      
317T1_GND           X5    -2   MD0098PA00X+204742Y+057253X0785Y    R090 S3      
317T1_GND           X8011 -2   MD0098PA00X+203645Y+057257X0785Y    R270 S3      
317T1_GND           X8011 -3   MD0098PA00X+202645Y+057257X0785Y    R270 S3      
317T1_GND           X2    -2   MD0098PA00X+203645Y+057257X0785Y    R270 S3      
317T1_GND           X2    -3   MD0098PA00X+202645Y+057257X0785Y    R270 S3      
317T1_GND           X8008 -3   MD0098PA00X+201545Y+057239X0785Y    R090 S3      
317T1_GND           X25   -3   MD0098PA00X+201545Y+057239X0785Y    R090 S3      
317T1_GND           X8008 -2   MD0098PA00X+200545Y+057239X0785Y    R090 S3      
317T1_GND           X8027 -2   MD0098PA00X+199448Y+057239X0785Y    R270 S3      
317T1_GND           X9    -2   MD0098PA00X+199448Y+057239X0785Y    R270 S3      
317T1_GND           X25   -2   MD0098PA00X+200545Y+057239X0785Y    R090 S3      
317T1_GND           X8027 -3   MD0098PA00X+198448Y+057239X0785Y    R270 S3      
317T1_GND           X9    -3   MD0098PA00X+198448Y+057239X0785Y    R270 S3      
317T1_GND           X8003 -3   MD0098PA00X+197336Y+057238X0785Y    R090 S3      
317T1_GND           X28   -3   MD0098PA00X+197336Y+057238X0785Y    R090 S3      
317T1_GND           X8003 -2   MD0098PA00X+196336Y+057238X0785Y    R090 S3      
317T1_GND           X8028 -2   MD0098PA00X+195240Y+057242X0785Y    R270 S3      
317T1_GND           X4    -2   MD0098PA00X+195240Y+057242X0785Y    R270 S3      
317T1_GND           X28   -2   MD0098PA00X+196336Y+057238X0785Y    R090 S3      
317T1_GND           X8028 -3   MD0098PA00X+194240Y+057242X0785Y    R270 S3      
317T1_GND           X4    -3   MD0098PA00X+194240Y+057242X0785Y    R270 S3      
317T1_GND           X8010 -2   MD0098PA00X+192140Y+057224X0785Y    R090 S3      
317T1_GND           X8010 -3   MD0098PA00X+193140Y+057224X0785Y    R090 S3      
317T1_GND           X6    -2   MD0098PA00X+192140Y+057224X0785Y    R090 S3      
317T1_GND           X6    -3   MD0098PA00X+193140Y+057224X0785Y    R090 S3      
317T1_GND           X8012 -2   MD0098PA00X+191028Y+057223X0785Y    R270 S3      
317T1_GND           X8012 -3   MD0098PA00X+190028Y+057223X0785Y    R270 S3      
317T1_GND           DB2   -1   MD0670PA00X+188771Y+046368X0850Y         S3      
317T1_GND           DB5   -1   MD0670PA00X+186679Y+046339X0850Y         S3      
317T1_GND           DB12  -1   MD0670PA00X+207613Y+042401X0850Y    R180 S3      
317T1_GND           DB10  -1   MD0670PA00X+188734Y+042401X0850Y    R180 S3      
317T1_GND           DB16  -1   MD0670PA00X+207701Y+009513X0850Y         S3      
317T1_GND           DB9   -1   MD0670PA00X+188686Y+009411X0850Y         S3      
317T1_GND           X8001 -2   MD0098PA00X+205742Y-003967X0785Y    R270 S3      
317T1_GND           X8001 -3   MD0098PA00X+204742Y-003967X0785Y    R270 S3      
317T1_GND           X8005 -2   MD0098PA00X+202645Y-003963X0785Y    R090 S3      
317T1_GND           X8005 -3   MD0098PA00X+203645Y-003963X0785Y    R090 S3      
317T1_GND           X8002 -2   MD0098PA00X+201545Y-003981X0785Y    R270 S3      
317T1_GND           X8002 -3   MD0098PA00X+200545Y-003981X0785Y    R270 S3      
317T1_GND           X8025 -3   MD0098PA00X+199448Y-003981X0785Y    R090 S3      
317T1_GND           X8025 -2   MD0098PA00X+198448Y-003981X0785Y    R090 S3      
317T1_GND           X8009 -2   MD0098PA00X+197336Y-003982X0785Y    R270 S3      
317T1_GND           X8009 -3   MD0098PA00X+196336Y-003982X0785Y    R270 S3      
317T1_GND           X8026 -3   MD0098PA00X+195240Y-003978X0785Y    R090 S3      
317T1_GND           X8026 -2   MD0098PA00X+194240Y-003978X0785Y    R090 S3      
317T1_GND           X8004 -2   MD0098PA00X+193140Y-003996X0785Y    R270 S3      
317T1_GND           X8004 -3   MD0098PA00X+192140Y-003996X0785Y    R270 S3      
317T1_GND           X8006 -3   MD0098PA00X+191028Y-003997X0785Y    R090 S3      
317T1_GND           X8006 -2   MD0098PA00X+190028Y-003997X0785Y    R090 S3      
327m2026            U212  -10         A01X+052998Y+022788X0160Y0540R270 S1      
327m2026            R6102 -2          A01X+054341Y+022644X0198Y0197R180 S1      
317m2026            VIA   -    M      A01X+053861Y+022788X0200Y    R180 S2      
017m2026            VIA   -    M      A18X+053861Y+022788X0260Y    R180 S2      
017m2026                  -    MD0100PA00X+053861Y+022788                       
327m2027            U160  -10         A01X+045193Y+022520X0160Y0540R270 S1      
327m2027            R6101 -2          A01X+046582Y+022276X0198Y0197R180 S1      
317m2027            VIA   -    M      A01X+046057Y+022520X0200Y    R180 S2      
017m2027            VIA   -    M      A18X+046057Y+022520X0260Y    R180 S2      
017m2027                  -    MD0100PA00X+046057Y+022520                       
317m2028            VIA   -    M      A01X+181728Y+018062X0200Y    R270 S2      
017m2028            VIA   -    M      A18X+181728Y+018062X0260Y    R270 S2      
017m2028                  -    MD0100PA00X+181728Y+018062                       
327m2028            R6099 -1   M      A01X+181171Y+018062X0198Y0197R270 S1      
327m2028            PU9   -2          A01X+180650Y+019416X0110Y0240R270 S1      
327m2028            PR8073-2          A18X+181420Y+017087X0198Y0197R180 S2      
327m2029            VIA   -           A01X+004037Y+076833X0300Y         S1      
327m2029            R1837 -3          A01X+005077Y+077586X0160Y0440     S1      
327m2030            VIA   -           A01X+004037Y+076212X0300Y         S1      
327m2030            R1837 -4          A01X+005077Y+075460X0160Y0440     S1      
327m2031            VIA   -           A01X+176281Y+067750X0300Y    R090 S1      
327m2031            R1838 -3          A01X+178566Y+070908X0160Y0440R270 S1      
327m2032            VIA   -           A01X+175660Y+067750X0300Y    R090 S1      
327m2032            R1838 -4          A01X+176440Y+070908X0160Y0440R270 S1      
317m2033            VIA   -    M      A01X+050800Y+022017X0200Y    R270 S2      
017m2033            VIA   -    M      A18X+050800Y+022017X0260Y    R270 S2      
017m2033                  -    MD0100PA00X+050800Y+022017                       
327m2033            R6103 -1          A01X+050435Y+022017X0198Y0197R180 S1      
327m2033            U152  -5          A01X+051050Y+021683X0070Y0320R180 S1      
327m2034            VIA   -    M      A01X+091026Y+060075X0300Y         S1      
327m2034            U13   -6          A01X+091689Y+060219X0140Y0520R090 S1      
327m2034            R6105 -1          A01X+090538Y+060218X0198Y0197R180 S1      
327m2035            VIA   -    M      A01X+091038Y+060669X0300Y         S1      
327m2035            U13   -5          A01X+091689Y+060475X0140Y0520R090 S1      
327m2035            R6104 -2          A01X+090536Y+060692X0198Y0197     S1      
327m2036            VIA   -    M      A18X+157004Y+135270X0260Y         S2      
327m2036            U101  -4          A18X+158760Y+135177X0220Y0530R090 S2      
327m2036            R943  -2   M      A18X+158092Y+135177X0198Y0197R270 S2      
327m2036            R6100 -1          A18X+156891Y+135610X0198Y0197R270 S2      
327DELTA_L_GND_1    J8068 -3   M      A18X+173538Y-003421X0850Y1528     S2      
327DELTA_L_GND_1    J66   -3   M      A01X+173538Y-002421X0850Y1528R180 S1      
327DELTA_L_GND_1    J74   -3   M      A18X+153332Y-003421X0850Y1528R180 S2      
327DELTA_L_GND_1    J72   -3   M      A01X+153332Y-002421X0850Y1528     S1      
327DELTA_L_GND_1    J117  -3   M      A18X+144208Y+000999X0850Y1528     S2      
327DELTA_L_GND_1    J63   -3   M      A01X+144208Y+001999X0850Y1528R180 S1      
327DELTA_L_GND_1    J8067 -3   M      A01X+144208Y-000001X0850Y1528R180 S1      
327DELTA_L_GND_1    J64   -3   M      A18X+144208Y-001001X0850Y1528     S2      
327DELTA_L_GND_1    J116  -3   M      A18X+144208Y-003001X0850Y1528     S2      
327DELTA_L_GND_1    J65   -3   M      A01X+144208Y-002001X0850Y1528R180 S1      
327DELTA_L_GND_1    J115  -3   M      A18X+124002Y+000999X0850Y1528R180 S2      
327DELTA_L_GND_1    J8069 -3   M      A01X+124002Y+001999X0850Y1528     S1      
327DELTA_L_GND_1    J73   -3   M      A01X+124002Y-000001X0850Y1528     S1      
327DELTA_L_GND_1    J70   -3   M      A18X+124002Y-001001X0850Y1528R180 S2      
327DELTA_L_GND_1    J114  -3   M      A18X+124002Y-003001X0850Y1528R180 S2      
327DELTA_L_GND_1    J71   -3   M      A01X+124002Y-002001X0850Y1528     S1      
327DELTA_L_GND_1    J86   -3   M      A18X+118322Y+000999X0850Y1528     S2      
327DELTA_L_GND_1    J84   -3   M      A01X+118322Y+001999X0850Y1528R180 S1      
327DELTA_L_GND_1    J81   -3   M      A01X+118322Y-000001X0850Y1528R180 S1      
327DELTA_L_GND_1    J119  -3   M      A18X+118322Y-001001X0850Y1528     S2      
327DELTA_L_GND_1    J82   -3   M      A18X+118322Y-003001X0850Y1528     S2      
327DELTA_L_GND_1    J85   -3   M      A01X+118322Y-002001X0850Y1528R180 S1      
327DELTA_L_GND_1    J80   -3   M      A18X+083650Y+000999X0850Y1528R180 S2      
327DELTA_L_GND_1    J78   -3   M      A01X+083650Y+001999X0850Y1528     S1      
327DELTA_L_GND_1    J75   -3   M      A01X+083650Y-000001X0850Y1528     S1      
327DELTA_L_GND_1    J121  -3   M      A18X+083650Y-001001X0850Y1528R180 S2      
327DELTA_L_GND_1    J76   -3   M      A18X+083650Y-003001X0850Y1528R180 S2      
327DELTA_L_GND_1    J79   -3   M      A01X+083650Y-002001X0850Y1528     S1      
327DELTA_L_GND_1    J120  -3   M      A18X+073174Y-001387X0850Y1528     S2      
327DELTA_L_GND_1    J83   -3   M      A01X+073174Y-002387X0850Y1528R180 S1      
327DELTA_L_GND_1    J118  -3   M      A18X+038502Y-001387X0850Y1528R180 S2      
327DELTA_L_GND_1    J77   -3   M      A01X+038502Y-002387X0850Y1528     S1      
317DELTA_L_GND_1    VIA   -    MD0100PA00X+173866Y-002254X0200Y         S0      
317DELTA_L_GND_1    VIA   -    MD0100PA00X+173867Y-002506X0200Y         S0      
317DELTA_L_GND_1    VIA   -    MD0100PA00X+173863Y-001751X0200Y         S0      
317DELTA_L_GND_1    VIA   -    MD0100PA00X+173864Y-002003X0200Y         S0      
317DELTA_L_GND_1    VIA   -    MD0100PA00X+173864Y-003044X0200Y         S0      
317DELTA_L_GND_1    VIA   -    MD0100PA00X+173863Y-002793X0200Y         S0      
317DELTA_L_GND_1    VIA   -    MD0100PA00X+173864Y-003840X0200Y    R180 S0      
317DELTA_L_GND_1    VIA   -    MD0100PA00X+173867Y-003337X0200Y    R180 S0      
317DELTA_L_GND_1    VIA   -    MD0100PA00X+173866Y-003588X0200Y    R180 S0      
317DELTA_L_GND_1    VIA   -    MD0100PA00X+173863Y-004091X0200Y    R180 S0      
317DELTA_L_GND_1    VIA   -    MD0100PA00X+173235Y-001882X0200Y         S0      
317DELTA_L_GND_1    VIA   -    MD0100PA00X+173538Y-001750X0200Y         S0      
317DELTA_L_GND_1    VIA   -    MD0100PA00X+173539Y-002001X0200Y         S0      
317DELTA_L_GND_1    VIA   -    MD0100PA00X+172711Y-001958X0200Y    R180 S0      
317DELTA_L_GND_1    VIA   -    MD0100PA00X+173539Y-003043X0200Y         S0      
317DELTA_L_GND_1    VIA   -    MD0100PA00X+173235Y-002924X0200Y         S0      
317DELTA_L_GND_1    VIA   -    MD0100PA00X+173537Y-002792X0200Y         S0      
317DELTA_L_GND_1    VIA   -    MD0100PA00X+173539Y-003841X0200Y    R180 S0      
317DELTA_L_GND_1    VIA   -    MD0100PA00X+173235Y-003960X0200Y    R180 S0      
317DELTA_L_GND_1    VIA   -    MD0100PA00X+172711Y-002885X0200Y         S0      
317DELTA_L_GND_1    VIA   -    MD0100PA00X+172711Y-003885X0200Y         S0      
317DELTA_L_GND_1    VIA   -    MD0100PA00X+173538Y-004092X0200Y    R180 S0      
317DELTA_L_GND_1    VIA   -    MD0100PA00X+154158Y-001958X0200Y    R180 S0      
317DELTA_L_GND_1    VIA   -    MD0100PA00X+153634Y-001882X0200Y         S0      
317DELTA_L_GND_1    VIA   -    MD0100PA00X+153332Y-001750X0200Y         S0      
317DELTA_L_GND_1    VIA   -    MD0100PA00X+153330Y-002001X0200Y         S0      
317DELTA_L_GND_1    VIA   -    MD0100PA00X+153003Y-002254X0200Y         S0      
317DELTA_L_GND_1    VIA   -    MD0100PA00X+153002Y-002506X0200Y         S0      
317DELTA_L_GND_1    VIA   -    MD0100PA00X+153006Y-001751X0200Y         S0      
317DELTA_L_GND_1    VIA   -    MD0100PA00X+153005Y-002003X0200Y         S0      
317DELTA_L_GND_1    VIA   -    MD0100PA00X+153330Y-003841X0200Y    R180 S0      
317DELTA_L_GND_1    VIA   -    MD0100PA00X+153634Y-003960X0200Y    R180 S0      
317DELTA_L_GND_1    VIA   -    MD0100PA00X+154158Y-002885X0200Y         S0      
317DELTA_L_GND_1    VIA   -    MD0100PA00X+154158Y-003885X0200Y         S0      
317DELTA_L_GND_1    VIA   -    MD0100PA00X+153330Y-003043X0200Y         S0      
317DELTA_L_GND_1    VIA   -    MD0100PA00X+153634Y-002924X0200Y         S0      
317DELTA_L_GND_1    VIA   -    MD0100PA00X+153332Y-002792X0200Y         S0      
317DELTA_L_GND_1    VIA   -    MD0100PA00X+153332Y-004092X0200Y    R180 S0      
317DELTA_L_GND_1    VIA   -    MD0100PA00X+153005Y-003840X0200Y    R180 S0      
317DELTA_L_GND_1    VIA   -    MD0100PA00X+153002Y-003337X0200Y    R180 S0      
317DELTA_L_GND_1    VIA   -    MD0100PA00X+153003Y-003588X0200Y    R180 S0      
317DELTA_L_GND_1    VIA   -    MD0100PA00X+153005Y-003044X0200Y         S0      
317DELTA_L_GND_1    VIA   -    MD0100PA00X+153006Y-002793X0200Y         S0      
317DELTA_L_GND_1    VIA   -    MD0100PA00X+153006Y-004091X0200Y    R180 S0      
317DELTA_L_GND_1    VIA   -    MD0100PA00X+144528Y+001914X0200Y         S0      
317DELTA_L_GND_1    VIA   -    MD0100PA00X+144527Y+002166X0200Y         S0      
317DELTA_L_GND_1    VIA   -    MD0100PA00X+144200Y+002419X0200Y         S0      
317DELTA_L_GND_1    VIA   -    MD0100PA00X+144198Y+002670X0200Y         S0      
317DELTA_L_GND_1    VIA   -    MD0100PA00X+144525Y+002417X0200Y         S0      
317DELTA_L_GND_1    VIA   -    MD0100PA00X+144524Y+002669X0200Y         S0      
317DELTA_L_GND_1    VIA   -    MD0100PA00X+144518Y+000616X0200Y    R180 S0      
317DELTA_L_GND_1    VIA   -    MD0100PA00X+144192Y+000614X0200Y    R180 S0      
317DELTA_L_GND_1    VIA   -    MD0100PA00X+144518Y+001616X0200Y    R180 S0      
317DELTA_L_GND_1    VIA   -    MD0100PA00X+144516Y+001364X0200Y    R180 S0      
317DELTA_L_GND_1    VIA   -    MD0100PA00X+144192Y+001614X0200Y    R180 S0      
317DELTA_L_GND_1    VIA   -    MD0100PA00X+144191Y+001363X0200Y    R180 S0      
317DELTA_L_GND_1    VIA   -    MD0100PA00X+144517Y+001005X0200Y         S0      
317DELTA_L_GND_1    VIA   -    MD0100PA00X+144191Y+001005X0200Y         S0      
317DELTA_L_GND_1    VIA   -    MD0100PA00X+144516Y+000364X0200Y    R180 S0      
317DELTA_L_GND_1    VIA   -    MD0100PA00X+144191Y+000363X0200Y    R180 S0      
317DELTA_L_GND_1    VIA   -    MD0100PA00X+144518Y-000384X0200Y    R180 S0      
317DELTA_L_GND_1    VIA   -    MD0100PA00X+144516Y-000636X0200Y    R180 S0      
317DELTA_L_GND_1    VIA   -    MD0100PA00X+144192Y-000386X0200Y    R180 S0      
317DELTA_L_GND_1    VIA   -    MD0100PA00X+144191Y-000637X0200Y    R180 S0      
317DELTA_L_GND_1    VIA   -    MD0100PA00X+144517Y+000005X0200Y         S0      
317DELTA_L_GND_1    VIA   -    MD0100PA00X+144191Y+000005X0200Y         S0      
317DELTA_L_GND_1    VIA   -    MD0100PA00X+144517Y-000995X0200Y         S0      
317DELTA_L_GND_1    VIA   -    MD0100PA00X+144191Y-000995X0200Y         S0      
317DELTA_L_GND_1    VIA   -    MD0100PA00X+144518Y-002384X0200Y    R180 S0      
317DELTA_L_GND_1    VIA   -    MD0100PA00X+144192Y-002386X0200Y    R180 S0      
317DELTA_L_GND_1    VIA   -    MD0100PA00X+144518Y-001384X0200Y    R180 S0      
317DELTA_L_GND_1    VIA   -    MD0100PA00X+144516Y-001636X0200Y    R180 S0      
317DELTA_L_GND_1    VIA   -    MD0100PA00X+144192Y-001386X0200Y    R180 S0      
317DELTA_L_GND_1    VIA   -    MD0100PA00X+144191Y-001637X0200Y    R180 S0      
317DELTA_L_GND_1    VIA   -    MD0100PA00X+144517Y-001995X0200Y         S0      
317DELTA_L_GND_1    VIA   -    MD0100PA00X+144191Y-001995X0200Y         S0      
317DELTA_L_GND_1    VIA   -    MD0100PA00X+144516Y-002636X0200Y    R180 S0      
317DELTA_L_GND_1    VIA   -    MD0100PA00X+144191Y-002637X0200Y    R180 S0      
317DELTA_L_GND_1    VIA   -    MD0100PA00X+144526Y-003426X0200Y         S0      
317DELTA_L_GND_1    VIA   -    MD0100PA00X+144528Y-003678X0200Y         S0      
317DELTA_L_GND_1    VIA   -    MD0100PA00X+144201Y-003425X0200Y         S0      
317DELTA_L_GND_1    VIA   -    MD0100PA00X+144202Y-003676X0200Y         S0      
317DELTA_L_GND_1    VIA   -    MD0100PA00X+144531Y-003144X0200Y         S0      
317DELTA_L_GND_1    VIA   -    MD0100PA00X+144529Y-002893X0200Y         S0      
317DELTA_L_GND_1    VIA   -    MD0100PA00X+143896Y+002538X0200Y         S0      
317DELTA_L_GND_1    VIA   -    MD0100PA00X+143888Y+000495X0200Y    R180 S0      
317DELTA_L_GND_1    VIA   -    MD0100PA00X+143888Y+001495X0200Y    R180 S0      
317DELTA_L_GND_1    VIA   -    MD0100PA00X+143382Y+001463X0200Y    R180 S0      
317DELTA_L_GND_1    VIA   -    MD0100PA00X+143382Y+000535X0200Y         S0      
317DELTA_L_GND_1    VIA   -    MD0100PA00X+143888Y-000505X0200Y    R180 S0      
317DELTA_L_GND_1    VIA   -    MD0100PA00X+143382Y-000465X0200Y         S0      
317DELTA_L_GND_1    VIA   -    MD0100PA00X+143888Y-002505X0200Y    R180 S0      
317DELTA_L_GND_1    VIA   -    MD0100PA00X+143888Y-001505X0200Y    R180 S0      
317DELTA_L_GND_1    VIA   -    MD0100PA00X+143382Y-001537X0200Y    R180 S0      
317DELTA_L_GND_1    VIA   -    MD0100PA00X+143382Y-002537X0200Y    R180 S0      
317DELTA_L_GND_1    VIA   -    MD0100PA00X+143898Y-003557X0200Y         S0      
317DELTA_L_GND_1    VIA   -    MD0100PA00X+143382Y-003465X0200Y         S0      
317DELTA_L_GND_1    VIA   -    MD0100PA00X+124829Y+001463X0200Y    R180 S0      
317DELTA_L_GND_1    VIA   -    MD0100PA00X+124829Y+000535X0200Y         S0      
317DELTA_L_GND_1    VIA   -    MD0100PA00X+124829Y-000465X0200Y         S0      
317DELTA_L_GND_1    VIA   -    MD0100PA00X+124829Y-002537X0200Y    R180 S0      
317DELTA_L_GND_1    VIA   -    MD0100PA00X+124829Y-001537X0200Y    R180 S0      
317DELTA_L_GND_1    VIA   -    MD0100PA00X+124829Y-003465X0200Y         S0      
317DELTA_L_GND_1    VIA   -    MD0100PA00X+124018Y+002425X0200Y         S0      
317DELTA_L_GND_1    VIA   -    MD0100PA00X+124019Y+002676X0200Y         S0      
317DELTA_L_GND_1    VIA   -    MD0100PA00X+124322Y+002544X0200Y         S0      
317DELTA_L_GND_1    VIA   -    MD0100PA00X+123693Y+002424X0200Y         S0      
317DELTA_L_GND_1    VIA   -    MD0100PA00X+123694Y+002675X0200Y         S0      
317DELTA_L_GND_1    VIA   -    MD0100PA00X+123690Y+001921X0200Y         S0      
317DELTA_L_GND_1    VIA   -    MD0100PA00X+123691Y+002172X0200Y         S0      
317DELTA_L_GND_1    VIA   -    MD0100PA00X+124018Y+000383X0200Y         S0      
317DELTA_L_GND_1    VIA   -    MD0100PA00X+124322Y+000503X0200Y         S0      
317DELTA_L_GND_1    VIA   -    MD0100PA00X+124020Y+000635X0200Y         S0      
317DELTA_L_GND_1    VIA   -    MD0100PA00X+124019Y+001005X0200Y         S0      
317DELTA_L_GND_1    VIA   -    MD0100PA00X+124020Y+001635X0200Y         S0      
317DELTA_L_GND_1    VIA   -    MD0100PA00X+124322Y+001503X0200Y         S0      
317DELTA_L_GND_1    VIA   -    MD0100PA00X+124018Y+001383X0200Y         S0      
317DELTA_L_GND_1    VIA   -    MD0100PA00X+123693Y+000382X0200Y         S0      
317DELTA_L_GND_1    VIA   -    MD0100PA00X+123694Y+000633X0200Y         S0      
317DELTA_L_GND_1    VIA   -    MD0100PA00X+123693Y+001005X0200Y         S0      
317DELTA_L_GND_1    VIA   -    MD0100PA00X+123694Y+001633X0200Y         S0      
317DELTA_L_GND_1    VIA   -    MD0100PA00X+123693Y+001382X0200Y         S0      
317DELTA_L_GND_1    VIA   -    MD0100PA00X+124018Y-000617X0200Y         S0      
317DELTA_L_GND_1    VIA   -    MD0100PA00X+124322Y-000497X0200Y         S0      
317DELTA_L_GND_1    VIA   -    MD0100PA00X+124020Y-000365X0200Y         S0      
317DELTA_L_GND_1    VIA   -    MD0100PA00X+124019Y+000005X0200Y         S0      
317DELTA_L_GND_1    VIA   -    MD0100PA00X+124019Y-000995X0200Y         S0      
317DELTA_L_GND_1    VIA   -    MD0100PA00X+123693Y-000618X0200Y         S0      
317DELTA_L_GND_1    VIA   -    MD0100PA00X+123694Y-000367X0200Y         S0      
317DELTA_L_GND_1    VIA   -    MD0100PA00X+123693Y+000005X0200Y         S0      
317DELTA_L_GND_1    VIA   -    MD0100PA00X+123693Y-000995X0200Y         S0      
317DELTA_L_GND_1    VIA   -    MD0100PA00X+124317Y-002502X0200Y         S0      
317DELTA_L_GND_1    VIA   -    MD0100PA00X+124014Y-002370X0200Y         S0      
317DELTA_L_GND_1    VIA   -    MD0100PA00X+124018Y-001617X0200Y         S0      
317DELTA_L_GND_1    VIA   -    MD0100PA00X+124322Y-001497X0200Y         S0      
317DELTA_L_GND_1    VIA   -    MD0100PA00X+124020Y-001365X0200Y         S0      
317DELTA_L_GND_1    VIA   -    MD0100PA00X+124019Y-001995X0200Y         S0      
317DELTA_L_GND_1    VIA   -    MD0100PA00X+124013Y-002621X0200Y         S0      
317DELTA_L_GND_1    VIA   -    MD0100PA00X+123689Y-002371X0200Y         S0      
317DELTA_L_GND_1    VIA   -    MD0100PA00X+123693Y-001618X0200Y         S0      
317DELTA_L_GND_1    VIA   -    MD0100PA00X+123694Y-001367X0200Y         S0      
317DELTA_L_GND_1    VIA   -    MD0100PA00X+123693Y-001995X0200Y         S0      
317DELTA_L_GND_1    VIA   -    MD0100PA00X+123688Y-002623X0200Y         S0      
317DELTA_L_GND_1    VIA   -    MD0100PA00X+124008Y-003685X0200Y         S0      
317DELTA_L_GND_1    VIA   -    MD0100PA00X+124312Y-003565X0200Y         S0      
317DELTA_L_GND_1    VIA   -    MD0100PA00X+124010Y-003433X0200Y         S0      
317DELTA_L_GND_1    VIA   -    MD0100PA00X+123681Y-002896X0200Y         S0      
317DELTA_L_GND_1    VIA   -    MD0100PA00X+123680Y-003148X0200Y         S0      
317DELTA_L_GND_1    VIA   -    MD0100PA00X+123683Y-003686X0200Y         S0      
317DELTA_L_GND_1    VIA   -    MD0100PA00X+123684Y-003435X0200Y         S0      
317DELTA_L_GND_1    VIA   -    MD0100PA00X+118638Y+002669X0200Y         S0      
317DELTA_L_GND_1    VIA   -    MD0100PA00X+118639Y+002417X0200Y         S0      
317DELTA_L_GND_1    VIA   -    MD0100PA00X+118641Y+002166X0200Y         S0      
317DELTA_L_GND_1    VIA   -    MD0100PA00X+118642Y+001914X0200Y         S0      
317DELTA_L_GND_1    VIA   -    MD0100PA00X+118639Y+000381X0200Y         S0      
317DELTA_L_GND_1    VIA   -    MD0100PA00X+118638Y+000632X0200Y         S0      
317DELTA_L_GND_1    VIA   -    MD0100PA00X+118631Y+000993X0200Y    R180 S0      
317DELTA_L_GND_1    VIA   -    MD0100PA00X+118639Y+001381X0200Y         S0      
317DELTA_L_GND_1    VIA   -    MD0100PA00X+118638Y+001632X0200Y         S0      
317DELTA_L_GND_1    VIA   -    MD0100PA00X+118638Y-000368X0200Y         S0      
317DELTA_L_GND_1    VIA   -    MD0100PA00X+118639Y-000619X0200Y         S0      
317DELTA_L_GND_1    VIA   -    MD0100PA00X+118631Y-000007X0200Y    R180 S0      
317DELTA_L_GND_1    VIA   -    MD0100PA00X+118631Y-001007X0200Y    R180 S0      
317DELTA_L_GND_1    VIA   -    MD0100PA00X+118638Y-002368X0200Y         S0      
317DELTA_L_GND_1    VIA   -    MD0100PA00X+118639Y-001619X0200Y         S0      
317DELTA_L_GND_1    VIA   -    MD0100PA00X+118638Y-001368X0200Y         S0      
317DELTA_L_GND_1    VIA   -    MD0100PA00X+118631Y-002007X0200Y    R180 S0      
317DELTA_L_GND_1    VIA   -    MD0100PA00X+118639Y-002619X0200Y         S0      
317DELTA_L_GND_1    VIA   -    MD0100PA00X+118643Y-002893X0200Y         S0      
317DELTA_L_GND_1    VIA   -    MD0100PA00X+118645Y-003144X0200Y         S0      
317DELTA_L_GND_1    VIA   -    MD0100PA00X+118642Y-003678X0200Y         S0      
317DELTA_L_GND_1    VIA   -    MD0100PA00X+118640Y-003426X0200Y         S0      
317DELTA_L_GND_1    VIA   -    MD0100PA00X+118010Y+002538X0200Y         S0      
317DELTA_L_GND_1    VIA   -    MD0100PA00X+118312Y+002670X0200Y         S0      
317DELTA_L_GND_1    VIA   -    MD0100PA00X+118314Y+002419X0200Y         S0      
317DELTA_L_GND_1    VIA   -    MD0100PA00X+117496Y+002463X0200Y    R180 S0      
317DELTA_L_GND_1    VIA   -    MD0100PA00X+118314Y+000382X0200Y         S0      
317DELTA_L_GND_1    VIA   -    MD0100PA00X+118312Y+000634X0200Y         S0      
317DELTA_L_GND_1    VIA   -    MD0100PA00X+118010Y+000502X0200Y         S0      
317DELTA_L_GND_1    VIA   -    MD0100PA00X+118305Y+000993X0200Y    R180 S0      
317DELTA_L_GND_1    VIA   -    MD0100PA00X+118314Y+001382X0200Y         S0      
317DELTA_L_GND_1    VIA   -    MD0100PA00X+118312Y+001634X0200Y         S0      
317DELTA_L_GND_1    VIA   -    MD0100PA00X+118010Y+001502X0200Y         S0      
317DELTA_L_GND_1    VIA   -    MD0100PA00X+117496Y+001535X0200Y         S0      
317DELTA_L_GND_1    VIA   -    MD0100PA00X+117496Y+000535X0200Y         S0      
317DELTA_L_GND_1    VIA   -    MD0100PA00X+118010Y-000498X0200Y         S0      
317DELTA_L_GND_1    VIA   -    MD0100PA00X+118312Y-000366X0200Y         S0      
317DELTA_L_GND_1    VIA   -    MD0100PA00X+118314Y-000618X0200Y         S0      
317DELTA_L_GND_1    VIA   -    MD0100PA00X+118305Y-000007X0200Y    R180 S0      
317DELTA_L_GND_1    VIA   -    MD0100PA00X+118305Y-001007X0200Y    R180 S0      
317DELTA_L_GND_1    VIA   -    MD0100PA00X+117496Y-000537X0200Y    R180 S0      
317DELTA_L_GND_1    VIA   -    MD0100PA00X+118010Y-002498X0200Y         S0      
317DELTA_L_GND_1    VIA   -    MD0100PA00X+118312Y-002366X0200Y         S0      
317DELTA_L_GND_1    VIA   -    MD0100PA00X+118314Y-001618X0200Y         S0      
317DELTA_L_GND_1    VIA   -    MD0100PA00X+118312Y-001366X0200Y         S0      
317DELTA_L_GND_1    VIA   -    MD0100PA00X+118010Y-001498X0200Y         S0      
317DELTA_L_GND_1    VIA   -    MD0100PA00X+118305Y-002007X0200Y    R180 S0      
317DELTA_L_GND_1    VIA   -    MD0100PA00X+118314Y-002618X0200Y         S0      
317DELTA_L_GND_1    VIA   -    MD0100PA00X+117496Y-001537X0200Y    R180 S0      
317DELTA_L_GND_1    VIA   -    MD0100PA00X+117496Y-002465X0200Y         S0      
317DELTA_L_GND_1    VIA   -    MD0100PA00X+118316Y-003676X0200Y         S0      
317DELTA_L_GND_1    VIA   -    MD0100PA00X+118315Y-003425X0200Y         S0      
317DELTA_L_GND_1    VIA   -    MD0100PA00X+118012Y-003557X0200Y         S0      
317DELTA_L_GND_1    VIA   -    MD0100PA00X+084477Y+002463X0200Y    R180 S0      
317DELTA_L_GND_1    VIA   -    MD0100PA00X+084477Y+001535X0200Y         S0      
317DELTA_L_GND_1    VIA   -    MD0100PA00X+084477Y+000535X0200Y         S0      
317DELTA_L_GND_1    VIA   -    MD0100PA00X+084477Y-000537X0200Y    R180 S0      
317DELTA_L_GND_1    VIA   -    MD0100PA00X+084477Y-001537X0200Y    R180 S0      
317DELTA_L_GND_1    VIA   -    MD0100PA00X+084477Y-002465X0200Y         S0      
317DELTA_L_GND_1    VIA   -    MD0100PA00X+083339Y+002172X0200Y         S0      
317DELTA_L_GND_1    VIA   -    MD0100PA00X+083338Y+001921X0200Y         S0      
317DELTA_L_GND_1    VIA   -    MD0100PA00X+083342Y+002675X0200Y         S0      
317DELTA_L_GND_1    VIA   -    MD0100PA00X+083970Y+002544X0200Y         S0      
317DELTA_L_GND_1    VIA   -    MD0100PA00X+083341Y+002424X0200Y         S0      
317DELTA_L_GND_1    VIA   -    MD0100PA00X+083667Y+002676X0200Y         S0      
317DELTA_L_GND_1    VIA   -    MD0100PA00X+083666Y+002425X0200Y         S0      
317DELTA_L_GND_1    VIA   -    MD0100PA00X+083666Y+000383X0200Y         S0      
317DELTA_L_GND_1    VIA   -    MD0100PA00X+083341Y+000382X0200Y         S0      
317DELTA_L_GND_1    VIA   -    MD0100PA00X+083970Y+000503X0200Y         S0      
317DELTA_L_GND_1    VIA   -    MD0100PA00X+083342Y+000633X0200Y         S0      
317DELTA_L_GND_1    VIA   -    MD0100PA00X+083668Y+000635X0200Y         S0      
317DELTA_L_GND_1    VIA   -    MD0100PA00X+083341Y+001005X0200Y         S0      
317DELTA_L_GND_1    VIA   -    MD0100PA00X+083667Y+001005X0200Y         S0      
317DELTA_L_GND_1    VIA   -    MD0100PA00X+083666Y+001383X0200Y         S0      
317DELTA_L_GND_1    VIA   -    MD0100PA00X+083341Y+001382X0200Y         S0      
317DELTA_L_GND_1    VIA   -    MD0100PA00X+083970Y+001503X0200Y         S0      
317DELTA_L_GND_1    VIA   -    MD0100PA00X+083342Y+001633X0200Y         S0      
317DELTA_L_GND_1    VIA   -    MD0100PA00X+083668Y+001635X0200Y         S0      
317DELTA_L_GND_1    VIA   -    MD0100PA00X+083666Y-000617X0200Y         S0      
317DELTA_L_GND_1    VIA   -    MD0100PA00X+083341Y-000618X0200Y         S0      
317DELTA_L_GND_1    VIA   -    MD0100PA00X+083970Y-000497X0200Y         S0      
317DELTA_L_GND_1    VIA   -    MD0100PA00X+083342Y-000367X0200Y         S0      
317DELTA_L_GND_1    VIA   -    MD0100PA00X+083668Y-000365X0200Y         S0      
317DELTA_L_GND_1    VIA   -    MD0100PA00X+083667Y-000995X0200Y         S0      
317DELTA_L_GND_1    VIA   -    MD0100PA00X+083341Y-000995X0200Y         S0      
317DELTA_L_GND_1    VIA   -    MD0100PA00X+083667Y+000005X0200Y         S0      
317DELTA_L_GND_1    VIA   -    MD0100PA00X+083341Y+000005X0200Y         S0      
317DELTA_L_GND_1    VIA   -    MD0100PA00X+083970Y-002497X0200Y         S0      
317DELTA_L_GND_1    VIA   -    MD0100PA00X+083342Y-002367X0200Y         S0      
317DELTA_L_GND_1    VIA   -    MD0100PA00X+083668Y-002365X0200Y         S0      
317DELTA_L_GND_1    VIA   -    MD0100PA00X+083667Y-001995X0200Y         S0      
317DELTA_L_GND_1    VIA   -    MD0100PA00X+083341Y-001995X0200Y         S0      
317DELTA_L_GND_1    VIA   -    MD0100PA00X+083668Y-001365X0200Y         S0      
317DELTA_L_GND_1    VIA   -    MD0100PA00X+083342Y-001367X0200Y         S0      
317DELTA_L_GND_1    VIA   -    MD0100PA00X+083970Y-001497X0200Y         S0      
317DELTA_L_GND_1    VIA   -    MD0100PA00X+083341Y-001618X0200Y         S0      
317DELTA_L_GND_1    VIA   -    MD0100PA00X+083666Y-001617X0200Y         S0      
317DELTA_L_GND_1    VIA   -    MD0100PA00X+083666Y-002617X0200Y         S0      
317DELTA_L_GND_1    VIA   -    MD0100PA00X+083341Y-002618X0200Y         S0      
317DELTA_L_GND_1    VIA   -    MD0100PA00X+083663Y-002912X0200Y    R180 S0      
317DELTA_L_GND_1    VIA   -    MD0100PA00X+083664Y-003163X0200Y    R180 S0      
317DELTA_L_GND_1    VIA   -    MD0100PA00X+083338Y-002910X0200Y    R180 S0      
317DELTA_L_GND_1    VIA   -    MD0100PA00X+083339Y-003162X0200Y    R180 S0      
317DELTA_L_GND_1    VIA   -    MD0100PA00X+083666Y-003415X0200Y    R180 S0      
317DELTA_L_GND_1    VIA   -    MD0100PA00X+083667Y-003666X0200Y    R180 S0      
317DELTA_L_GND_1    VIA   -    MD0100PA00X+083341Y-003413X0200Y    R180 S0      
317DELTA_L_GND_1    VIA   -    MD0100PA00X+083970Y-003534X0200Y    R180 S0      
317DELTA_L_GND_1    VIA   -    MD0100PA00X+083342Y-003665X0200Y    R180 S0      
317DELTA_L_GND_1    VIA   -    MD0100PA00X+073176Y-000967X0200Y         S0      
317DELTA_L_GND_1    VIA   -    MD0100PA00X+073174Y-000716X0200Y         S0      
317DELTA_L_GND_1    VIA   -    MD0100PA00X+073501Y-000969X0200Y         S0      
317DELTA_L_GND_1    VIA   -    MD0100PA00X+072872Y-000848X0200Y         S0      
317DELTA_L_GND_1    VIA   -    MD0100PA00X+073500Y-000717X0200Y         S0      
317DELTA_L_GND_1    VIA   -    MD0100PA00X+073503Y-001220X0200Y         S0      
317DELTA_L_GND_1    VIA   -    MD0100PA00X+073504Y-001472X0200Y         S0      
317DELTA_L_GND_1    VIA   -    MD0100PA00X+073503Y-002554X0200Y    R180 S0      
317DELTA_L_GND_1    VIA   -    MD0100PA00X+073504Y-002302X0200Y    R180 S0      
317DELTA_L_GND_1    VIA   -    MD0100PA00X+073174Y-001758X0200Y         S0      
317DELTA_L_GND_1    VIA   -    MD0100PA00X+073500Y-001759X0200Y         S0      
317DELTA_L_GND_1    VIA   -    MD0100PA00X+072872Y-001890X0200Y         S0      
317DELTA_L_GND_1    VIA   -    MD0100PA00X+073501Y-002010X0200Y         S0      
317DELTA_L_GND_1    VIA   -    MD0100PA00X+073176Y-002009X0200Y         S0      
317DELTA_L_GND_1    VIA   -    MD0100PA00X+072872Y-002926X0200Y    R180 S0      
317DELTA_L_GND_1    VIA   -    MD0100PA00X+073501Y-002806X0200Y    R180 S0      
317DELTA_L_GND_1    VIA   -    MD0100PA00X+073176Y-002807X0200Y    R180 S0      
317DELTA_L_GND_1    VIA   -    MD0100PA00X+073500Y-003057X0200Y    R180 S0      
317DELTA_L_GND_1    VIA   -    MD0100PA00X+073174Y-003058X0200Y    R180 S0      
317DELTA_L_GND_1    VIA   -    MD0100PA00X+072348Y-000923X0200Y    R180 S0      
317DELTA_L_GND_1    VIA   -    MD0100PA00X+072348Y-001923X0200Y    R180 S0      
317DELTA_L_GND_1    VIA   -    MD0100PA00X+072348Y-002851X0200Y         S0      
317DELTA_L_GND_1    VIA   -    MD0100PA00X+039329Y-000923X0200Y    R180 S0      
317DELTA_L_GND_1    VIA   -    MD0100PA00X+038174Y-001220X0200Y         S0      
317DELTA_L_GND_1    VIA   -    MD0100PA00X+038177Y-000717X0200Y         S0      
317DELTA_L_GND_1    VIA   -    MD0100PA00X+038805Y-000848X0200Y         S0      
317DELTA_L_GND_1    VIA   -    MD0100PA00X+038176Y-000969X0200Y         S0      
317DELTA_L_GND_1    VIA   -    MD0100PA00X+038502Y-000716X0200Y         S0      
317DELTA_L_GND_1    VIA   -    MD0100PA00X+038501Y-000967X0200Y         S0      
317DELTA_L_GND_1    VIA   -    MD0100PA00X+039329Y-001851X0200Y         S0      
317DELTA_L_GND_1    VIA   -    MD0100PA00X+038172Y-001472X0200Y         S0      
317DELTA_L_GND_1    VIA   -    MD0100PA00X+038501Y-002009X0200Y         S0      
317DELTA_L_GND_1    VIA   -    MD0100PA00X+038176Y-002010X0200Y         S0      
317DELTA_L_GND_1    VIA   -    MD0100PA00X+038805Y-001890X0200Y         S0      
317DELTA_L_GND_1    VIA   -    MD0100PA00X+038177Y-001759X0200Y         S0      
317DELTA_L_GND_1    VIA   -    MD0100PA00X+038502Y-001758X0200Y         S0      
317DELTA_L_GND_1    VIA   -    MD0100PA00X+038172Y-002302X0200Y    R180 S0      
317DELTA_L_GND_1    VIA   -    MD0100PA00X+038174Y-002554X0200Y    R180 S0      
317DELTA_L_GND_1    VIA   -    MD0100PA00X+039329Y-002851X0200Y         S0      
317DELTA_L_GND_1    VIA   -    MD0100PA00X+038501Y-002807X0200Y    R180 S0      
317DELTA_L_GND_1    VIA   -    MD0100PA00X+038176Y-002806X0200Y    R180 S0      
317DELTA_L_GND_1    VIA   -    MD0100PA00X+038805Y-002926X0200Y    R180 S0      
317DELTA_L_GND_1    VIA   -    MD0100PA00X+038502Y-003058X0200Y    R180 S0      
317DELTA_L_GND_1    VIA   -    MD0100PA00X+038177Y-003057X0200Y    R180 S0      
327m2037            J63   -1          A01X+143883Y+001900X0120Y0200R090 S1      
327m2037            J8069 -2          A01X+124327Y+001900X0120Y0200R270 S1      
327m2038            J63   -2          A01X+143883Y+002097X0120Y0200R090 S1      
327m2038            J8069 -1          A01X+124327Y+002097X0120Y0200R270 S1      
327m2039            J117  -2          A18X+143883Y+000900X0120Y0200R090 S2      
327m2039            J115  -1          A18X+124327Y+000900X0120Y0200R270 S2      
317m2039            VIA   -    MD0100PA18X+143626Y+000829X0200Y    R180 S0      
317m2039            VIA   -    MD0100PA18X+124584Y+000829X0200Y         S0      
327m2040            J117  -1          A18X+143883Y+001097X0120Y0200R090 S2      
327m2040            J115  -2          A18X+124327Y+001097X0120Y0200R270 S2      
317m2040            VIA   -    MD0100PA18X+143626Y+001169X0200Y    R180 S0      
317m2040            VIA   -    MD0100PA18X+124584Y+001169X0200Y         S0      
327m2041            J116  -2          A18X+143883Y-003100X0120Y0200R090 S2      
327m2041            J114  -1          A18X+124327Y-003100X0120Y0200R270 S2      
317m2041            VIA   -    MD0100PA18X+143626Y-003171X0200Y    R180 S0      
317m2041            VIA   -    MD0100PA18X+124584Y-003171X0200Y         S0      
327m2042            J116  -1          A18X+143883Y-002903X0120Y0200R090 S2      
327m2042            J114  -2          A18X+124327Y-002903X0120Y0200R270 S2      
317m2042            VIA   -    MD0100PA18X+143626Y-002831X0200Y    R180 S0      
317m2042            VIA   -    MD0100PA18X+124584Y-002831X0200Y         S0      
327m2043            J8068 -1          A18X+173212Y-003323X0120Y0200R090 S2      
327m2043            J74   -2          A18X+153657Y-003323X0120Y0200R270 S2      
317m2043            VIA   -    MD0100PA18X+172956Y-003251X0200Y         S0      
317m2043            VIA   -    MD0100PA18X+153913Y-003251X0200Y         S0      
327m2044            J8068 -2          A18X+173212Y-003520X0120Y0200R090 S2      
327m2044            J74   -1          A18X+153657Y-003520X0120Y0200R270 S2      
317m2044            VIA   -    MD0100PA18X+172956Y-003591X0200Y         S0      
317m2044            VIA   -    MD0100PA18X+153913Y-003591X0200Y         S0      
327m2045            J8067 -1          A01X+143883Y-000100X0120Y0200R090 S1      
327m2045            J73   -2          A01X+124327Y-000100X0120Y0200R270 S1      
317m2045            VIA   -    MD0100PA01X+143626Y-000171X0200Y    R180 S0      
317m2045            VIA   -    MD0100PA01X+124584Y-000171X0200Y         S0      
327m2046            J8067 -2          A01X+143883Y+000097X0120Y0200R090 S1      
327m2046            J73   -1          A01X+124327Y+000097X0120Y0200R270 S1      
317m2046            VIA   -    MD0100PA01X+143626Y+000169X0200Y    R180 S0      
317m2046            VIA   -    MD0100PA01X+124584Y+000169X0200Y         S0      
327m2047            J66   -1          A01X+173212Y-002520X0120Y0200R090 S1      
327m2047            J72   -2          A01X+153657Y-002520X0120Y0200R270 S1      
317m2047            VIA   -    MD0100PA01X+172956Y-002591X0200Y         S0      
317m2047            VIA   -    MD0100PA01X+153913Y-002591X0200Y         S0      
327m2048            J66   -2          A01X+173212Y-002323X0120Y0200R090 S1      
327m2048            J72   -1          A01X+153657Y-002323X0120Y0200R270 S1      
317m2048            VIA   -    MD0100PA01X+172956Y-002251X0200Y         S0      
317m2048            VIA   -    MD0100PA01X+153913Y-002251X0200Y         S0      
327m2049            J65   -1          A01X+143883Y-002100X0120Y0200R090 S1      
327m2049            J71   -2          A01X+124327Y-002100X0120Y0200R270 S1      
317m2049            VIA   -    MD0100PA01X+143626Y-002171X0200Y    R180 S0      
317m2049            VIA   -    MD0100PA01X+124584Y-002171X0200Y         S0      
327m2050            J65   -2          A01X+143883Y-001903X0120Y0200R090 S1      
327m2050            J71   -1          A01X+124327Y-001903X0120Y0200R270 S1      
317m2050            VIA   -    MD0100PA01X+143626Y-001831X0200Y    R180 S0      
317m2050            VIA   -    MD0100PA01X+124584Y-001831X0200Y         S0      
327m2051            J64   -1          A18X+143883Y-000903X0120Y0200R090 S2      
327m2051            J70   -2          A18X+124327Y-000903X0120Y0200R270 S2      
327m2052            J64   -2          A18X+143883Y-001100X0120Y0200R090 S2      
327m2052            J70   -1          A18X+124327Y-001100X0120Y0200R270 S2      
327m2053            J81   -2          A01X+117997Y+000097X0120Y0200R090 S1      
327m2053            J75   -1          A01X+083975Y+000097X0120Y0200R270 S1      
327m2054            J81   -1          A01X+117997Y-000100X0120Y0200R090 S1      
327m2054            J75   -2          A01X+083975Y-000100X0120Y0200R270 S1      
327m2055            J119  -1          A18X+117997Y-000903X0120Y0200R090 S2      
327m2055            J121  -2          A18X+083975Y-000903X0120Y0200R270 S2      
317m2055            VIA   -    MD0100PA18X+117740Y-000831X0200Y    R180 S0      
317m2055            VIA   -    MD0100PA18X+084232Y-000831X0200Y         S0      
327m2056            J119  -2          A18X+117997Y-001100X0120Y0200R090 S2      
327m2056            J121  -1          A18X+083975Y-001100X0120Y0200R270 S2      
317m2056            VIA   -    MD0100PA18X+117740Y-001171X0200Y    R180 S0      
317m2056            VIA   -    MD0100PA18X+084232Y-001171X0200Y         S0      
327m2057            J120  -2          A18X+072849Y-001486X0120Y0200R090 S2      
327m2057            J118  -1          A18X+038827Y-001486X0120Y0200R270 S2      
317m2057            VIA   -    MD0100PA18X+072592Y-001557X0200Y    R180 S0      
317m2057            VIA   -    MD0100PA18X+039084Y-001557X0200Y    R180 S0      
327m2058            J120  -1          A18X+072849Y-001289X0120Y0200R090 S2      
327m2058            J118  -2          A18X+038827Y-001289X0120Y0200R270 S2      
317m2058            VIA   -    MD0100PA18X+072592Y-001217X0200Y    R180 S0      
317m2058            VIA   -    MD0100PA18X+039084Y-001217X0200Y    R180 S0      
327m2059            J86   -2          A18X+117997Y+000900X0120Y0200R090 S2      
327m2059            J80   -1          A18X+083975Y+000900X0120Y0200R270 S2      
317m2059            VIA   -    MD0100PA18X+117740Y+000829X0200Y    R180 S0      
317m2059            VIA   -    MD0100PA18X+084232Y+000829X0200Y         S0      
327m2060            J86   -1          A18X+117997Y+001097X0120Y0200R090 S2      
327m2060            J80   -2          A18X+083975Y+001097X0120Y0200R270 S2      
317m2060            VIA   -    MD0100PA18X+117740Y+001169X0200Y    R180 S0      
317m2060            VIA   -    MD0100PA18X+084232Y+001169X0200Y         S0      
327m2061            J85   -2          A01X+117997Y-001903X0120Y0200R090 S1      
327m2061            J79   -1          A01X+083975Y-001903X0120Y0200R270 S1      
317m2061            VIA   -    MD0100PA01X+117740Y-001831X0200Y    R180 S0      
317m2061            VIA   -    MD0100PA01X+084232Y-001831X0200Y         S0      
327m2062            J85   -1          A01X+117997Y-002100X0120Y0200R090 S1      
327m2062            J79   -2          A01X+083975Y-002100X0120Y0200R270 S1      
317m2062            VIA   -    MD0100PA01X+117740Y-002171X0200Y    R180 S0      
317m2062            VIA   -    MD0100PA01X+084232Y-002171X0200Y         S0      
327m2063            J84   -2          A01X+117997Y+002097X0120Y0200R090 S1      
327m2063            J78   -1          A01X+083975Y+002097X0120Y0200R270 S1      
317m2063            VIA   -    MD0100PA01X+117740Y+002169X0200Y    R180 S0      
317m2063            VIA   -    MD0100PA01X+084232Y+002169X0200Y         S0      
327m2064            J84   -1          A01X+117997Y+001900X0120Y0200R090 S1      
327m2064            J78   -2          A01X+083975Y+001900X0120Y0200R270 S1      
317m2064            VIA   -    MD0100PA01X+117740Y+001829X0200Y    R180 S0      
317m2064            VIA   -    MD0100PA01X+084232Y+001829X0200Y         S0      
327m2065            J83   -2          A01X+072849Y-002289X0120Y0200R090 S1      
327m2065            J77   -1          A01X+038827Y-002289X0120Y0200R270 S1      
317m2065            VIA   -    MD0100PA01X+072592Y-002217X0200Y    R180 S0      
317m2065            VIA   -    MD0100PA01X+039084Y-002217X0200Y    R180 S0      
327m2066            J83   -1          A01X+072849Y-002486X0120Y0200R090 S1      
327m2066            J77   -2          A01X+038827Y-002486X0120Y0200R270 S1      
317m2066            VIA   -    MD0100PA01X+072592Y-002557X0200Y    R180 S0      
317m2066            VIA   -    MD0100PA01X+039084Y-002557X0200Y    R180 S0      
327m2067            J82   -2          A18X+117997Y-003100X0120Y0200R090 S2      
327m2067            J76   -1          A18X+083975Y-003100X0120Y0200R270 S2      
327m2068            J82   -1          A18X+117997Y-002903X0120Y0200R090 S2      
327m2068            J76   -2          A18X+083975Y-002903X0120Y0200R270 S2      
327m2069            R571  -2          A18X+058473Y+123408X0198Y0197R180 S2      
327m2069            R5103 -2   M      A18X+058858Y+123408X0198Y0197     S2      
327m2069            C237  -1   M      A18X+058858Y+123808X0198Y0197R180 S2      
327m2069            Y4    -3          A18X+059113Y+124442X0480Y0590R090 S2      
327m2070            Y2    -3          A18X+156848Y+124351X0480Y0590R090 S2      
327m2070            C214  -1   M      A18X+156469Y+123766X0198Y0197R180 S2      
327m2070            R432  -2          A18X+156125Y+123416X0198Y0197R180 S2      
327m2070            R5102 -2   M      A18X+156510Y+123416X0198Y0197     S2      
317m2071            VIA   -    MD0080PA00X+133414Y+116199X0160Y         S0      
327m2071            U25   -DH60       A01X+133598Y+116094X0177Y    R180 S1      
317m2071            VIA   -    MD0100PA00X+170556Y+064455X0200Y         S2      
327m2071            R46   -2          A01X+153745Y+009130X0198Y0197R090 S1      
317m2072            VIA   -    MD0080PA00X+133599Y+116518X0160Y         S0      
327m2072            U25   -DJ60       A01X+133783Y+116413X0177Y    R180 S1      
327m2072            R42   -2          A01X+153345Y+009130X0198Y0197R090 S1      
317m2072            VIA   -    MD0100PA00X+170166Y+064455X0200Y         S2      
317m2073            VIA   -    M      A01X+078376Y+047934X0300Y         S1      
017m2073            VIA   -    M      A18X+078376Y+047934X0200Y         S1      
017m2073                  -    MD0100PA00X+078376Y+047934                       
327m2073            U18   -Y14        A01X+075717Y+046084X0160Y    R090 S1      
317m2073            VIA   -    MD0100PA00X+075871Y+046237X0180Y    R090 S0      
327m2073            R4563 -1          A18X+078958Y+047934X0198Y0197R180 S2      
327SWB_HSC_EN_R     R4558 -1          A18X+077508Y+047134X0198Y0197R180 S2      
327SWB_HSC_EN_R     U18   -Y13        A01X+075717Y+045769X0160Y    R090 S1      
317SWB_HSC_EN_R     VIA   -    MD0100PA00X+075871Y+045922X0180Y    R090 S2      
317m2074            VIA   -    M      A01X+122209Y+029207X0300Y         S1      
017m2074            VIA   -    M      A18X+122209Y+029207X0200Y         S1      
017m2074                  -    MD0100PA00X+122209Y+029207                       
327m2074            Q87   -5          A18X+122518Y+028951X0170Y0200R270 S2      
317m2074            VIA   -    MD0100PA00X+120251Y+034142X0200Y         S0      
327m2074            C1209 -1          A18X+064434Y+047914X0198Y0197R180 S2      
327m2074            R6093 -2   M      A18X+064438Y+047388X0198Y0197     S2      
317m2074            VIA   -    MD0100PA00X+083791Y+040154X0200Y         S0      
327m2075            J41   -A48        A01X+056278Y+005354X0150Y0570R180 S1      
317m2075            VIA   -    M      A01X+058134Y+047210X0200Y         S2      
017m2075            VIA   -    M      A18X+058134Y+047210X0260Y         S2      
017m2075                  -    MD0100PA00X+058134Y+047210                       
327m2075            R6092 -2          A18X+064434Y+046983X0198Y0197     S2      
317m2075            VIA   -    MD0100PA00X+063564Y+046426X0200Y         S0      
317m2075            VIA   -    MD0100PA00X+056233Y+004844X0200Y    R180 S0      
327m2076            R6058 -1          A01X+032922Y+014712X0198Y0197R180 S1      
327m2076            R6056 -1   M      A01X+032922Y+016012X0198Y0197R180 S1      
327m2076            R6057 -1   M      A01X+032922Y+015612X0198Y0197R180 S1      
327m2076            R6059 -1   M      A01X+032922Y+015212X0198Y0197R180 S1      
327m2076            VIA   -    M      A01X+032922Y+016492X0300Y    R180 S1      
327m2076            U207  -4          A01X+032922Y+017117X0140Y0490     S1      
327m2077            VIA   -    M      A01X+083524Y+048364X0300Y         S1      
327m2077            R956  -1   M      A01X+084062Y+048213X0198Y0197     S1      
327m2077            U75   -4          A01X+082903Y+048650X0140Y0490R090 S1      
327m2077            R877  -1   M      A01X+084066Y+048648X0198Y0197     S1      
327m2077            R899  -1          A01X+084051Y+049466X0198Y0197     S1      
327m2077            R905  -1   M      A01X+084063Y+049057X0198Y0197     S1      
317m2078            VIA   -    M      A01X+077717Y+050448X0200Y    R270 S2      
017m2078            VIA   -    M      A18X+077717Y+050448X0260Y    R270 S2      
017m2078                  -    MD0100PA00X+077717Y+050448                       
327m2078            R2847 -1          A01X+077508Y+049934X0198Y0197     S1      
327m2078            U18   -U15        A01X+074772Y+046399X0160Y    R090 S1      
317m2078            VIA   -    MD0100PA00X+074926Y+046552X0180Y    R090 S0      
317m2079            VIA   -    M      A01X+078382Y+043153X0200Y    R180 S2      
017m2079            VIA   -    M      A18X+078382Y+043153X0260Y    R180 S2      
017m2079                  -    MD0100PA00X+078382Y+043153                       
327m2079            R6047 -2          A01X+078953Y+043134X0198Y0197R180 S1      
327m2079            U18   -W8         A01X+075402Y+044194X0160Y    R090 S1      
317m2079            VIA   -    MD0100PA00X+075556Y+044040X0180Y    R090 S0      
327m2080            R214  -2          A01X+084933Y+050711X0198Y0197     S1      
317m2080            VIA   -    MD0100PA00X+059705Y+028195X0200Y    R270 S0      
327m2080            C6085 -1   M      A18X+047799Y+028109X0198Y0197R180 S2      
327m2080            R6240 -1          A18X+047799Y+028569X0198Y0197     S2      
317m2080            VIA   -    M      A01X+126209Y+028795X0300Y         S1      
017m2080            VIA   -    M      A18X+126209Y+028795X0200Y         S1      
017m2080                  -    MD0100PA00X+126209Y+028795                       
327m2080            Q78   -2          A18X+126466Y+028951X0170Y0200R270 S2      
317m2080            VIA   -    MD0100PA00X+120562Y+031376X0200Y         S0      
317m2080            VIA   -    MD0100PA00X+062682Y+018208X0200Y         S0      
317m2080            VIA   -    MD0100PA00X+098958Y+030356X0200Y         S0      
327m2080            U18   -Y8         A01X+075717Y+044194X0160Y    R090 S1      
317m2080            VIA   -    MD0100PA00X+075871Y+044040X0180Y    R090 S0      
317m2080            VIA   -    MD0100PA00X+085947Y+042529X0200Y         S0      
317m2080            VIA   -    MD0100PA00X+085550Y+050720X0200Y         S0      
317m2080            VIA   -    MD0100PA00X+099441Y+034981X0200Y         S0      
317m2080            VIA   -    MD0100PA00X+093213Y+024410X0200Y         S0      
327m2080            R2476 -2          A01X+062531Y+017868X0198Y0197R090 S1      
317m2081            VIA   -    M      A01X+038218Y+046635X0200Y         S2      
017m2081            VIA   -    M      A18X+038218Y+046635X0260Y         S2      
017m2081                  -    MD0100PA00X+038218Y+046635                       
327m2081            C5014 -1   M      A01X+038218Y+046878X0198Y0197R090 S1      
327m2081            R1363 -2          A01X+037818Y+046878X0198Y0197R270 S1      
317m2081            VIA   -    MD0100PA00X+065327Y+047911X0200Y         S0      
327m2081            U18   -N19        A01X+073513Y+047659X0160Y    R090 S1      
317m2081            VIA   -    MD0100PA00X+073666Y+047812X0180Y    R090 S0      
327m2082            R1459 -2          A01X+038218Y+050153X0198Y0197R270 S1      
327m2082            U38   -3          A01X+038462Y+049106X0160Y0360     S1      
327m2082            VIA   -    M      A01X+038218Y+049673X0300Y         S1      
327m2083            R1449 -2          A01X+041598Y+047197X0198Y0197R090 S1      
327m2083            Q19   -6          A01X+041854Y+048302X0120Y0490     S1      
327m2083            Q19   -5   M      A01X+041598Y+048302X0120Y0490     S1      
327m2083            VIA   -    M      A01X+041598Y+047677X0300Y    R180 S1      
327m2084            R1440 -2          A01X+041998Y+050145X0198Y0197R270 S1      
327m2084            R1441 -1   M      A01X+041598Y+050145X0198Y0197R090 S1      
327m2084            Q19   -2          A01X+041598Y+049040X0120Y0490     S1      
327m2084            VIA   -    M      A01X+041598Y+049665X0300Y         S1      
327m2085            R1459 -1          A01X+038218Y+050468X0198Y0197R270 S1      
317m2085            VIA   -    MD0100PA00X+038218Y+050710X0200Y    R180 S0      
317m2085            VIA   -    M      A01X+041098Y+049665X0200Y         S2      
017m2085            VIA   -    M      A18X+041098Y+049665X0260Y         S2      
017m2085                  -    MD0100PA00X+041098Y+049665                       
327m2085            R1452 -2          A01X+041098Y+050145X0198Y0197R270 S1      
327m2085            Q19   -3          A01X+041342Y+049040X0120Y0490     S1      
327m2086            R1458 -2          A01X+039218Y+050153X0198Y0197R270 S1      
327m2086            U38   -1          A01X+038974Y+049106X0160Y0360     S1      
327m2086            VIA   -    M      A01X+039218Y+049673X0300Y         S1      
327m2087            R1450 -2          A01X+040218Y+047204X0198Y0197R090 S1      
327m2087            Q18   -6          A01X+040474Y+048309X0120Y0490     S1      
327m2087            Q18   -5   M      A01X+040218Y+048309X0120Y0490     S1      
327m2087            VIA   -    M      A01X+040218Y+047684X0300Y    R180 S1      
327m2088            R1442 -2          A01X+040618Y+050153X0198Y0197R270 S1      
327m2088            R1443 -1   M      A01X+040218Y+050153X0198Y0197R090 S1      
327m2088            Q18   -2          A01X+040218Y+049048X0120Y0490     S1      
327m2088            VIA   -    M      A01X+040218Y+049673X0300Y         S1      
327m2089            R1458 -1          A01X+039218Y+050468X0198Y0197R270 S1      
327m2089            R1457 -2   M      A01X+039718Y+050153X0198Y0197R270 S1      
327m2089            Q18   -3          A01X+039962Y+049048X0120Y0490     S1      
327m2089            VIA   -    M      A01X+039718Y+049673X0300Y         S1      
327PWRGD_P12V_MEM   R1363 -1          A01X+037818Y+047193X0198Y0197R270 S1      
327PWRGD_P12V_MEM   U38   -4          A01X+038462Y+048240X0160Y0360     S1      
327PWRGD_P12V_MEM   VIA   -    M      A01X+038218Y+047673X0300Y         S1      
327m2090            VIA   -    M      A01X+077640Y+053330X0300Y         S1      
327m2090            R6085 -2          A01X+077200Y+052429X0198Y0197R270 S1      
327m2090            U18   -AB21       A01X+076347Y+048288X0160Y    R090 S1      
327P5V_AUX_EN       U326  -8          A01X+162154Y+054954X0070Y0320R090 S1      
327P5V_AUX_EN       VIA   -           A01X+160524Y+054112X0300Y    R270 S1      
327P5V_AUX_EN       R6097 -2   M      A01X+161369Y+054273X0198Y0197     S1      
317P3V3_STBY_R      VIA   -    M      A01X+120843Y+012875X0200Y    R180 S2      
017P3V3_STBY_R      VIA   -    M      A18X+120843Y+012875X0260Y    R180 S2      
017P3V3_STBY_R            -    MD0100PA00X+120843Y+012875                       
327P3V3_STBY_R      R5101 -2          A01X+120533Y+012875X0198Y0197     S1      
327P3V3_STBY_R      U166  -1          A01X+121153Y+012875X0240Y0320R270 S1      
327P3V3_RTC_AUX_R   R5052 -1          A01X+127598Y+009069X0198Y0197R270 S1      
327P3V3_RTC_AUX_R   R5054 -1          A01X+128076Y+009538X0198Y0197R270 S1      
327P3V3_RTC_AUX_R   VIA   -    M      A01X+127596Y+009538X0300Y    R180 S1      
317P1V5_BAT_OUT_R   JP12  -1    D0410PA00X+129944Y+009281X0610Y0610R180 S3      
327P1V5_BAT_OUT_R   VIA   -    M      A01X+128346Y+008696X0300Y         S1      
327P1V5_BAT_OUT_R   R5054 -2          A01X+128076Y+009223X0198Y0197R270 S1      
327P1V5_BAT_OUT_R   R5053 -2   M      A01X+128476Y+009223X0198Y0197R270 S1      
327P1V5_BAT_IN      U9    -1          A01X+119619Y+010343X0160Y0360R270 S1      
327P1V5_BAT_IN      R5051 -2   M      A01X+118501Y+009969X0198Y0197R180 S1      
327P1V5_BAT_IN      VIA   -    M      A01X+118028Y+010079X0300Y    R180 S1      
327P1V5_BAT_IN      R1777 -1   M      A01X+117962Y+009586X0198Y0197     S1      
327P1V5_BAT_IN      C45   -1   M      A01X+117185Y+009356X0198Y0197     S1      
327P1V5_BAT_IN      U167  -2          A01X+117185Y+008349X0280Y0360R180 S1      
327P1V5_BAT_IN      C193  -1   M      A01X+117185Y+008956X0198Y0197     S1      
317P12V_MEM_CPU1    VIA   -    MD0100PA00X+064285Y+075683X0190Y         S0      
327P12V_MEM_CPU1    C531  -1   M      A18X+064386Y+075850X0400Y0500     S2      
317P12V_MEM_CPU1    VIA   -    MD0100PA00X+064285Y+076018X0190Y         S0      
327P12V_MEM_CPU1    J102  -145 M      A01X+064735Y+075683X0205Y0590R090 S1      
327P12V_MEM_CPU1    J102  -146 M      A01X+064735Y+076018X0205Y0590R090 S1      
317P12V_MEM_CPU1    VIA   -    MD0100PA00X+012398Y+071498X0200Y         S0      
317P12V_MEM_CPU1    VIA   -    MD0100PA00X+012148Y+071498X0200Y         S0      
317P12V_MEM_CPU1    VIA   -    MD0100PA00X+011898Y+071498X0200Y         S0      
317P12V_MEM_CPU1    VIA   -    MD0100PA00X+011648Y+071498X0200Y         S0      
317P12V_MEM_CPU1    VIA   -    MD0100PA00X+011398Y+071498X0200Y         S0      
317P12V_MEM_CPU1    VIA   -    MD0100PA00X+011398Y+072248X0200Y         S0      
317P12V_MEM_CPU1    VIA   -    MD0100PA00X+012398Y+071748X0200Y         S0      
317P12V_MEM_CPU1    VIA   -    MD0100PA00X+012148Y+071748X0200Y         S0      
317P12V_MEM_CPU1    VIA   -    MD0100PA00X+011898Y+071748X0200Y         S0      
317P12V_MEM_CPU1    VIA   -    MD0100PA00X+011648Y+071748X0200Y         S0      
317P12V_MEM_CPU1    VIA   -    MD0100PA00X+011398Y+071748X0200Y         S0      
317P12V_MEM_CPU1    VIA   -    MD0100PA00X+012398Y+071998X0200Y         S0      
317P12V_MEM_CPU1    VIA   -    MD0100PA00X+012148Y+071998X0200Y         S0      
317P12V_MEM_CPU1    VIA   -    MD0100PA00X+011898Y+071998X0200Y         S0      
317P12V_MEM_CPU1    VIA   -    MD0100PA00X+011648Y+071998X0200Y         S0      
317P12V_MEM_CPU1    VIA   -    MD0100PA00X+011398Y+071998X0200Y         S0      
317P12V_MEM_CPU1    VIA   -    MD0100PA00X+012398Y+072248X0200Y         S0      
317P12V_MEM_CPU1    VIA   -    MD0100PA00X+012148Y+072248X0200Y         S0      
317P12V_MEM_CPU1    VIA   -    MD0100PA00X+011898Y+072248X0200Y         S0      
317P12V_MEM_CPU1    VIA   -    MD0100PA00X+011648Y+072248X0200Y         S0      
327P12V_MEM_CPU1    J24   -1   M      A01X+023397Y+075683X0205Y0590R090 S1      
317P12V_MEM_CPU1    VIA   -    MD0100PA00X+023847Y+075683X0190Y         S0      
327P12V_MEM_CPU1    C174  -1          A18X+023747Y+075850X0400Y0500R180 S2      
327P12V_MEM_CPU1    J26   -1   M      A01X+020427Y+075683X0205Y0590R090 S1      
317P12V_MEM_CPU1    VIA   -    MD0100PA00X+020877Y+075683X0190Y         S0      
327P12V_MEM_CPU1    C177  -1          A18X+020777Y+075850X0400Y0500R180 S2      
327P12V_MEM_CPU1    J24   -145 M      A01X+021783Y+075683X0205Y0590R090 S1      
327P12V_MEM_CPU1    J24   -146 M      A01X+021783Y+076018X0205Y0590R090 S1      
317P12V_MEM_CPU1    VIA   -    MD0100PA00X+021333Y+075683X0190Y    R180 S0      
327P12V_MEM_CPU1    C173  -1   M      A18X+021433Y+075850X0400Y0500     S2      
317P12V_MEM_CPU1    VIA   -    MD0100PA00X+021333Y+076018X0190Y    R180 S0      
327P12V_MEM_CPU1    J28   -1   M      A01X+017457Y+075683X0205Y0590R090 S1      
317P12V_MEM_CPU1    VIA   -    MD0100PA00X+017907Y+075683X0190Y         S0      
327P12V_MEM_CPU1    C179  -1          A18X+017807Y+075850X0400Y0500R180 S2      
327P12V_MEM_CPU1    J26   -145 M      A01X+018813Y+075683X0205Y0590R090 S1      
327P12V_MEM_CPU1    J26   -146 M      A01X+018813Y+076018X0205Y0590R090 S1      
317P12V_MEM_CPU1    VIA   -    MD0100PA00X+018363Y+075683X0190Y         S0      
327P12V_MEM_CPU1    C175  -1   M      A18X+018463Y+075850X0400Y0500     S2      
317P12V_MEM_CPU1    VIA   -    MD0100PA00X+018363Y+076018X0190Y         S0      
327P12V_MEM_CPU1    R1837 -2          A01X+005077Y+075066X1260Y0591     S1      
317P12V_MEM_CPU1    VIA   -    MD0100PA00X+067256Y+076018X0190Y         S0      
327P12V_MEM_CPU1    C532  -1   M      A18X+067356Y+075850X0400Y0500     S2      
317P12V_MEM_CPU1    VIA   -    MD0100PA00X+067256Y+075683X0190Y         S0      
327P12V_MEM_CPU1    C530  -1          A18X+066700Y+075850X0400Y0500R180 S2      
317P12V_MEM_CPU1    VIA   -    MD0100PA00X+066800Y+075683X0190Y         S0      
317P12V_MEM_CPU1    VIA   -    MD0100PA00X+070226Y+076018X0190Y         S0      
327P12V_MEM_CPU1    C534  -1   M      A18X+070326Y+075850X0400Y0500     S2      
317P12V_MEM_CPU1    VIA   -    MD0100PA00X+070226Y+075683X0190Y         S0      
327P12V_MEM_CPU1    C533  -1          A18X+069670Y+075850X0400Y0500R180 S2      
317P12V_MEM_CPU1    VIA   -    MD0100PA00X+069770Y+075683X0190Y         S0      
317P12V_MEM_CPU1    VIA   -    MD0100PA00X+073196Y+076018X0190Y         S0      
327P12V_MEM_CPU1    C537  -1   M      A18X+073296Y+075850X0400Y0500     S2      
317P12V_MEM_CPU1    VIA   -    MD0100PA00X+073196Y+075683X0190Y         S0      
327P12V_MEM_CPU1    C535  -1          A18X+072640Y+075850X0400Y0500R180 S2      
317P12V_MEM_CPU1    VIA   -    MD0100PA00X+072740Y+075683X0190Y         S0      
317P12V_MEM_CPU1    VIA   -    MD0100PA00X+076166Y+076018X0190Y         S0      
327P12V_MEM_CPU1    C547  -1   M      A18X+076266Y+075850X0400Y0500     S2      
317P12V_MEM_CPU1    VIA   -    MD0100PA00X+076166Y+075683X0190Y         S0      
327P12V_MEM_CPU1    C536  -1          A18X+075610Y+075850X0400Y0500R180 S2      
317P12V_MEM_CPU1    VIA   -    MD0100PA00X+075710Y+075683X0190Y         S0      
317P12V_MEM_CPU1    VIA   -    MD0100PA00X+079136Y+075683X0190Y         S0      
327P12V_MEM_CPU1    C549  -1   M      A18X+079236Y+075850X0400Y0500     S2      
317P12V_MEM_CPU1    VIA   -    MD0100PA00X+079136Y+076018X0190Y         S0      
327P12V_MEM_CPU1    C546  -1          A18X+078580Y+075850X0400Y0500R180 S2      
317P12V_MEM_CPU1    VIA   -    MD0100PA00X+078680Y+075683X0190Y         S0      
327P12V_MEM_CPU1    C548  -1          A18X+081550Y+075850X0400Y0500R180 S2      
317P12V_MEM_CPU1    VIA   -    MD0100PA00X+081650Y+075683X0190Y         S0      
327P12V_MEM_CPU1    J37   -1   M      A01X+081200Y+075683X0205Y0590R090 S1      
327P12V_MEM_CPU1    J37   -145 M      A01X+079586Y+075683X0205Y0590R090 S1      
327P12V_MEM_CPU1    J37   -146 M      A01X+079586Y+076018X0205Y0590R090 S1      
327P12V_MEM_CPU1    J99   -1   M      A01X+078230Y+075683X0205Y0590R090 S1      
327P12V_MEM_CPU1    J99   -146 M      A01X+076616Y+076018X0205Y0590R090 S1      
327P12V_MEM_CPU1    J99   -145 M      A01X+076616Y+075683X0205Y0590R090 S1      
327P12V_MEM_CPU1    J29   -1   M      A01X+075260Y+075683X0205Y0590R090 S1      
327P12V_MEM_CPU1    J29   -146 M      A01X+073646Y+076018X0205Y0590R090 S1      
327P12V_MEM_CPU1    J29   -145 M      A01X+073646Y+075683X0205Y0590R090 S1      
327P12V_MEM_CPU1    J100  -1   M      A01X+072290Y+075683X0205Y0590R090 S1      
327P12V_MEM_CPU1    J100  -146 M      A01X+070676Y+076018X0205Y0590R090 S1      
327P12V_MEM_CPU1    J100  -145 M      A01X+070676Y+075683X0205Y0590R090 S1      
327P12V_MEM_CPU1    J27   -1   M      A01X+069320Y+075683X0205Y0590R090 S1      
327P12V_MEM_CPU1    J27   -146 M      A01X+067706Y+076018X0205Y0590R090 S1      
327P12V_MEM_CPU1    J27   -145 M      A01X+067706Y+075683X0205Y0590R090 S1      
327P12V_MEM_CPU1    J102  -1   M      A01X+066350Y+075683X0205Y0590R090 S1      
317P12V_MEM_CPU1    VIA   -    M      A01X+041998Y+050800X0200Y    R180 S2      
017P12V_MEM_CPU1    VIA   -    M      A18X+041998Y+050800X0260Y    R180 S2      
017P12V_MEM_CPU1          -    MD0100PA00X+041998Y+050800                       
317P12V_MEM_CPU1    VIA   -    MD0100PA00X+044444Y+056555X0200Y         S0      
327P12V_MEM_CPU1    R1440 -1          A01X+041998Y+050460X0198Y0197R270 S1      
317P12V_MEM_CPU1    VIA   -    MD0100PA00X+006482Y+076018X0190Y         S0      
327P12V_MEM_CPU1    C518  -1   M      A18X+006582Y+075850X0400Y0500     S2      
317P12V_MEM_CPU1    VIA   -    MD0100PA00X+006482Y+075683X0190Y         S0      
327P12V_MEM_CPU1    C527  -1          A18X+008896Y+075850X0400Y0500R180 S2      
317P12V_MEM_CPU1    VIA   -    MD0100PA00X+008996Y+075683X0190Y         S0      
317P12V_MEM_CPU1    VIA   -    MD0100PA00X+009452Y+075683X0190Y         S0      
327P12V_MEM_CPU1    C509  -1   M      A18X+009552Y+075850X0400Y0500     S2      
317P12V_MEM_CPU1    VIA   -    MD0100PA00X+009452Y+076018X0190Y         S0      
327P12V_MEM_CPU1    C183  -1          A18X+011867Y+075850X0400Y0500R180 S2      
317P12V_MEM_CPU1    VIA   -    MD0100PA00X+011967Y+075683X0190Y         S0      
317P12V_MEM_CPU1    VIA   -    MD0100PA00X+012422Y+075683X0190Y         S0      
327P12V_MEM_CPU1    C182  -1   M      A18X+012522Y+075850X0400Y0500     S2      
317P12V_MEM_CPU1    VIA   -    MD0100PA00X+012422Y+076018X0190Y         S0      
327P12V_MEM_CPU1    C181  -1          A18X+014837Y+075850X0400Y0500R180 S2      
317P12V_MEM_CPU1    VIA   -    MD0100PA00X+014937Y+075683X0190Y         S0      
317P12V_MEM_CPU1    VIA   -    MD0100PA00X+015392Y+075683X0190Y         S0      
327P12V_MEM_CPU1    C178  -1   M      A18X+015493Y+075850X0400Y0500     S2      
317P12V_MEM_CPU1    VIA   -    MD0100PA00X+015392Y+076018X0190Y         S0      
327P12V_MEM_CPU1    J30   -1   M      A01X+014487Y+075683X0205Y0590R090 S1      
327P12V_MEM_CPU1    J28   -145 M      A01X+015842Y+075683X0205Y0590R090 S1      
327P12V_MEM_CPU1    J28   -146 M      A01X+015842Y+076018X0205Y0590R090 S1      
327P12V_MEM_CPU1    J32   -1   M      A01X+011517Y+075683X0205Y0590R090 S1      
327P12V_MEM_CPU1    J30   -145 M      A01X+012872Y+075683X0205Y0590R090 S1      
327P12V_MEM_CPU1    J30   -146 M      A01X+012872Y+076018X0205Y0590R090 S1      
327P12V_MEM_CPU1    J33   -1   M      A01X+008546Y+075683X0205Y0590R090 S1      
327P12V_MEM_CPU1    J32   -145 M      A01X+009902Y+075683X0205Y0590R090 S1      
327P12V_MEM_CPU1    J32   -146 M      A01X+009902Y+076018X0205Y0590R090 S1      
327P12V_MEM_CPU1    J33   -146 M      A01X+006932Y+076018X0205Y0590R090 S1      
327P12V_MEM_CPU1    J33   -145 M      A01X+006932Y+075683X0205Y0590R090 S1      
317P12V_MEM_CPU0    VIA   -    MD0100PA00X+175399Y+071389X0200Y    R180 S0      
327P12V_MEM_CPU0    C159  -1          A18X+167284Y+075850X0400Y0500R180 S2      
317P12V_MEM_CPU0    VIA   -    MD0100PA00X+167384Y+075683X0190Y         S0      
327P12V_MEM_CPU0    J69   -1   M      A01X+166934Y+075683X0205Y0590R090 S1      
317P12V_MEM_CPU0    VIA   -    MD0100PA00X+164870Y+075683X0190Y         S0      
327P12V_MEM_CPU0    C161  -1   M      A18X+164970Y+075850X0400Y0500     S2      
317P12V_MEM_CPU0    VIA   -    MD0100PA00X+164870Y+076018X0190Y         S0      
327P12V_MEM_CPU0    J69   -145 M      A01X+165320Y+075683X0205Y0590R090 S1      
327P12V_MEM_CPU0    J69   -146 M      A01X+165320Y+076018X0205Y0590R090 S1      
327P12V_MEM_CPU0    C158  -1          A18X+164314Y+075850X0400Y0500R180 S2      
317P12V_MEM_CPU0    VIA   -    MD0100PA00X+164414Y+075683X0190Y         S0      
327P12V_MEM_CPU0    J16   -1   M      A01X+163964Y+075683X0205Y0590R090 S1      
317P12V_MEM_CPU0    VIA   -    MD0100PA00X+161900Y+075683X0190Y         S0      
327P12V_MEM_CPU0    C157  -1   M      A18X+162000Y+075850X0400Y0500     S2      
317P12V_MEM_CPU0    VIA   -    MD0100PA00X+161900Y+076018X0190Y         S0      
327P12V_MEM_CPU0    J16   -145 M      A01X+162350Y+075683X0205Y0590R090 S1      
327P12V_MEM_CPU0    J16   -146 M      A01X+162350Y+076018X0205Y0590R090 S1      
327P12V_MEM_CPU0    R1838 -2          A01X+176046Y+070908X1260Y0591R270 S1      
317P12V_MEM_CPU0    VIA   -    MD0100PA00X+175399Y+070639X0200Y    R180 S0      
317P12V_MEM_CPU0    VIA   -    MD0100PA00X+175399Y+070889X0200Y    R180 S0      
317P12V_MEM_CPU0    VIA   -    MD0100PA00X+175399Y+071139X0200Y    R180 S0      
317P12V_MEM_CPU0    VIA   -    MD0100PA00X+174399Y+071139X0200Y    R180 S0      
317P12V_MEM_CPU0    VIA   -    MD0100PA00X+174649Y+071139X0200Y    R180 S0      
317P12V_MEM_CPU0    VIA   -    MD0100PA00X+174899Y+071139X0200Y    R180 S0      
317P12V_MEM_CPU0    VIA   -    MD0100PA00X+175149Y+071139X0200Y    R180 S0      
317P12V_MEM_CPU0    VIA   -    MD0100PA00X+174399Y+070889X0200Y    R180 S0      
317P12V_MEM_CPU0    VIA   -    MD0100PA00X+174649Y+070889X0200Y    R180 S0      
317P12V_MEM_CPU0    VIA   -    MD0100PA00X+174899Y+070889X0200Y    R180 S0      
317P12V_MEM_CPU0    VIA   -    MD0100PA00X+175149Y+070889X0200Y    R180 S0      
317P12V_MEM_CPU0    VIA   -    MD0100PA00X+174399Y+070639X0200Y    R180 S0      
317P12V_MEM_CPU0    VIA   -    MD0100PA00X+174649Y+070639X0200Y    R180 S0      
317P12V_MEM_CPU0    VIA   -    MD0100PA00X+174899Y+070639X0200Y    R180 S0      
317P12V_MEM_CPU0    VIA   -    MD0100PA00X+175149Y+070639X0200Y    R180 S0      
317P12V_MEM_CPU0    VIA   -    MD0100PA00X+174399Y+071389X0200Y    R180 S0      
317P12V_MEM_CPU0    VIA   -    MD0100PA00X+174649Y+071389X0200Y    R180 S0      
317P12V_MEM_CPU0    VIA   -    MD0100PA00X+174899Y+071389X0200Y    R180 S0      
317P12V_MEM_CPU0    VIA   -    MD0100PA00X+175149Y+071389X0200Y    R180 S0      
317P12V_MEM_CPU0    VIA   -    MD0100PA00X+167840Y+075683X0190Y         S0      
327P12V_MEM_CPU0    C162  -1   M      A18X+167940Y+075850X0400Y0500     S2      
317P12V_MEM_CPU0    VIA   -    MD0100PA00X+167840Y+076018X0190Y         S0      
327P12V_MEM_CPU0    C163  -1          A18X+170254Y+075850X0400Y0500R180 S2      
317P12V_MEM_CPU0    VIA   -    MD0100PA00X+170354Y+075683X0190Y         S0      
317P12V_MEM_CPU0    VIA   -    MD0100PA00X+170810Y+075683X0190Y         S0      
327P12V_MEM_CPU0    C165  -1   M      A18X+170910Y+075850X0400Y0500     S2      
317P12V_MEM_CPU0    VIA   -    MD0100PA00X+170810Y+076018X0190Y         S0      
327P12V_MEM_CPU0    C166  -1          A18X+173224Y+075850X0400Y0500R180 S2      
317P12V_MEM_CPU0    VIA   -    MD0100PA00X+173324Y+075683X0190Y         S0      
317P12V_MEM_CPU0    VIA   -    MD0100PA00X+173780Y+076018X0190Y         S0      
327P12V_MEM_CPU0    C167  -1   M      A18X+173880Y+075850X0400Y0500     S2      
317P12V_MEM_CPU0    VIA   -    MD0100PA00X+173780Y+075683X0190Y         S0      
327P12V_MEM_CPU0    C169  -1          A18X+176194Y+075850X0400Y0500R180 S2      
317P12V_MEM_CPU0    VIA   -    MD0100PA00X+176294Y+075683X0190Y         S0      
317P12V_MEM_CPU0    VIA   -    MD0100PA00X+176750Y+075683X0190Y         S0      
327P12V_MEM_CPU0    C171  -1   M      A18X+176850Y+075850X0400Y0500     S2      
317P12V_MEM_CPU0    VIA   -    MD0100PA00X+176750Y+076018X0190Y         S0      
327P12V_MEM_CPU0    C170  -1          A18X+179164Y+075850X0400Y0500R180 S2      
317P12V_MEM_CPU0    VIA   -    MD0100PA00X+179264Y+075683X0190Y         S0      
327P12V_MEM_CPU0    J67   -1   M      A01X+178814Y+075683X0205Y0590R090 S1      
327P12V_MEM_CPU0    J67   -145 M      A01X+177200Y+075683X0205Y0590R090 S1      
327P12V_MEM_CPU0    J67   -146 M      A01X+177200Y+076018X0205Y0590R090 S1      
327P12V_MEM_CPU0    J20   -1   M      A01X+175844Y+075683X0205Y0590R090 S1      
327P12V_MEM_CPU0    J20   -145 M      A01X+174230Y+075683X0205Y0590R090 S1      
327P12V_MEM_CPU0    J20   -146 M      A01X+174230Y+076018X0205Y0590R090 S1      
327P12V_MEM_CPU0    J68   -1   M      A01X+172874Y+075683X0205Y0590R090 S1      
327P12V_MEM_CPU0    J68   -145 M      A01X+171260Y+075683X0205Y0590R090 S1      
327P12V_MEM_CPU0    J68   -146 M      A01X+171260Y+076018X0205Y0590R090 S1      
327P12V_MEM_CPU0    J18   -1   M      A01X+169904Y+075683X0205Y0590R090 S1      
327P12V_MEM_CPU0    J18   -145 M      A01X+168290Y+075683X0205Y0590R090 S1      
327P12V_MEM_CPU0    J18   -146 M      A01X+168290Y+076018X0205Y0590R090 S1      
327P12V_MEM_CPU0    C89   -1          A18X+121361Y+075850X0400Y0500R180 S2      
317P12V_MEM_CPU0    VIA   -    MD0100PA00X+121460Y+075956X0190Y         S0      
327P12V_MEM_CPU0    J1    -1          A01X+121011Y+075683X0205Y0590R090 S1      
317P12V_MEM_CPU0    VIA   -    MD0100PA00X+118947Y+075683X0190Y    R180 S0      
327P12V_MEM_CPU0    C142  -1   M      A18X+119047Y+075850X0400Y0500     S2      
317P12V_MEM_CPU0    VIA   -    MD0100PA00X+118947Y+076018X0190Y    R180 S0      
327P12V_MEM_CPU0    J1    -146        A01X+119397Y+076018X0205Y0590R090 S1      
327P12V_MEM_CPU0    J1    -145        A01X+119397Y+075683X0205Y0590R090 S1      
327P12V_MEM_CPU0    C143  -1          A18X+118391Y+075850X0400Y0500R180 S2      
317P12V_MEM_CPU0    VIA   -    MD0100PA00X+118491Y+075683X0190Y    R180 S0      
327P12V_MEM_CPU0    J15   -1          A01X+118041Y+075683X0205Y0590R090 S1      
317P12V_MEM_CPU0    VIA   -    MD0100PA00X+115977Y+076018X0190Y    R180 S0      
327P12V_MEM_CPU0    C145  -1   M      A18X+116077Y+075850X0400Y0500     S2      
317P12V_MEM_CPU0    VIA   -    MD0100PA00X+115977Y+075683X0190Y    R180 S0      
327P12V_MEM_CPU0    J15   -146        A01X+116427Y+076018X0205Y0590R090 S1      
327P12V_MEM_CPU0    J15   -145        A01X+116427Y+075683X0205Y0590R090 S1      
327P12V_MEM_CPU0    C147  -1          A18X+115421Y+075850X0400Y0500R180 S2      
317P12V_MEM_CPU0    VIA   -    MD0100PA00X+115521Y+075683X0190Y         S0      
327P12V_MEM_CPU0    J17   -1          A01X+115071Y+075683X0205Y0590R090 S1      
317P12V_MEM_CPU0    VIA   -    MD0100PA00X+113007Y+076018X0190Y         S0      
327P12V_MEM_CPU0    C146  -1   M      A18X+113107Y+075850X0400Y0500     S2      
317P12V_MEM_CPU0    VIA   -    MD0100PA00X+113007Y+075683X0190Y         S0      
327P12V_MEM_CPU0    J17   -146        A01X+113457Y+076018X0205Y0590R090 S1      
327P12V_MEM_CPU0    J17   -145        A01X+113457Y+075683X0205Y0590R090 S1      
327P12V_MEM_CPU0    C150  -1          A18X+112451Y+075850X0400Y0500R180 S2      
317P12V_MEM_CPU0    VIA   -    MD0100PA00X+112551Y+075683X0190Y         S0      
327P12V_MEM_CPU0    J19   -1          A01X+112101Y+075683X0205Y0590R090 S1      
317P12V_MEM_CPU0    VIA   -    MD0100PA00X+110037Y+076018X0190Y         S0      
327P12V_MEM_CPU0    C149  -1   M      A18X+110137Y+075850X0400Y0500     S2      
317P12V_MEM_CPU0    VIA   -    MD0100PA00X+110037Y+075683X0190Y         S0      
327P12V_MEM_CPU0    J19   -146        A01X+110487Y+076018X0205Y0590R090 S1      
327P12V_MEM_CPU0    J19   -145        A01X+110487Y+075683X0205Y0590R090 S1      
327P12V_MEM_CPU0    C151  -1          A18X+109481Y+075850X0400Y0500R180 S2      
317P12V_MEM_CPU0    VIA   -    MD0100PA00X+109581Y+075683X0190Y         S0      
327P12V_MEM_CPU0    J21   -1          A01X+109131Y+075683X0205Y0590R090 S1      
317P12V_MEM_CPU0    VIA   -    MD0100PA00X+107067Y+076018X0190Y         S0      
327P12V_MEM_CPU0    C153  -1   M      A18X+107167Y+075850X0400Y0500     S2      
317P12V_MEM_CPU0    VIA   -    MD0100PA00X+107067Y+075683X0190Y         S0      
327P12V_MEM_CPU0    J21   -146        A01X+107517Y+076018X0205Y0590R090 S1      
327P12V_MEM_CPU0    J21   -145        A01X+107517Y+075683X0205Y0590R090 S1      
327P12V_MEM_CPU0    C154  -1          A18X+106511Y+075850X0400Y0500R180 S2      
317P12V_MEM_CPU0    VIA   -    MD0100PA00X+106611Y+075683X0190Y         S0      
327P12V_MEM_CPU0    J23   -1          A01X+106161Y+075683X0205Y0590R090 S1      
317P12V_MEM_CPU0    VIA   -    M      A01X+118226Y+063237X0200Y         S2      
017P12V_MEM_CPU0    VIA   -    M      A18X+118226Y+063237X0260Y         S2      
017P12V_MEM_CPU0          -    MD0100PA00X+118226Y+063237                       
327P12V_MEM_CPU0    R1442 -1          A01X+040618Y+050468X0198Y0197R270 S1      
317P12V_MEM_CPU0    VIA   -    MD0100PA00X+040618Y+050790X0200Y    R180 S0      
317P12V_MEM_CPU0    VIA   -    MD0100PA00X+104096Y+076018X0190Y         S0      
327P12V_MEM_CPU0    C155  -1   M      A18X+104196Y+075850X0400Y0500     S2      
317P12V_MEM_CPU0    VIA   -    MD0100PA00X+104096Y+075683X0190Y         S0      
327P12V_MEM_CPU0    J23   -146        A01X+104546Y+076018X0205Y0590R090 S1      
327P12V_MEM_CPU0    J23   -145        A01X+104546Y+075683X0205Y0590R090 S1      
327m2091            D88   -C          A01X+123009Y+027785X0240Y0280R090 S1      
327m2091            Q87   -3          A18X+123266Y+028695X0170Y0200R270 S2      
317m2091            VIA   -    M      A01X+123009Y+028295X0300Y         S1      
017m2091            VIA   -    M      A18X+123009Y+028295X0200Y         S1      
017m2091                  -    MD0100PA00X+123009Y+028295                       
317m2092            VIA   -    M      A01X+123009Y+026901X0200Y         S2      
017m2092            VIA   -    M      A18X+123009Y+026901X0260Y         S2      
017m2092                  -    MD0100PA00X+123009Y+026901                       
327m2092            D88   -A          A01X+123009Y+027411X0240Y0280R090 S1      
327m2092            R3069 -1          A18X+123009Y+026421X0198Y0197R090 S2      
327m2093            D91   -C          A01X+125409Y+027785X0240Y0280R090 S1      
317m2093            VIA   -    M      A01X+125409Y+028295X0300Y         S1      
017m2093            VIA   -    M      A18X+125409Y+028295X0200Y         S1      
017m2093                  -    MD0100PA00X+125409Y+028295                       
327m2093            Q78   -6          A18X+125718Y+029207X0170Y0200R270 S2      
317m2094            VIA   -    M      A01X+125409Y+026901X0200Y         S2      
017m2094            VIA   -    M      A18X+125409Y+026901X0260Y         S2      
017m2094                  -    MD0100PA00X+125409Y+026901                       
327m2094            D91   -A          A01X+125409Y+027411X0240Y0280R090 S1      
327m2094            R3071 -1          A18X+125409Y+026421X0198Y0197R090 S2      
327m2095            VIA   -    M      A01X+068330Y+043832X0300Y    R090 S1      
327m2095            R6095 -1          A01X+067558Y+043386X0198Y0197R180 S1      
327m2095            U18   -B6         A01X+070048Y+043564X0160Y    R090 S1      
327m2096            R4557 -2          A01X+080636Y+045934X0198Y0197R180 S1      
317m2096            VIA   -    M      A01X+080275Y+045934X0200Y         S2      
017m2096            VIA   -    M      A18X+080275Y+045934X0260Y         S2      
017m2096                  -    MD0100PA00X+080275Y+045934                       
327m2096            U18   -T12        A01X+074458Y+045454X0160Y    R090 S1      
317m2096            VIA   -    MD0100PA00X+074611Y+045607X0180Y    R090 S0      
327HGX_DETECT_N_R   R4556 -1          A01X+080614Y+044980X0198Y0197     S1      
317HGX_DETECT_N_R   VIA   -    M      A01X+080253Y+044980X0200Y         S2      
017HGX_DETECT_N_R   VIA   -    M      A18X+080253Y+044980X0260Y         S2      
017HGX_DETECT_N_R         -    MD0100PA00X+080253Y+044980                       
327HGX_DETECT_N_R   U18   -U13        A01X+074772Y+045769X0160Y    R090 S1      
317HGX_DETECT_N_R   VIA   -    MD0100PA00X+074926Y+045922X0180Y    R090 S0      
327m2097            R3485 -1          A18X+077778Y+048334X0198Y0197R180 S2      
327m2097            VIA   -    M      A18X+077009Y+047854X0260Y    R090 S2      
327m2097            U18   -W15        A01X+075402Y+046399X0160Y    R090 S1      
317m2097            VIA   -    MD0100PA00X+075556Y+046552X0180Y    R090 S0      
327m2098            VIA   -    M      A01X+065102Y+046986X0300Y    R090 S1      
327m2098            R3486 -1          A01X+064622Y+046986X0198Y0197R180 S1      
327m2098            U18   -AB16       A01X+076347Y+046714X0160Y    R090 S1      
317m2098            VIA   -    MD0100PA00X+076501Y+046867X0180Y    R090 S0      
317m2098            VIA   -    MD0100PA00X+066200Y+046986X0200Y    R270 S0      
317m2099            VIA   -    M      A01X+076598Y+041441X0200Y         S2      
017m2099            VIA   -    M      A18X+076598Y+041441X0260Y         S2      
017m2099                  -    MD0100PA00X+076598Y+041441                       
327m2099            R3477 -2          A01X+077550Y+039644X0198Y0197R090 S1      
327m2099            U18   -AB2        A01X+076347Y+042304X0160Y    R090 S1      
317m2100            VIA   -    M      A01X+081600Y+046358X0300Y         S1      
017m2100            VIA   -    M      A18X+081600Y+046358X0200Y         S1      
017m2100                  -    MD0100PA00X+081600Y+046358                       
327m2100            U18   -AA15       A01X+076032Y+046399X0160Y    R090 S1      
317m2100            VIA   -    MD0100PA00X+076186Y+046552X0180Y    R090 S0      
327m2100            R3481 -1          A01X+082078Y+046358X0198Y0197     S1      
327m2101            R3476 -1          A18X+077508Y+047934X0198Y0197R180 S2      
327m2101            VIA   -    M      A18X+076789Y+046620X0260Y    R090 S2      
327m2101            U18   -W14        A01X+075402Y+046084X0160Y    R090 S1      
317m2101            VIA   -    MD0100PA00X+075556Y+046237X0180Y    R090 S0      
327GPU_FPGA_RST_N   U18   -V7         A01X+075087Y+043879X0160Y    R090 S1      
317GPU_FPGA_RST_N   VIA   -    MD0100PA00X+075241Y+043726X0180Y    R090 S0      
327GPU_FPGA_RST_N   R4608 -2          A01X+082084Y+044980X0198Y0197R180 S1      
317GPU_FPGA_RST_N   VIA   -    M      A01X+081611Y+044980X0300Y         S1      
017GPU_FPGA_RST_N   VIA   -    M      A18X+081611Y+044980X0200Y         S1      
017GPU_FPGA_RST_N         -    MD0100PA00X+081611Y+044980                       
327m2102            VIA   -    M      A01X+077746Y+048334X0300Y         S1      
327m2102            R3324 -1          A01X+079009Y+048346X0198Y0197     S1      
327m2102            U18   -AB19       A01X+076347Y+047659X0160Y    R090 S1      
327m2103            R3484 -1          A18X+078958Y+048334X0198Y0197R180 S2      
317m2103            VIA   -    MD0100PA00X+078636Y+048357X0200Y    R180 S0      
327m2103            U18   -Y15        A01X+075717Y+046399X0160Y    R090 S1      
317m2103            VIA   -    MD0100PA00X+075871Y+046552X0180Y    R090 S2      
317m2104            VIA   -    MD0100PA00X+078700Y+043548X0200Y    R180 S2      
327m2104            R3478 -2          A01X+078958Y+043534X0198Y0197R180 S1      
327m2104            U18   -AA4        A01X+076032Y+042934X0160Y    R090 S1      
317m2104            VIA   -    MD0100PA00X+076186Y+042781X0180Y    R090 S0      
327m2105            U18   -AA5        A01X+076032Y+043249X0160Y    R090 S1      
317m2105            VIA   -    MD0100PA00X+076186Y+043096X0180Y    R090 S0      
317m2105            VIA   -    M      A01X+080227Y+043537X0200Y         S2      
017m2105            VIA   -    M      A18X+080227Y+043537X0260Y         S2      
017m2105                  -    MD0100PA00X+080227Y+043537                       
327m2105            R3483 -2          A01X+080643Y+043563X0198Y0197R180 S1      
327m2106            R3505 -1          A01X+082078Y+046757X0198Y0197     S1      
317m2106            VIA   -    M      A01X+081641Y+046757X0200Y         S2      
017m2106            VIA   -    M      A18X+081641Y+046757X0260Y         S2      
017m2106                  -    MD0100PA00X+081641Y+046757                       
327m2106            U18   -AA16       A01X+076032Y+046714X0160Y    R090 S1      
317m2106            VIA   -    MD0100PA00X+076186Y+046867X0180Y    R090 S0      
327m2107            R3482 -1          A01X+076450Y+052429X0198Y0197R090 S1      
317m2107            VIA   -    M      A01X+076460Y+051702X0300Y    R180 S1      
017m2107            VIA   -    M      A18X+076460Y+051702X0200Y    R180 S1      
017m2107                  -    MD0100PA00X+076460Y+051702                       
327m2107            U18   -T15        A01X+074458Y+046399X0160Y    R090 S1      
317m2107            VIA   -    MD0100PA00X+074611Y+046552X0180Y    R090 S0      
327m2108            VIA   -    M      A01X+078390Y+047096X0300Y         S1      
327m2108            R4157 -1          A01X+078975Y+046765X0198Y0197     S1      
327m2108            U18   -AA14       A01X+076032Y+046084X0160Y    R090 S1      
327m2109            R3479 -1          A01X+077508Y+049534X0198Y0197     S1      
317m2109            VIA   -    MD0100PA00X+077243Y+049534X0200Y    R090 S0      
327m2109            U18   -Y19        A01X+075717Y+047659X0160Y    R090 S1      
317m2109            VIA   -    MD0100PA00X+075871Y+047812X0180Y    R090 S2      
317m2110            VIA   -    M      A01X+080155Y+046332X0300Y         S1      
017m2110            VIA   -    M      A18X+080155Y+046332X0200Y         S1      
017m2110                  -    MD0100PA00X+080155Y+046332                       
327m2110            R3480 -1          A01X+080623Y+046358X0198Y0197     S1      
327m2110            U18   -AB15       A01X+076347Y+046399X0160Y    R090 S1      
317m2110            VIA   -    MD0100PA00X+076501Y+046552X0180Y    R090 S0      
327m2111            R4148 -1          A01X+078958Y+046334X0198Y0197     S1      
327m2111            U18   -AB14       A01X+076347Y+046084X0160Y    R090 S1      
327m2111            VIA   -    M      A01X+078662Y+046558X0300Y    R090 S1      
327m2112            R4172 -1          A01X+078958Y+045134X0198Y0197     S1      
317m2112            VIA   -    M      A01X+078689Y+045134X0200Y    R180 S2      
017m2112            VIA   -    M      A18X+078689Y+045134X0260Y    R180 S2      
017m2112                  -    MD0100PA00X+078689Y+045134                       
327m2112            U18   -V13        A01X+075087Y+045769X0160Y    R090 S1      
317m2112            VIA   -    MD0100PA00X+075241Y+045922X0180Y    R090 S0      
327m2113            R4147 -1          A01X+077508Y+047634X0198Y0197     S1      
317m2113            VIA   -    MD0100PA00X+077243Y+047534X0200Y    R090 S0      
327m2113            U18   -V14        A01X+075087Y+046084X0160Y    R090 S1      
317m2113            VIA   -    MD0100PA00X+075241Y+046237X0180Y    R090 S2      
327m2114            VIA   -           A01X+078380Y+045620X0300Y         S1      
327m2114            R4171 -1   M      A01X+077508Y+045534X0198Y0197     S1      
327m2114            U18   -AA12       A01X+076032Y+045454X0160Y    R090 S1      
327m2115            U18   -F12        A01X+071308Y+045454X0160Y    R090 S1      
317m2115            VIA   -    MD0100PA00X+071154Y+045607X0180Y    R090 S0      
327m2115            R4146 -1          A01X+080647Y+048016X0198Y0197     S1      
317m2115            VIA   -    M      A01X+080275Y+048016X0200Y         S2      
017m2115            VIA   -    M      A18X+080275Y+048016X0260Y         S2      
017m2115                  -    MD0100PA00X+080275Y+048016                       
317m2116            VIA   -    M      A01X+068731Y+050045X0200Y         S2      
017m2116            VIA   -    M      A18X+068731Y+050045X0260Y         S2      
017m2116                  -    MD0100PA00X+068731Y+050045                       
327m2116            R4145 -1          A01X+068731Y+050779X0198Y0197R090 S1      
327m2116            U18   -G12        A01X+071623Y+045454X0160Y    R090 S1      
317m2116            VIA   -    MD0100PA00X+071469Y+045607X0180Y    R090 S0      
327m2117            VIA   -    M      A18X+077430Y+045879X0260Y    R090 S2      
327m2117            R4170 -1          A18X+077508Y+046334X0198Y0197R180 S2      
327m2117            U18   -AB12       A01X+076347Y+045454X0160Y    R090 S1      
317m2117            VIA   -    MD0100PA00X+076501Y+045607X0180Y    R090 S0      
317m2118            VIA   -    M      A01X+079746Y+047616X0200Y         S2      
017m2118            VIA   -    M      A18X+079746Y+047616X0260Y         S2      
017m2118                  -    MD0100PA00X+079746Y+047616                       
327m2118            U18   -T13        A01X+074458Y+045769X0160Y    R090 S1      
317m2118            VIA   -    MD0100PA00X+074611Y+045922X0180Y    R090 S0      
327m2118            R4144 -1          A01X+080647Y+047616X0198Y0197     S1      
327m2119            R4143 -1          A18X+077508Y+047534X0198Y0197R180 S2      
327m2119            VIA   -    M      A18X+076361Y+046197X0260Y    R090 S2      
327m2119            U18   -W13        A01X+075402Y+045769X0160Y    R090 S1      
317m2119            VIA   -    MD0100PA00X+075556Y+045922X0180Y    R090 S0      
317m2120            VIA   -    MD0100PA00X+069580Y+043726X0180Y    R090 S2      
327m2120            R6096 -1          A01X+065958Y+042986X0198Y0197R180 S1      
327m2120            U18   -A7         A01X+069733Y+043879X0160Y    R090 S1      
317m2120            VIA   -    MD0100PA00X+066200Y+042984X0200Y         S0      
327FM_SWB_PWR_EN    VIA   -    M      A01X+076630Y+040428X0300Y         S1      
327FM_SWB_PWR_EN    R2261 -2          A01X+077150Y+039644X0198Y0197R090 S1      
327FM_SWB_PWR_EN    U18   -AA2        A01X+076032Y+042304X0160Y    R090 S1      
317m2121            VIA   -    MD0100PA00X+076501Y+047497X0180Y    R090 S2      
327m2121            U18   -AB18       A01X+076347Y+047344X0160Y    R090 S1      
327m2121            R2663 -1          A01X+080643Y+049134X0198Y0197     S1      
317m2121            VIA   -    MD0100PA00X+080175Y+049134X0200Y         S0      
327m2122            R2844 -1          A01X+080636Y+048734X0198Y0197     S1      
317m2122            VIA   -    M      A01X+080275Y+048734X0200Y         S2      
017m2122            VIA   -    M      A18X+080275Y+048734X0260Y         S2      
017m2122                  -    MD0100PA00X+080275Y+048734                       
327m2122            U18   -AB17       A01X+076347Y+047029X0160Y    R090 S1      
317m2122            VIA   -    MD0100PA00X+076501Y+047182X0180Y    R090 S0      
317m2123            VIA   -    MD0100PA00X+077243Y+048734X0200Y    R090 S2      
327m2123            R11667-1          A01X+077508Y+048734X0198Y0197     S1      
327m2123            U18   -Y18        A01X+075717Y+047344X0160Y    R090 S1      
317m2123            VIA   -    MD0100PA00X+075871Y+047497X0180Y    R090 S0      
327m2124            R3066 -1          A01X+080636Y+047134X0198Y0197     S1      
327m2124            U18   -AA17       A01X+076032Y+047029X0160Y    R090 S1      
317m2124            VIA   -    MD0100PA00X+076186Y+047182X0180Y    R090 S0      
317m2124            VIA   -    M      A01X+080187Y+047134X0200Y         S2      
017m2124            VIA   -    M      A18X+080187Y+047134X0260Y         S2      
017m2124                  -    MD0100PA00X+080187Y+047134                       
317FM_GPU_PWR_EN    VIA   -    M      A01X+081624Y+043928X0300Y         S1      
017FM_GPU_PWR_EN    VIA   -    M      A18X+081624Y+043928X0200Y         S1      
017FM_GPU_PWR_EN          -    MD0100PA00X+081624Y+043928                       
327FM_GPU_PWR_EN    R2262 -2          A01X+082097Y+043928X0198Y0197R180 S1      
327FM_GPU_PWR_EN    U18   -W6         A01X+075402Y+043564X0160Y    R090 S1      
317FM_GPU_PWR_EN    VIA   -    MD0100PA00X+075556Y+043411X0180Y    R090 S0      
327m2125            R2664 -1          A01X+082078Y+047134X0198Y0197     S1      
317m2125            VIA   -    M      A01X+081611Y+047134X0300Y         S1      
017m2125            VIA   -    M      A18X+081611Y+047134X0200Y         S1      
017m2125                  -    MD0100PA00X+081611Y+047134                       
327m2125            U18   -AA18       A01X+076032Y+047344X0160Y    R090 S1      
317m2125            VIA   -    MD0100PA00X+076186Y+047497X0180Y    R090 S0      
327m2126            R6116 -1          A01X+063258Y+043788X0198Y0197R180 S1      
327m2126            VIA   -    M      A01X+065113Y+043652X0300Y    R090 S1      
327m2126            R6094 -1   M      A01X+064608Y+043786X0198Y0197R180 S1      
327m2126            U18   -A6         A01X+069733Y+043564X0160Y    R090 S1      
317m2127            VIA   -    MD0080PA00X+153026Y+116199X0160Y         S0      
327m2127            U25   -DH8        A01X+152842Y+116094X0177Y    R180 S1      
327m2127            VIA   -    M      A18X+161260Y+128451X0260Y    R180 S2      
327m2127            R5055 -2          A18X+160865Y+129759X0198Y0197R090 S2      
327m2127            R5056 -1   M      A18X+160865Y+129239X0198Y0197R090 S2      
317BMC_MONITER      VIA   -    M      A01X+081624Y+043534X0200Y         S2      
017BMC_MONITER      VIA   -    M      A18X+081624Y+043534X0260Y         S2      
017BMC_MONITER            -    MD0100PA00X+081624Y+043534                       
327BMC_MONITER      U18   -AB5        A01X+076347Y+043249X0160Y    R090 S1      
317BMC_MONITER      VIA   -    MD0100PA00X+076501Y+043096X0180Y    R090 S0      
327BMC_MONITER      R2845 -2          A01X+082084Y+043563X0198Y0197R180 S1      
327m2128            VIA   -    M      A18X+078154Y+048682X0260Y         S2      
327m2128            R2846 -1          A18X+078592Y+048752X0198Y0197R180 S2      
327m2128            U18   -V15        A01X+075087Y+046399X0160Y    R090 S1      
317m2128            VIA   -    MD0100PA00X+075241Y+046552X0180Y    R090 S0      
327m2129            J41   -OB9        A01X+073332Y+006516X0150Y0570R180 S1      
317m2129            VIA   -    M      A01X+073186Y+007494X0200Y    R180 S2      
017m2129            VIA   -    M      A18X+073186Y+007494X0260Y    R180 S2      
017m2129                  -    MD0100PA00X+073186Y+007494                       
327m2129            R6065 -1          A01X+072938Y+007494X0198Y0197R090 S1      
327TP_ADC128_INT    VIA   -           A01X+121061Y+016605X0300Y         S1      
327TP_ADC128_INT    U269  -6          A01X+122018Y+016728X0140Y0630R270 S1      
327m2130            VIA   -    M      A01X+120906Y+018119X0300Y         S1      
327m2130            R3671 -2          A01X+120559Y+018119X0198Y0197     S1      
327m2130            U269  -2          A01X+122018Y+017751X0140Y0630R270 S1      
327m2131            VIA   -    M      A01X+121289Y+017647X0300Y         S1      
327m2131            R3672 -2          A01X+120559Y+017719X0198Y0197     S1      
327m2131            U269  -3          A01X+122018Y+017495X0140Y0630R270 S1      
327m2132            R6077 -2          A01X+153785Y+056269X0198Y0197R270 S1      
317m2132            VIA   -    M      A01X+153282Y+055598X0200Y         S2      
017m2132            VIA   -    M      A18X+153282Y+055598X0260Y         S2      
017m2132                  -    MD0100PA00X+153282Y+055598                       
317m2132            VIA   -    MD0100PA00X+162715Y+016892X0200Y         S0      
317m2132            VIA   -    MD0100PA00X+131301Y+013984X0200Y         S0      
327m2132            R1792 -1          A01X+129827Y+014174X0198Y0197R180 S1      
317m2132            VIA   -    MD0100PA00X+120001Y+018119X0200Y         S0      
327m2132            R3671 -1          A01X+120244Y+018119X0198Y0197     S1      
327m2133            R6076 -2          A01X+152785Y+056269X0198Y0197R270 S1      
317m2133            VIA   -    M      A01X+152785Y+056026X0200Y         S2      
017m2133            VIA   -    M      A18X+152785Y+056026X0260Y         S2      
017m2133                  -    MD0100PA00X+152785Y+056026                       
327m2133            R1793 -1          A01X+129827Y+013774X0198Y0197R180 S1      
317m2133            VIA   -    MD0100PA00X+131301Y+013582X0200Y         S0      
317m2133            VIA   -    MD0100PA00X+120004Y+017719X0200Y         S0      
327m2133            R3672 -1          A01X+120244Y+017719X0198Y0197     S1      
317m2133            VIA   -    MD0100PA00X+163146Y+016788X0200Y         S0      
327m2134            R1498 -2          A01X+099281Y+047918X0198Y0197R180 S1      
317m2134            PJ1   -2    D0410PA00X+154038Y+058135X0610Y    R270 S3      
327m2134            R6077 -1   M      A01X+153785Y+056584X0198Y0197R270 S1      
317m2134            VIA   -    MD0100PA00X+153456Y+056494X0200Y    R090 S0      
317m2134            VIA   -    MD0100PA00X+098679Y+048014X0200Y         S0      
317m2134            VIA   -    MD0100PA00X+147140Y+048758X0200Y         S0      
317m2134            VIA   -    MD0100PA00X+147526Y+053066X0200Y         S0      
327m2134            R8309 -1   M      A18X+147526Y+054090X0198Y0197R270 S2      
327m2135            R1497 -2          A01X+099281Y+047368X0198Y0197R180 S1      
317m2135            PJ1   -3    D0410PA00X+153038Y+058135X0610Y    R270 S3      
327m2135            R6076 -1   M      A01X+152785Y+056584X0198Y0197R270 S1      
317m2135            VIA   -    MD0100PA00X+153273Y+056295X0200Y    R090 S0      
317m2135            VIA   -    MD0100PA00X+146540Y+048758X0200Y         S0      
317m2135            VIA   -    M      A01X+098865Y+046532X0200Y         S2      
017m2135            VIA   -    M      A18X+098865Y+046532X0260Y         S2      
017m2135                  -    MD0100PA00X+098865Y+046532                       
317m2135            VIA   -    MD0100PA00X+146583Y+053066X0200Y         S0      
327m2135            R8308 -1   M      A18X+146983Y+053783X0198Y0197R270 S2      
317m2136            VIA   -    M      A01X+034498Y+019930X0200Y         S2      
017m2136            VIA   -    M      A18X+034498Y+019930X0260Y         S2      
017m2136                  -    MD0100PA00X+034498Y+019930                       
327m2136            R1174 -1          A01X+029295Y+024949X0198Y0197R270 S1      
317m2136            VIA   -    MD0100PA00X+029628Y+024239X0200Y         S0      
327m2136            U18   -AA19       A01X+076032Y+047659X0160Y    R090 S1      
317m2136            VIA   -    MD0100PA00X+076186Y+047812X0180Y    R090 S0      
317m2136            VIA   -    MD0100PA00X+068058Y+020710X0200Y         S0      
317m2137            VIA   -    MD0100PA00X+155820Y+048679X0200Y         S0      
317m2137            VIA   -    MD0100PA00X+082734Y+041934X0200Y    R180 S0      
327m2137            R6118 -2          A01X+082399Y+041934X0198Y0197     S1      
317m2137            VIA   -    M      A01X+159630Y+053634X0200Y    R180 S2      
017m2137            VIA   -    M      A18X+159630Y+053634X0260Y    R180 S2      
017m2137                  -    MD0100PA00X+159630Y+053634                       
327m2137            R2346 -2          A01X+159872Y+053634X0198Y0197R180 S1      
327m2137            Q50   -3   M      A01X+159041Y+053634X0170Y0200R270 S1      
327m2138            VIA   -    M      A01X+157793Y+053123X0300Y    R180 S1      
327m2138            Q50   -5          A01X+158293Y+053378X0170Y0200R270 S1      
327m2138            Q50   -6   M      A01X+158293Y+053123X0170Y0200R270 S1      
327m2138            R2344 -2          A01X+157322Y+053122X0198Y0197     S1      
327PWRGD_P3V3_R2    R1362 -2          A01X+073381Y+052416X0198Y0197R270 S1      
327PWRGD_P3V3_R2    VIA   -    M      A01X+073634Y+051460X0300Y    R090 S1      
327PWRGD_P3V3_R2    U18   -M16        A01X+073198Y+046714X0160Y    R090 S1      
317PWRGD_P3V3_R2    VIA   -    MD0100PA00X+073867Y+049444X0200Y    R180 S0      
317PWRGD_P3V3_R2    VIA   -    MD0100PA00X+073351Y+046867X0180Y    R090 S0      
317PWRGD_P3V3_R1    VIA   -    M      A01X+060709Y+052817X0200Y         S2      
017PWRGD_P3V3_R1    VIA   -    M      A18X+060709Y+052817X0260Y         S2      
017PWRGD_P3V3_R1          -    MD0100PA00X+060709Y+052817                       
327PWRGD_P3V3_R1    R1362 -1          A01X+073381Y+052731X0198Y0197R270 S1      
327PWRGD_P3V3_R1    R1493 -2          A01X+042478Y+050137X0198Y0197R270 S1      
327PWRGD_P3V3_R1    Q27   -3          A01X+042722Y+049032X0120Y0490     S1      
317PWRGD_P3V3_R1    VIA   -    MD0100PA00X+042478Y+049657X0200Y         S0      
317PWRGD_P3V3_R1    VIA   -    MD0100PA00X+073250Y+052986X0200Y         S0      
327m2139            R1492 -2          A01X+042978Y+047189X0198Y0197R090 S1      
327m2139            VIA   -    M      A01X+042978Y+047669X0300Y    R180 S1      
327m2139            Q27   -6          A01X+043234Y+048294X0120Y0490     S1      
327m2139            Q27   -5   M      A01X+042978Y+048294X0120Y0490     S1      
327PWRGD_P3V3_EN    R6500 -2          A01X+043950Y+049658X0198Y0197R090 S1      
327PWRGD_P3V3_EN    VIA   -    M      A01X+042978Y+049657X0300Y         S1      
327PWRGD_P3V3_EN    Q27   -2          A01X+042978Y+049032X0120Y0490     S1      
327m2140            J41   -A50        A01X+055806Y+005354X0150Y0570R180 S1      
317m2140            VIA   -    M      A01X+055635Y+004154X0200Y         S2      
017m2140            VIA   -    M      A18X+055635Y+004154X0260Y         S2      
017m2140                  -    MD0100PA00X+055635Y+004154                       
327m2140            R6071 -2          A01X+058219Y+008625X0198Y0197R090 S1      
317m2140            VIA   -    MD0100PA00X+058475Y+008625X0200Y         S0      
327P5V_ADC_TIC      R3686 -2          A01X+126944Y+017155X0180Y0200     S1      
327P5V_ADC_TIC      VIA   -    M      A01X+125311Y+017405X0300Y         S1      
327P5V_ADC_TIC      U269  -13         A01X+124223Y+017240X0140Y0630R270 S1      
327P5V_ADC_TIC      C2049 -1   M      A01X+125803Y+017205X0198Y0197     S1      
327P5V_ADC_MAM      R3685 -2          A01X+127574Y+017155X0180Y0200R180 S1      
317P5V_ADC_MAM      VIA   -    M      A01X+127814Y+017155X0200Y         S2      
017P5V_ADC_MAM      VIA   -    M      A18X+127814Y+017155X0260Y         S2      
017P5V_ADC_MAM            -    MD0100PA00X+127814Y+017155                       
317P5V_ADC_MAM      VIA   -    MD0100PA00X+125269Y+012474X0200Y         S0      
327P5V_ADC_MAM      C2044 -1          A01X+124477Y+012374X0198Y0197R180 S1      
327P5V_ADC_MAM      U193  -8          A01X+125984Y+012755X0150Y0630R090 S1      
327P5V_ADC          R3685 -1          A01X+127259Y+017155X0180Y0200R180 S1      
327P5V_ADC          R3686 -1   M      A01X+127259Y+017155X0180Y0200     S1      
327P5V_ADC          R3005 -2          A01X+129603Y+017155X0198Y0197R180 S1      
327P5V_ADC          R1791 -1   M      A01X+128653Y+017155X0198Y0197     S1      
327P5V_ADC          VIA   -    M      A01X+128079Y+017378X0300Y         S1      
327m2141            R3688 -2          A01X+126944Y+015805X0180Y0200     S1      
327m2141            VIA   -    M      A01X+124911Y+016355X0300Y         S1      
327m2141            U269  -10         A01X+124223Y+016472X0140Y0630R270 S1      
327m2141            C2050 -1   M      A01X+125803Y+016005X0198Y0197     S1      
327m2142            R3687 -2          A01X+127574Y+015805X0180Y0200R180 S1      
327m2142            U193  -11         A01X+128074Y+013255X0150Y0630R090 S1      
327m2142            VIA   -    M      A01X+129019Y+013274X0300Y         S1      
317m2142            VIA   -    MD0100PA00X+130509Y+013175X0200Y         S0      
327m2142            C2045 -1   M      A01X+129512Y+013374X0198Y0197     S1      
317m2142            VIA   -    MD0100PA00X+127821Y+015603X0200Y         S0      
327m2143            R3264 -2          A01X+060334Y+014164X0198Y0197     S1      
317m2143            VIA   -    MD0100PA00X+060334Y+013913X0200Y    R090 S0      
317m2143            VIA   -    MD0100PA00X+076500Y+018650X0200Y         S0      
327m2143            R6062 -1          A18X+076750Y+038394X0198Y0197R090 S2      
317m2143            VIA   -    MD0100PA00X+076750Y+038686X0200Y         S0      
327m2143            U18   -V17        A01X+075087Y+047029X0160Y    R090 S1      
317m2143            VIA   -    MD0100PA00X+075241Y+047182X0180Y    R090 S0      
317m2143            VIA   -    M      A01X+023610Y+015200X0200Y    R180 S2      
017m2143            VIA   -    M      A18X+023610Y+015200X0260Y    R180 S2      
017m2143                  -    MD0100PA00X+023610Y+015200                       
327m2143            R4060 -1          A01X+023360Y+015200X0198Y0197R090 S1      
317m2143            VIA   -    MD0100PA00X+039088Y+028416X0200Y    R270 S0      
327m2143            R3631 -1          A01X+038416Y+028737X0198Y0197R180 S1      
327m2144            L15   -1          A01X+129508Y+015750X0280Y0320R270 S1      
327m2144            VIA   -           A01X+128769Y+014624X0300Y         S1      
327m2144            C1768 -1          A01X+129508Y+015122X0400Y0500R180 S1      
327m2144            C1757 -1          A01X+129512Y+014574X0198Y0197     S1      
327m2144            U193  -16         A01X+128074Y+014505X0150Y0630R090 S1      
327m2145            R3682 -2          A01X+126944Y+016205X0180Y0200     S1      
327m2145            U269  -11         A01X+124223Y+016728X0140Y0630R270 S1      
327m2145            VIA   -    M      A01X+125311Y+016728X0300Y         S1      
327m2145            C2047 -1   M      A01X+125803Y+016405X0198Y0197     S1      
327m2146            R3681 -2          A01X+127574Y+016205X0180Y0200R180 S1      
327m2146            VIA   -    M      A01X+128769Y+012824X0300Y         S1      
327m2146            U193  -10         A01X+128074Y+013005X0150Y0630R090 S1      
317m2146            VIA   -    MD0100PA00X+130509Y+012783X0200Y         S0      
327m2146            C2042 -1   M      A01X+129512Y+012974X0198Y0197     S1      
317m2146            VIA   -    MD0100PA00X+127821Y+016103X0200Y         S0      
327P3V3_AUX_ADC     R3681 -1          A01X+127259Y+016205X0180Y0200R180 S1      
327P3V3_AUX_ADC     R3682 -1   M      A01X+127259Y+016205X0180Y0200     S1      
327P3V3_AUX_ADC     VIA   -    M      A01X+128113Y+016182X0300Y         S1      
327P3V3_AUX_ADC     R2907 -2          A01X+129603Y+016205X0198Y0197R180 S1      
327P3V3_AUX_ADC     R1785 -1   M      A01X+128653Y+016205X0198Y0197     S1      
327P3V3_ADC_TIC     R3684 -2          A01X+126944Y+016605X0180Y0200     S1      
327P3V3_ADC_TIC     C2048 -1   M      A01X+125803Y+016805X0198Y0197     S1      
327P3V3_ADC_TIC     VIA   -    M      A01X+124911Y+017055X0300Y         S1      
327P3V3_ADC_TIC     U269  -12         A01X+124223Y+016984X0140Y0630R270 S1      
327P3V3_ADC_MAM     R3683 -2          A01X+127574Y+016605X0180Y0200R180 S1      
327P3V3_ADC_MAM     U193  -9          A01X+128074Y+012755X0150Y0630R090 S1      
327P3V3_ADC_MAM     VIA   -    M      A01X+128459Y+012226X0300Y         S1      
317P3V3_ADC_MAM     VIA   -    MD0100PA00X+130509Y+012368X0200Y         S0      
327P3V3_ADC_MAM     C2043 -1   M      A01X+129512Y+012574X0198Y0197     S1      
317P3V3_ADC_MAM     VIA   -    MD0100PA00X+127814Y+016605X0200Y         S0      
327m2147            L16   -2          A01X+119591Y+018285X0280Y0320R270 S1      
327m2147            R3689 -1          A01X+120247Y+018894X0198Y0197     S1      
327m2147            U269  -5          A01X+122018Y+016984X0140Y0630R270 S1      
327m2147            VIA   -           A01X+121071Y+017105X0300Y         S1      
327m2147            C2051 -1          A01X+119528Y+017719X0198Y0197R180 S1      
327m2147            C2052 -1          A01X+119528Y+017319X0198Y0197R180 S1      
327P3V3_ADC         R3683 -1          A01X+127259Y+016605X0180Y0200R180 S1      
327P3V3_ADC         R3684 -1   M      A01X+127259Y+016605X0180Y0200     S1      
327P3V3_ADC         R2908 -2          A01X+129603Y+016605X0198Y0197R180 S1      
327P3V3_ADC         R2843 -1   M      A01X+128653Y+016605X0198Y0197     S1      
327P3V3_ADC         VIA   -    M      A01X+128090Y+016840X0300Y         S1      
327P1V581_PDB_ADC   R3688 -1          A01X+127259Y+015805X0180Y0200     S1      
327P1V581_PDB_ADC   R3687 -1   M      A01X+127259Y+015805X0180Y0200R180 S1      
327P1V581_PDB_ADC   VIA   -    M      A01X+126761Y+015003X0300Y         S1      
327P1V581_PDB_ADC   R4568 -1          A01X+127254Y+015003X0198Y0197     S1      
327P1V581_PDB_ADC   R4567 -2   M      A01X+127254Y+015403X0198Y0197R180 S1      
327m2148            R3862 -2          A01X+127259Y+017605X0180Y0200     S1      
327m2148            R3861 -2   M      A01X+127259Y+017605X0180Y0200R180 S1      
327m2148            C33   -1   M      A01X+125803Y+017605X0198Y0197     S1      
327m2148            VIA   -    M      A01X+124911Y+017705X0300Y         S1      
327m2148            U269  -14         A01X+124223Y+017495X0140Y0630R270 S1      
327m2149            R3859 -2          A01X+122812Y+012824X0180Y0200R180 S1      
327m2149            R3860 -2   M      A01X+122812Y+012824X0180Y0200     S1      
327m2149            C59   -1   M      A01X+124477Y+012824X0198Y0197R180 S1      
327m2149            VIA   -    M      A01X+124969Y+012924X0300Y         S1      
327m2149            U193  -7          A01X+125984Y+013005X0150Y0630R090 S1      
327m2150            R1164 -1          A01X+019871Y+016532X0198Y0197R180 S1      
317m2150            VIA   -    MD0100PA00X+023463Y+016674X0200Y         S0      
327m2150            R3630 -1          A01X+027580Y+012712X0198Y0197R270 S1      
317m2150            VIA   -    MD0100PA00X+027579Y+012960X0200Y         S0      
317m2150            VIA   -    MD0100PA00X+025659Y+013837X0200Y         S0      
327m2150            R4059 -1          A01X+025659Y+014088X0198Y0197     S1      
317m2150            VIA   -    MD0100PA00X+062576Y+016892X0200Y         S0      
317m2150            VIA   -    M      A01X+080176Y+049534X0200Y         S2      
017m2150            VIA   -    M      A18X+080176Y+049534X0260Y         S2      
017m2150                  -    MD0100PA00X+080176Y+049534                       
327m2150            R6061 -1          A01X+080654Y+049534X0198Y0197     S1      
327m2150            U18   -AA20       A01X+076032Y+047974X0160Y    R090 S1      
317m2150            VIA   -    MD0100PA00X+076186Y+048127X0180Y    R090 S0      
317m2150            VIA   -    MD0100PA00X+067932Y+020986X0200Y         S0      
327m2151            R3865 -2          A01X+127259Y+018056X0180Y0200     S1      
327m2151            R3866 -2   M      A01X+127259Y+018056X0180Y0200R180 S1      
327m2151            C37   -1   M      A01X+125803Y+018055X0198Y0197     S1      
327m2151            VIA   -    M      A01X+125311Y+018055X0300Y         S1      
327m2151            U269  -15         A01X+124223Y+017751X0140Y0630R270 S1      
327m2152            R3863 -2          A01X+122812Y+013274X0180Y0200R180 S1      
327m2152            R3864 -2   M      A01X+122812Y+013274X0180Y0200     S1      
327m2152            C2176 -1   M      A01X+124477Y+013274X0198Y0197R180 S1      
327m2152            VIA   -    M      A01X+125269Y+013355X0300Y         S1      
327m2152            U193  -6          A01X+125984Y+013255X0150Y0630R090 S1      
327m2153            R3942 -2   M      A18X+124246Y+016038X0180Y0200R270 S2      
327m2153            R3941 -2          A18X+124246Y+016038X0180Y0200R090 S2      
327m2153            U269  -9          A01X+124223Y+016216X0140Y0630R270 S1      
317m2153            VIA   -    M      A01X+124783Y+015984X0200Y         S2      
017m2153            VIA   -    M      A18X+124783Y+015984X0260Y         S2      
017m2153                  -    MD0100PA00X+124783Y+015984                       
327m2153            C2194 -1          A01X+125803Y+015573X0198Y0197     S1      
327m2154            R3939 -2   M      A18X+128203Y+013485X0180Y0200R270 S2      
327m2154            R3940 -2          A18X+128203Y+013485X0180Y0200R090 S2      
327m2154            C35   -1          A18X+129340Y+013441X0198Y0197R180 S2      
317m2154            VIA   -    M      A01X+128749Y+013416X0200Y         S2      
017m2154            VIA   -    M      A18X+128749Y+013416X0260Y         S2      
017m2154                  -    MD0100PA00X+128749Y+013416                       
327m2154            U193  -12         A01X+128074Y+013505X0150Y0630R090 S1      
327m2155            R3680 -2          A01X+126944Y+018499X0180Y0200     S1      
327m2155            VIA   -    M      A01X+124911Y+018405X0300Y         S1      
327m2155            U269  -16         A01X+124223Y+018007X0140Y0630R270 S1      
327m2155            C2046 -1   M      A01X+125803Y+018505X0198Y0197     S1      
327m2156            R3679 -2          A01X+127574Y+018499X0180Y0200R180 S1      
327m2156            C1344 -1          A01X+124477Y+013724X0198Y0197R180 S1      
317m2156            VIA   -    M      A01X+127814Y+018499X0200Y         S2      
017m2156            VIA   -    M      A18X+127814Y+018499X0260Y         S2      
017m2156                  -    MD0100PA00X+127814Y+018499                       
327m2156            U193  -5          A01X+125984Y+013505X0150Y0630R090 S1      
317m2156            VIA   -    MD0100PA00X+124943Y+013774X0200Y         S0      
327P12V_AUX_ADC     R3679 -1          A01X+127259Y+018499X0180Y0200R180 S1      
327P12V_AUX_ADC     R3680 -1   M      A01X+127259Y+018499X0180Y0200     S1      
327P12V_AUX_ADC     VIA   -    M      A01X+128157Y+018451X0300Y         S1      
327P12V_AUX_ADC     R1799 -2          A01X+129603Y+018405X0198Y0197R180 S1      
327P12V_AUX_ADC     R1800 -1   M      A01X+128653Y+018405X0198Y0197     S1      
327m2157            U193  -1          A01X+125984Y+014505X0150Y0630R090 S1      
327m2157            VIA   -    M      A01X+124969Y+014505X0300Y         S1      
327m2157            R2900 -2          A01X+124477Y+014524X0198Y0197     S1      
327MAX11617_VREF    C1767 -1          A01X+122419Y+014574X0400Y0500     S1      
327MAX11617_VREF    R2900 -1          A01X+124162Y+014524X0198Y0197     S1      
327MAX11617_VREF    C1347 -1   M      A01X+123427Y+014524X0198Y0197R180 S1      
327MAX11617_VREF    VIA   -    M      A01X+123069Y+015024X0300Y         S1      
327m2158            R3301 -1          A01X+064624Y+016186X0198Y0197     S1      
317m2158            VIA   -    MD0100PA00X+064380Y+016186X0200Y         S0      
327m2158            R1005 -1          A01X+062270Y+029273X0198Y0197R090 S1      
317m2158            VIA   -    M      A01X+062270Y+028530X0200Y         S2      
017m2158            VIA   -    M      A18X+062270Y+028530X0260Y         S2      
017m2158                  -    MD0100PA00X+062270Y+028530                       
317m2159            VIA   -    M      A01X+073150Y+036886X0200Y         S2      
017m2159            VIA   -    M      A18X+073150Y+036886X0260Y         S2      
017m2159                  -    MD0100PA00X+073150Y+036886                       
327m2159            U18   -L1         A01X+072883Y+041989X0160Y    R090 S1      
317m2159            VIA   -    MD0100PA00X+072729Y+041836X0180Y    R090 S0      
327m2159            R6075 -2          A01X+073150Y+036644X0198Y0197R090 S1      
327JTAG_SCM_TDO_R   J41   -A37        A01X+060574Y+005354X0150Y0570R180 S1      
327JTAG_SCM_TDO_R   R6068 -1          A18X+060857Y+003890X0180Y0200R270 S2      
327JTAG_SCM_TDO_R   R6067 -1          A18X+051440Y+019962X0180Y0200R270 S2      
317JTAG_SCM_TDO_R   VIA   -    MD0100PA00X+051731Y+020045X0200Y         S0      
317JTAG_SCM_TDO_R   VIA   -    M      A01X+060658Y+004353X0200Y         S2      
017JTAG_SCM_TDO_R   VIA   -    M      A18X+060658Y+004353X0260Y         S2      
017JTAG_SCM_TDO_R         -    MD0100PA00X+060658Y+004353                       
327JTAG_SCM_TDI_R   J41   -A36        A01X+060810Y+005354X0150Y0570R180 S1      
327JTAG_SCM_TDI_R   R6069 -1          A18X+060857Y+003260X0180Y0200R090 S2      
327JTAG_SCM_TDI_R   R6066 -1          A18X+051440Y+019332X0180Y0200R090 S2      
317JTAG_SCM_TDI_R   VIA   -    MD0100PA00X+051869Y+019185X0200Y         S0      
317JTAG_SCM_TDI_R   VIA   -    M      A01X+060284Y+003291X0200Y         S2      
017JTAG_SCM_TDI_R   VIA   -    M      A18X+060284Y+003291X0260Y         S2      
017JTAG_SCM_TDI_R         -    MD0100PA00X+060284Y+003291                       
327m2160            R3193 -2          A01X+039898Y+013498X0198Y0197     S1      
317m2160            VIA   -    M      A01X+039559Y+014701X0200Y         S2      
017m2160            VIA   -    M      A18X+039559Y+014701X0260Y         S2      
017m2160                  -    MD0100PA00X+039559Y+014701                       
327m2160            R6063 -1          A01X+061870Y+029273X0198Y0197R090 S1      
317m2160            VIA   -    MD0100PA00X+061870Y+028530X0200Y         S0      
317m2161            VIA   -    MD0100PA00X+064101Y+016183X0200Y         S0      
327m2161            R2489 -2          A01X+064623Y+015313X0198Y0197R090 S1      
327m2161            R116  -1          A01X+062670Y+029273X0198Y0197R090 S1      
317m2161            VIA   -    M      A01X+062670Y+028530X0300Y         S1      
017m2161            VIA   -    M      A18X+062670Y+028530X0200Y         S1      
017m2161                  -    MD0100PA00X+062670Y+028530                       
327m2162            R8012 -2          A18X+068150Y+012008X0198Y0197R270 S2      
317m2162            VIA   -    MD0100PA00X+068550Y+012400X0200Y         S0      
317m2162            VIA   -    MD0100PA00X+075600Y+014550X0200Y         S0      
317m2162            VIA   -    M      A01X+075719Y+009183X0200Y         S2      
017m2162            VIA   -    M      A18X+075719Y+009183X0260Y         S2      
017m2162                  -    MD0100PA00X+075719Y+009183                       
327m2162            PR4012-2          A01X+076019Y+008935X0198Y0197     S1      
327m2162            R4015 -2   M      A01X+076019Y+009327X0198Y0197R270 S1      
317m2162            VIA   -    MD0100PA00X+082647Y+043134X0200Y         S0      
327m2162            R6055 -1          A01X+082399Y+043134X0198Y0197R180 S1      
317m2163            VIA   -    MD0100PA00X+072729Y+042466X0180Y    R090 S2      
317m2163            VIA   -    MD0100PA00X+071950Y+036886X0200Y         S0      
327m2163            U18   -L3         A01X+072883Y+042619X0160Y    R090 S1      
327m2163            R6074 -2          A01X+072350Y+036644X0198Y0197R090 S1      
327m2164            R3775 -1          A01X+098451Y+029564X0198Y0197     S1      
317m2164            VIA   -    M      A01X+098451Y+030362X0200Y         S2      
017m2164            VIA   -    M      A18X+098451Y+030362X0260Y         S2      
017m2164                  -    MD0100PA00X+098451Y+030362                       
327m2164            R1036 -2          A01X+073950Y+037679X0198Y0197R270 S1      
317m2164            VIA   -    MD0100PA00X+073950Y+037436X0200Y         S0      
317m2164            VIA   -    MD0100PA00X+092002Y+036288X0200Y         S0      
327m2165            VIA   -    M      A18X+070565Y+041196X0260Y    R090 S2      
327m2165            R188  -2          A18X+069550Y+039644X0198Y0197R270 S2      
327m2165            U18   -F4         A01X+071308Y+042934X0160Y    R090 S1      
317m2165            VIA   -    MD0100PA00X+071154Y+042781X0180Y    R090 S0      
317m2166            VIA   -    M      A01X+075481Y+037436X0200Y         S2      
017m2166            VIA   -    M      A18X+075481Y+037436X0260Y         S2      
017m2166                  -    MD0100PA00X+075481Y+037436                       
327m2166            U18   -T5         A01X+074458Y+043249X0160Y    R090 S1      
317m2166            VIA   -    MD0100PA00X+074611Y+043096X0180Y         S0      
327m2166            R6073 -2          A01X+074750Y+037994X0198Y0197R090 S1      
327ADC128_VREF      R3689 -2          A01X+120562Y+018894X0198Y0197     S1      
327ADC128_VREF      VIA   -    M      A01X+121218Y+018519X0300Y         S1      
327ADC128_VREF      U269  -1          A01X+122018Y+018007X0140Y0630R270 S1      
327ADC128_VREF      R3690 -1   M      A01X+120559Y+018519X0198Y0197R180 S1      
327ADC128_A1        VIA   -    M      A01X+121061Y+015705X0300Y         S1      
327ADC128_A1        U269  -8          A01X+122018Y+016216X0140Y0630R270 S1      
327ADC128_A1        R3668 -1   M      A01X+120559Y+016099X0198Y0197R180 S1      
327ADC128_A1        R3667 -2          A01X+119528Y+016099X0198Y0197     S1      
327ADC128_A0        R3669 -2          A01X+119528Y+016499X0198Y0197     S1      
327ADC128_A0        R3670 -1   M      A01X+120559Y+016499X0198Y0197R180 S1      
327ADC128_A0        VIA   -    M      A01X+121311Y+016155X0300Y         S1      
327ADC128_A0        U269  -7          A01X+122018Y+016472X0140Y0630R270 S1      
327m2167            PR6000-2          A18X+080432Y+134588X0198Y0197R180 S2      
317m2167            VIA   -    M      A01X+080161Y+133906X0200Y    R090 S2      
017m2167            VIA   -    M      A18X+080161Y+133906X0260Y    R090 S2      
017m2167                  -    MD0100PA00X+080161Y+133906                       
327m2167            PU55  -4          A01X+079628Y+133959X0070Y0320R270 S1      
327m2168            U18   -J21        A01X+072253Y+048288X0160Y    R090 S1      
317m2168            VIA   -     D0100PA00X+072099Y+048442X0180Y    R090 S2      
327m2169            U18   -F18        A01X+071308Y+047344X0160Y    R090 S1      
317m2169            VIA   -     D0100PA00X+071154Y+047497X0180Y    R090 S2      
317m2170            VIA   -     D0100PA00X+075241Y+047812X0180Y    R090 S2      
327m2170            U18   -V19        A01X+075087Y+047659X0160Y    R090 S1      
327m2171            R798  -2          A01X+077823Y+047234X0198Y0197     S1      
327m2171            U259  -3          A01X+056591Y+039860X0140Y0440R270 S1      
317m2171            VIA   -    M      A01X+056221Y+039760X0200Y    R090 S2      
017m2171            VIA   -    M      A18X+056221Y+039760X0260Y    R090 S2      
017m2171                  -    MD0100PA00X+056221Y+039760                       
317m2171            VIA   -    MD0100PA00X+078688Y+047134X0200Y    R180 S0      
327m2171            R804  -1   M      A01X+078958Y+047134X0198Y0197     S1      
317m2171            VIA   -    MD0100PA00X+077775Y+055874X0200Y         S0      
317m2171            VIA   -    MD0100PA00X+065683Y+057720X0200Y         S0      
327m2172            R3779 -1          A01X+094452Y+018905X0198Y0197R180 S1      
317m2172            VIA   -    M      A01X+094512Y+019326X0200Y         S2      
017m2172            VIA   -    M      A18X+094512Y+019326X0260Y         S2      
017m2172                  -    MD0100PA00X+094512Y+019326                       
317m2172            VIA   -    MD0100PA00X+078682Y+045952X0200Y         S0      
327m2172            R800  -1          A01X+078958Y+045934X0198Y0197     S1      
327m2172            R685  -2          A01X+077823Y+046334X0198Y0197     S1      
317m2172            VIA   -    MD0100PA00X+095903Y+048729X0200Y         S0      
327m2173            R4604 -2          A18X+124778Y+030016X0198Y0197R090 S2      
327m2173            Q144  -5          A18X+124332Y+030272X0170Y0200R090 S2      
327m2173            VIA   -    M      A18X+124778Y+029536X0260Y    R180 S2      
327m2173            Q144  -6   M      A18X+124332Y+030016X0170Y0200R090 S2      
317m2174            VIA   -    MD0100PA00X+069362Y+034617X0200Y         S0      
327m2174            U18   -F8         A01X+071308Y+044194X0160Y    R090 S1      
317m2174            VIA   -    MD0100PA00X+071154Y+044040X0180Y    R090 S0      
327m2174            R9446 -2          A18X+122609Y+031172X0198Y0197R270 S2      
317m2174            VIA   -    M      A01X+122609Y+031422X0300Y         S1      
017m2174            VIA   -    M      A18X+122609Y+031422X0200Y         S1      
017m2174                  -    MD0100PA00X+122609Y+031422                       
327m2175            Q144  -3          A18X+123584Y+030528X0170Y0200R090 S2      
327m2175            VIA   -    M      A18X+123069Y+030857X0260Y    R090 S2      
327m2175            R4605 -2          A18X+122209Y+030857X0198Y0197R090 S2      
327m2175            R9446 -1   M      A18X+122609Y+030857X0198Y0197R270 S2      
327m2176            Q144  -2   M      A18X+123584Y+030272X0170Y0200R090 S2      
327m2176            Q78   -5          A18X+125718Y+028951X0170Y0200R270 S2      
327m2176            R3047 -2          A18X+122609Y+030272X0198Y0197R270 S2      
327m2176            VIA   -    M      A18X+123069Y+030272X0260Y    R090 S2      
327PWRGD_PS_PWROK   R3048 -2          A18X+122209Y+030272X0198Y0197R270 S2      
317PWRGD_PS_PWROK   VIA   -    M      A01X+122209Y+030522X0300Y         S1      
017PWRGD_PS_PWROK   VIA   -    M      A18X+122209Y+030522X0200Y         S1      
017PWRGD_PS_PWROK         -    MD0100PA00X+122209Y+030522                       
317PWRGD_PS_PWROK   VIA   -    MD0100PA00X+044132Y+031617X0200Y         S0      
327PWRGD_PS_PWROK   R1816 -1          A18X+057220Y+005576X0198Y0197R090 S2      
317PWRGD_PS_PWROK   VIA   -    MD0100PA00X+057376Y+005869X0200Y         S0      
317m2177            VIA   -    M      A01X+072750Y+038686X0200Y    R090 S2      
017m2177            VIA   -    M      A18X+072750Y+038686X0260Y    R090 S2      
017m2177                  -    MD0100PA00X+072750Y+038686                       
327m2177            U18   -N4         A01X+073513Y+042934X0160Y    R090 S1      
317m2177            VIA   -    MD0100PA00X+073666Y+042781X0180Y    R090 S0      
327m2177            R6054 -2          A01X+072756Y+037994X0198Y0197R090 S1      
327m2178            SW1   -5          A01X+166910Y+014676X0300Y0500R270 S1      
327m2178            VIA   -    M      A01X+166290Y+014676X0300Y    R180 S1      
327m2178            R6042 -2          A01X+165810Y+014676X0198Y0197     S1      
327m2179            SW1   -10         A01X+166910Y+012176X0300Y0500R270 S1      
317m2179            VIA   -    M      A01X+167310Y+012176X0200Y    R270 S2      
017m2179            VIA   -    M      A18X+167310Y+012176X0260Y    R270 S2      
017m2179                  -    MD0100PA00X+167310Y+012176                       
327m2179            R6040 -2          A18X+167770Y+012176X0198Y0197     S2      
317m2180            VIA   -    M      A01X+081750Y+042706X0200Y         S2      
017m2180            VIA   -    M      A18X+081750Y+042706X0260Y         S2      
017m2180                  -    MD0100PA00X+081750Y+042706                       
327m2180            R6046 -2          A01X+082084Y+042734X0198Y0197R180 S1      
327m2180            U18   -AA3        A01X+076032Y+042619X0160Y    R090 S1      
317m2180            VIA   -    MD0100PA00X+076186Y+042466X0180Y    R090 S0      
317m2181            VIA   -    M      A01X+088800Y+029300X0200Y         S2      
017m2181            VIA   -    M      A18X+088800Y+029300X0260Y         S2      
017m2181                  -    MD0100PA00X+088800Y+029300                       
317m2181            VIA   -    MD0100PA00X+088400Y+027133X0200Y         S0      
327m2181            R8100 -2          A01X+088808Y+032600X0198Y0197     S1      
327m2181            U18   -U11        A01X+074772Y+045139X0160Y    R090 S1      
317m2181            VIA   -    MD0100PA00X+074926Y+044985X0180Y    R090 S0      
317m2181            VIA   -    MD0100PA00X+077741Y+025665X0200Y         S0      
327m2181            R3973 -2          A01X+088700Y+026741X0198Y0197     S1      
327m2181            R3979 -2   M      A01X+088650Y+027133X0198Y0197R270 S1      
327m2182            R6049 -1          A01X+098803Y+027544X0198Y0197R180 S1      
327m2182            R4063 -2   M      A01X+098803Y+027144X0198Y0197     S1      
327m2182            VIA   -    M      A01X+099283Y+027144X0300Y         S1      
327m2182            Q126  -2          A01X+099769Y+027144X0170Y0200R090 S1      
327P1V8_AUX         R842  -1          A18X+100145Y+131050X0120Y0150R180 S2      
317P1V8_AUX         VIA   -    MD0100PA00X+099935Y+131050X0200Y         S0      
317P1V8_AUX         VIA   -    MD0100PA00X+103757Y+104714X0200Y         S0      
317P1V8_AUX         VIA   -    MD0100PA00X+089200Y+130750X0200Y         S0      
327P1V8_AUX         U6020 -24         A18X+089414Y+131209X0120Y0630R270 S2      
327P1V8_AUX         C7500 -1   M      A18X+088955Y+130750X0120Y0150     S2      
317P1V8_AUX         VIA   -    MD0100PA00X+091250Y+131000X0200Y         S0      
327P1V8_AUX         R6770 -1          A18X+091005Y+131000X0120Y0150     S2      
317P1V8_AUX         VIA   -    MD0100PA00X+012907Y+160834X0200Y         S0      
327P1V8_AUX         R6861 -1          A01X+008101Y+159633X0198Y0197R090 S1      
317P1V8_AUX         VIA   -    MD0100PA00X+008101Y+159326X0200Y         S0      
317P1V8_AUX         VIA   -    MD0100PA00X+090238Y+145646X0200Y         S0      
317P1V8_AUX         VIA   -    MD0100PA00X+094101Y+126950X0200Y    R180 S0      
327P1V8_AUX         R1237 -1          A18X+093818Y+126973X0198Y0197     S2      
317P1V8_AUX         VIA   -    MD0100PA00X+094587Y+130150X0200Y         S0      
327P1V8_AUX         R844  -1          A18X+094832Y+130150X0120Y0150R180 S2      
327P1V8_AUX         C365  -1   M      A18X+097955Y+130750X0120Y0150     S2      
327P1V8_AUX         U22   -24         A18X+098451Y+131209X0120Y0630R270 S2      
317P1V8_AUX         VIA   -    MD0100PA00X+098200Y+130750X0200Y         S0      
317P1V8_AUX         VIA   -    MD0100PA00X+094587Y+130454X0200Y         S0      
327P1V8_AUX         R843  -1          A18X+094832Y+130550X0120Y0150R180 S2      
317P1V8_AUX         VIA   -    MD0100PA00X+085140Y+130550X0200Y         S0      
327P1V8_AUX         R6771 -1          A18X+085395Y+130600X0120Y0150R180 S2      
317P1V8_AUX         VIA   -    MD0100PA00X+085150Y+130200X0200Y         S0      
327P1V8_AUX         R6772 -1          A18X+085395Y+130200X0120Y0150R180 S2      
317P1V8_AUX         VIA   -    MD0100PA00X+100309Y+103733X0200Y         S0      
317P1V8_AUX         VIA   -    MD0100PA00X+183329Y+146964X0200Y         S0      
327P1V8_AUX         C8007 -1   M      A18X+073913Y+056924X0198Y0197R180 S2      
327P1V8_AUX         R8035 -1          A18X+074913Y+057317X0198Y0197     S2      
327P1V8_AUX         R8018 -1          A01X+168900Y+023158X0198Y0197R270 S1      
317P1V8_AUX         VIA   -    MD0100PA00X+175995Y+129732X0200Y         S0      
317P1V8_AUX         VIA   -    MD0100PA00X+157802Y+134477X0200Y         S0      
327P1V8_AUX         U82   -5          A18X+158760Y+134477X0220Y0530R090 S2      
327P1V8_AUX         C218  -1   M      A18X+158092Y+134477X0198Y0197R090 S2      
317P1V8_AUX         VIA   -    MD0100PA00X+157841Y+134862X0200Y         S0      
327P1V8_AUX         R943  -1          A18X+158092Y+134862X0198Y0197R270 S2      
327P1V8_AUX         R654  -2          A18X+159536Y+080036X0198Y0197R270 S2      
327P1V8_AUX         U3    -5          A18X+157953Y+080099X0220Y0530R090 S2      
327P1V8_AUX         C30   -1   M      A18X+157267Y+080406X0198Y0197     S2      
317P1V8_AUX         VIA   -    MD0100PA00X+157267Y+080678X0200Y         S0      
327P1V8_AUX         U86   -5          A01X+136811Y+010656X0220Y0530R180 S1      
317P1V8_AUX         VIA   -    MD0100PA00X+136811Y+009800X0200Y         S0      
327P1V8_AUX         C219  -1   M      A01X+136811Y+010051X0198Y0197     S1      
317P1V8_AUX         VIA   -    MD0100PA00X+159748Y+027199X0200Y         S0      
327P1V8_AUX         R733  -1          A01X+166193Y+022775X0198Y0197R270 S1      
317P1V8_AUX         VIA   -    MD0100PA00X+166193Y+023017X0200Y    R180 S0      
327P1V8_AUX         R5071 -1          A01X+165495Y+016176X0198Y0197     S1      
317P1V8_AUX         VIA   -    MD0100PA00X+165252Y+016176X0200Y    R270 S0      
327P1V8_AUX         R22   -1          A01X+165495Y+015176X0198Y0197     S1      
317P1V8_AUX         VIA   -    MD0100PA00X+165252Y+015176X0200Y    R270 S0      
327P1V8_AUX         R1358 -1          A18X+168735Y+012676X0198Y0197R180 S2      
317P1V8_AUX         VIA   -    MD0100PA00X+168492Y+012676X0200Y    R090 S0      
327P1V8_AUX         R1264 -1          A18X+168735Y+014176X0198Y0197R180 S2      
317P1V8_AUX         VIA   -    MD0100PA00X+168492Y+014176X0200Y    R090 S0      
327P1V8_AUX         R1262 -1          A18X+168735Y+015776X0198Y0197R180 S2      
317P1V8_AUX         VIA   -    MD0100PA00X+168492Y+015776X0200Y    R090 S0      
327P1V8_AUX         R1261 -1          A18X+168735Y+016676X0198Y0197R180 S2      
317P1V8_AUX         VIA   -    MD0100PA00X+168492Y+016676X0200Y    R090 S0      
317P1V8_AUX         VIA   -    MD0100PA00X+168328Y+012076X0200Y    R270 S0      
327P1V8_AUX         R6040 -1          A18X+168085Y+012176X0198Y0197     S2      
317P1V8_AUX         VIA   -    MD0100PA00X+169753Y+063637X0200Y         S0      
327P1V8_AUX         U29   -5          A01X+154268Y+055522X0140Y0440     S1      
327P1V8_AUX         C223  -1   M      A01X+154270Y+056201X0198Y0197R090 S1      
317P1V8_AUX         VIA   -    MD0100PA00X+154599Y+056201X0200Y         S0      
317P1V8_AUX         VIA   -    MD0100PA00X+121205Y+055983X0200Y         S0      
317P1V8_AUX         VIA   -    MD0100PA00X+118381Y+064068X0200Y         S0      
317P1V8_AUX         VIA   -    MD0100PA00X+096411Y+055470X0200Y         S0      
317P1V8_AUX         VIA   -    MD0100PA00X+083300Y+050350X0200Y         S0      
317P1V8_AUX         VIA   -    MD0100PA00X+154615Y+054117X0200Y         S0      
317P1V8_AUX         VIA   -    MD0100PA00X+168900Y+023400X0200Y         S0      
317P1V8_AUX         VIA   -    MD0100PA00X+073913Y+056664X0200Y         S0      
327P1V8_AUX         U8000 -5          A18X+073124Y+056850X0160Y0200R270 S2      
317P1V8_AUX         VIA   -    MD0100PA00X+074913Y+057034X0200Y         S0      
317P1V8_AUX         VIA   -    MD0100PA00X+083102Y+058308X0200Y         S0      
327P1V8_AUX         R6860 -1          A01X+172542Y+169023X0198Y0197R270 S1      
317P1V8_AUX         VIA   -    MD0100PA00X+172542Y+169266X0200Y    R270 S0      
317P1V8_AUX         VIA   -    MD0100PA00X+104063Y+066844X0200Y         S0      
317P1V8_AUX         VIA   -    MD0100PA00X+103503Y+075601X0200Y         S0      
327P1V8_AUX         U18   -V20        A01X+075087Y+047974X0160Y    R090 S1      
317P1V8_AUX         VIA   -    MD0100PA00X+075241Y+048127X0180Y    R090 S0      
327P1V8_AUX         U18   -F20        A01X+071308Y+047974X0160Y    R090 S1      
317P1V8_AUX         VIA   -    MD0100PA00X+071154Y+048127X0180Y    R090 S0      
327P1V8_AUX         U18   -M18        A01X+073198Y+047344X0160Y    R090 S1      
317P1V8_AUX         VIA   -    MD0100PA00X+073351Y+047497X0180Y    R090 S0      
327P1V8_AUX         U18   -P15        A01X+073828Y+046399X0160Y    R090 S1      
317P1V8_AUX         VIA   -    MD0100PA00X+073981Y+046552X0180Y    R090 S0      
327P1V8_AUX         U18   -L15        A01X+072883Y+046399X0160Y    R090 S1      
327P1V8_AUX         U18   -N15        A01X+073513Y+046399X0160Y    R090 S1      
327P1V8_AUX         C1128 -1   M      A18X+073824Y+046395X0164Y0164R090 S2      
317P1V8_AUX         VIA   -    MD0100PA00X+073666Y+046552X0180Y    R090 S0      
327P1V8_AUX         U18   -K15        A01X+072568Y+046399X0160Y    R090 S1      
327P1V8_AUX         C1133 -1   M      A18X+073509Y+046395X0164Y0164R090 S2      
327P1V8_AUX         U18   -M15        A01X+073198Y+046399X0160Y    R090 S1      
327P1V8_AUX         C1134 -1   M      A18X+073015Y+046710X0164Y0164R090 S2      
317P1V8_AUX         VIA   -    MD0100PA00X+073351Y+046552X0180Y    R090 S0      
317P1V8_AUX         VIA   -    MD0100PA00X+072729Y+046552X0180Y    R090 S0      
327P1V8_AUX         C1132 -1   M      A18X+072572Y+046710X0164Y0164R090 S2      
327P1V8_AUX         U18   -J15        A01X+072253Y+046399X0160Y    R090 S1      
317P1V8_AUX         VIA   -    MD0100PA00X+072099Y+046552X0180Y    R090 S0      
327P1V8_AUX         C1129 -1          A18X+072257Y+046395X0164Y0164     S2      
317P1V8_AUX         VIA   -    MD0100PA00X+072414Y+046552X0180Y    R090 S0      
327P1V8_AUX         U18   -K8         A01X+072568Y+044194X0160Y    R090 S1      
327P1V8_AUX         C1131 -1          A18X+072572Y+043883X0164Y0164R270 S2      
317P1V8_AUX         VIA   -    MD0100PA00X+072414Y+044040X0180Y    R090 S0      
327P1V8_AUX         U18   -J8         A01X+072253Y+044194X0160Y    R090 S1      
327P1V8_AUX         C1126 -1   M      A18X+072264Y+043883X0164Y0164R270 S2      
327P1V8_AUX         C1127 -1          A18X+071942Y+043883X0164Y0164R270 S2      
317P1V8_AUX         VIA   -    MD0100PA00X+072099Y+044040X0180Y    R090 S0      
327P1V8_AUX         U18   -F3         A01X+071308Y+042619X0160Y    R090 S1      
317P1V8_AUX         VIA   -    MD0100PA00X+071154Y+042466X0180Y    R090 S0      
327P1V8_AUX         C352  -1          A18X+070880Y+042170X0198Y0197R090 S2      
327P1V8_AUX         R6147 -1          A18X+067242Y+040465X0198Y0197R180 S2      
317P1V8_AUX         VIA   -    MD0100PA00X+066993Y+040800X0200Y    R090 S0      
327P1V8_AUX         R6148 -1          A01X+071540Y+036328X0198Y0197R090 S1      
317P1V8_AUX         VIA   -    MD0100PA00X+071550Y+036086X0200Y         S0      
327P1V8_AUX         PC6021-1   M      A01X+060130Y+028972X0198Y0197R180 S1      
327P1V8_AUX         PC6019-2          A01X+056350Y+029374X0198Y0197     S1      
327P1V8_AUX         PR6007-2   M      A01X+056350Y+028986X0198Y0197     S1      
317P1V8_AUX         VIA   -    MD0100PA00X+060222Y+032220X0200Y    R270 S0      
317P1V8_AUX         VIA   -    MD0100PA00X+060475Y+032220X0200Y    R270 S0      
317P1V8_AUX         VIA   -    MD0100PA00X+060727Y+032220X0200Y    R270 S0      
317P1V8_AUX         VIA   -    MD0100PA00X+060475Y+031414X0200Y    R270 S0      
317P1V8_AUX         VIA   -    MD0100PA00X+060222Y+031414X0200Y    R270 S0      
317P1V8_AUX         VIA   -    MD0100PA00X+060727Y+031414X0200Y    R270 S0      
327P1V8_AUX         PL6000-2          A01X+060672Y+030611X0848Y1300     S1      
317P1V8_AUX         VIA   -    MD0100PA00X+060372Y+028972X0200Y    R270 S0      
317P1V8_AUX         VIA   -    MD0100PA00X+060475Y+029804X0200Y    R270 S0      
317P1V8_AUX         VIA   -    MD0100PA00X+060222Y+029804X0200Y    R270 S0      
317P1V8_AUX         VIA   -    MD0100PA00X+060625Y+028972X0200Y    R270 S0      
317P1V8_AUX         VIA   -    MD0100PA00X+060727Y+029804X0200Y    R270 S0      
317P1V8_AUX         VIA   -    MD0100PA00X+060980Y+032220X0200Y    R270 S0      
317P1V8_AUX         VIA   -    MD0100PA00X+060980Y+031414X0200Y    R270 S0      
317P1V8_AUX         VIA   -    MD0100PA00X+060980Y+029804X0200Y    R270 S0      
317P1V8_AUX         VIA   -    MD0100PA00X+060877Y+028972X0200Y    R270 S0      
327P1V8_AUX         PC867 -1          A18X+060272Y+031817X0400Y0500R180 S2      
327P1V8_AUX         PC850 -1          A18X+060272Y+030206X0400Y0500R180 S2      
327P1V8_AUX         PC865 -1          A18X+060272Y+031012X0400Y0500R180 S2      
327P1V8_AUX         PC866 -1          A18X+060272Y+029401X0400Y0500R180 S2      
327P1V8_AUX         C552  -1   M      A01X+061192Y+044000X0198Y0197     S1      
327P1V8_AUX         U92   -5          A01X+060449Y+043969X0220Y0530R270 S1      
327P1V8_AUX         C224  -1   M      A01X+032865Y+056609X0198Y0197     S1      
327P1V8_AUX         U40   -5          A01X+032838Y+056027X0140Y0440     S1      
317P1V8_AUX         VIA   -    MD0100PA00X+032465Y+056609X0200Y         S0      
327P1V8_AUX         U38   -5          A01X+038718Y+048240X0160Y0360     S1      
317P1V8_AUX         VIA   -    MD0100PA00X+038978Y+047607X0200Y    R090 S0      
327P1V8_AUX         C347  -1   M      A01X+038718Y+047607X0198Y0197R270 S1      
327P1V8_AUX         R1457 -1          A01X+039718Y+050468X0198Y0197R270 S1      
317P1V8_AUX         VIA   -    M      A01X+039718Y+050710X0200Y    R180 S2      
017P1V8_AUX         VIA   -    M      A18X+039718Y+050710X0260Y    R180 S2      
017P1V8_AUX               -    MD0100PA00X+039718Y+050710                       
327P1V8_AUX         R1452 -1          A01X+041098Y+050460X0198Y0197R270 S1      
317P1V8_AUX         VIA   -    MD0100PA00X+041150Y+051080X0200Y    R180 S0      
327P1V8_AUX         R1493 -1          A01X+042478Y+050452X0198Y0197R270 S1      
317P1V8_AUX         VIA   -    MD0100PA00X+042750Y+051055X0200Y    R180 S0      
327P1V8_AUX         R6146 -1   M      A01X+070754Y+036325X0198Y0197R090 S1      
317P1V8_AUX         VIA   -    MD0100PA00X+061192Y+043700X0200Y    R090 S0      
317P1V8_AUX         VIA   -    MD0100PA00X+058052Y+043595X0200Y    R270 S0      
327P1V8_AUX         R996  -1          A01X+058305Y+043595X0198Y0197     S1      
317P1V8_AUX         VIA   -    MD0100PA00X+064213Y+036328X0200Y         S0      
317P1V8_AUX         VIA   -    MD0100PA00X+070794Y+036064X0200Y         S0      
317P1V8_AUX         VIA   -    MD0100PA00X+053073Y+039863X0200Y         S0      
317P1V8_AUX         VIA   -    MD0100PA00X+058120Y+016436X0200Y    R270 S0      
327P1V8_AUX         R1702 -1          A01X+058363Y+016436X0198Y0197     S1      
317P1V8_AUX         VIA   -    MD0100PA00X+058120Y+016942X0200Y    R270 S0      
327P1V8_AUX         R1703 -1          A01X+058363Y+016942X0198Y0197     S1      
317P1V8_AUX         VIA   -    MD0100PA00X+058568Y+017498X0200Y    R270 S0      
327P1V8_AUX         C1323 -1   M      A01X+058819Y+017498X0198Y0197R090 S1      
327P1V8_AUX         U98   -2          A01X+059520Y+017298X0140Y0590R270 S1      
317P1V8_AUX         VIA   -    MD0100PA00X+069148Y+036064X0200Y         S0      
327P1V8_AUX         R6743 -1          A01X+068944Y+036333X0198Y0197R090 S1      
327P1V8_AUX         R6742 -1          A01X+070352Y+036333X0198Y0197R090 S1      
327P1V8_AUX         R6504 -1          A01X+039338Y+046912X0198Y0197R090 S1      
317m2183            VIA   -    MD0100PA00X+075556Y+042151X0180Y    R090 S2      
327m2183            U18   -W2         A01X+075402Y+042304X0160Y    R090 S1      
327m2183            R6051 -1          A01X+082084Y+041534X0198Y0197     S1      
317m2183            VIA   -    MD0100PA00X+081750Y+041534X0200Y         S0      
327m2184            R1130 -1          A01X+061847Y+042690X0198Y0197R180 S1      
317m2184            VIA   -    MD0100PA00X+062220Y+043612X0200Y         S0      
327m2184            R152  -2          A01X+065642Y+043386X0198Y0197R180 S1      
327m2184            R1195 -1          A01X+064608Y+043386X0198Y0197R180 S1      
317m2184            VIA   -    MD0100PA00X+065143Y+043353X0200Y         S0      
327m2184            R3834 -1          A01X+175092Y+012824X0198Y0197R270 S1      
317m2184            VIA   -    M      A01X+175434Y+012824X0200Y         S2      
017m2184            VIA   -    M      A18X+175434Y+012824X0260Y         S2      
017m2184                  -    MD0100PA00X+175434Y+012824                       
327m2184            R4061 -1          A01X+184787Y+016583X0198Y0197R180 S1      
317m2184            VIA   -    MD0100PA00X+064950Y+038512X0200Y         S0      
327m2185            VIA   -    M      A18X+077866Y+045319X0260Y         S2      
327m2185            R6048 -2          A18X+078397Y+045895X0198Y0197R270 S2      
327m2185            U18   -U10        A01X+074772Y+044824X0160Y    R090 S1      
317m2185            VIA   -    MD0100PA00X+074926Y+044670X0180Y    R090 S0      
327m2186            D96   -C          A01X+126209Y+027785X0240Y0280R090 S1      
327m2186            Q78   -3          A18X+126466Y+028695X0170Y0200R270 S2      
317m2186            VIA   -    M      A01X+126209Y+028295X0300Y         S1      
017m2186            VIA   -    M      A18X+126209Y+028295X0200Y         S1      
017m2186                  -    MD0100PA00X+126209Y+028295                       
317m2187            VIA   -    M      A01X+126209Y+026901X0200Y         S2      
017m2187            VIA   -    M      A18X+126209Y+026901X0260Y         S2      
017m2187                  -    MD0100PA00X+126209Y+026901                       
327m2187            D96   -A          A01X+126209Y+027411X0240Y0280R090 S1      
327m2187            R3075 -1          A18X+126209Y+026421X0198Y0197R090 S2      
317LED_P5V          VIA   -    M      A01X+123809Y+026901X0200Y         S2      
017LED_P5V          VIA   -    M      A18X+123809Y+026901X0260Y         S2      
017LED_P5V                -    MD0100PA00X+123809Y+026901                       
327LED_P5V          D98   -A          A01X+123809Y+027411X0240Y0280R090 S1      
327LED_P5V          R3102 -1          A18X+123809Y+026421X0198Y0197R090 S2      
317LED_P3V3         VIA   -    M      A01X+124609Y+026901X0200Y         S2      
017LED_P3V3         VIA   -    M      A18X+124609Y+026901X0260Y         S2      
017LED_P3V3               -    MD0100PA00X+124609Y+026901                       
327LED_P3V3         D99   -A          A01X+124609Y+027411X0240Y0280R090 S1      
327LED_P3V3         R3100 -1          A18X+124609Y+026421X0198Y0197R090 S2      
317m2188            VIA   -    MD0080PA00X+150435Y+116199X0160Y         S0      
327m2188            VIA   -    M      A18X+157807Y+125604X0260Y         S2      
317m2188            VIA   -    MD0100PA00X+154548Y+124509X0200Y    R180 S0      
327m2188            U25   -DH15       A01X+150251Y+116094X0177Y    R180 S1      
327m2188            R5029 -2   M      A18X+158237Y+125669X0198Y0197     S2      
327m2188            R447  -1          A18X+158237Y+126059X0198Y0197R180 S2      
317m2188            VIA   -    MD0100PA00X+071150Y+037436X0200Y         S0      
317m2188            VIA   -    MD0100PA00X+094411Y+038659X0200Y         S0      
317m2188            VIA   -    MD0100PA00X+093961Y+056203X0200Y         S0      
327m2188            R246  -1          A01X+071230Y+037679X0198Y0197R090 S1      
317m2189            VIA   -    MD0080PA00X+150065Y+116199X0160Y         S0      
327m2189            U25   -DH16       A01X+149881Y+116094X0177Y    R180 S1      
327m2189            VIA   -    M      A18X+157763Y+126442X0260Y         S2      
327m2189            R5027 -2   M      A18X+158237Y+126839X0198Y0197     S2      
327m2189            R446  -1   M      A18X+158237Y+126449X0198Y0197R180 S2      
317m2189            VIA   -    MD0100PA00X+158407Y+127120X0200Y    R180 S0      
327m2189            R245  -1          A18X+072858Y+038086X0198Y0197     S2      
317m2189            VIA   -    MD0100PA00X+085419Y+040404X0200Y         S0      
317m2189            VIA   -    MD0100PA00X+086736Y+055871X0200Y         S0      
317m2190            VIA   -    MD0080PA00X+043201Y+115562X0160Y         S0      
317m2190            VIA   -    MD0100PA00X+070750Y+037436X0200Y         S0      
327m2190            R187  -1          A01X+070830Y+037679X0198Y0197R090 S1      
327m2190            U26   -DF40       A01X+043385Y+115457X0177Y    R180 S1      
317m2190            VIA   -    M      A01X+063506Y+039970X0200Y         S2      
017m2190            VIA   -    M      A18X+063506Y+039970X0260Y         S2      
017m2190                  -    MD0100PA00X+063506Y+039970                       
327m2190            R5032 -2   M      A18X+037042Y+118786X0198Y0197     S2      
327m2190            R544  -1   M      A18X+037351Y+119215X0198Y0197     S2      
317IRQ_BMC_SMI_N    VIA   -    MD0080PA00X+141000Y+115242X0160Y         S0      
327IRQ_BMC_SMI_N    U25   -DE40       A01X+141184Y+115138X0177Y    R180 S1      
327IRQ_BMC_SMI_N    VIA   -    M      A18X+142204Y+119285X0260Y    R180 S2      
317IRQ_BMC_SMI_N    VIA   -    MD0100PA00X+159901Y+130976X0200Y         S0      
327IRQ_BMC_SMI_N    R445  -1          A18X+159960Y+129499X0198Y0197R180 S2      
327IRQ_BMC_SMI_N    R5028 -2   M      A18X+159968Y+130290X0198Y0197     S2      
317IRQ_BMC_SMI_N    VIA   -    MD0100PA00X+092132Y+054936X0200Y         S0      
317IRQ_BMC_SMI_N    VIA   -    MD0100PA00X+092132Y+037248X0200Y         S0      
317IRQ_BMC_SMI_N    VIA   -    MD0100PA00X+081778Y+036690X0200Y         S0      
327IRQ_BMC_SMI_N    R244  -1          A18X+068756Y+039329X0198Y0197R270 S2      
327m2191            SW1   -15         A01X+169910Y+014676X0300Y0500R270 S1      
317m2191            VIA   -    M      A01X+169510Y+014676X0200Y    R090 S2      
017m2191            VIA   -    M      A18X+169510Y+014676X0260Y    R090 S2      
017m2191                  -    MD0100PA00X+169510Y+014676                       
327m2191            R6043 -2          A18X+169050Y+014976X0198Y0197R180 S2      
317m2191            VIA   -    MD0100PA00X+082676Y+035633X0200Y         S0      
317m2191            VIA   -    MD0100PA00X+082871Y+044355X0200Y         S0      
327m2191            R5099 -1          A01X+082399Y+044355X0198Y0197R180 S1      
327m2192            SW1   -20         A01X+169910Y+012176X0300Y0500R270 S1      
327m2192            R6041 -2          A18X+169050Y+011876X0198Y0197R180 S2      
317m2192            VIA   -    M      A01X+169510Y+012176X0200Y    R090 S2      
017m2192            VIA   -    M      A18X+169510Y+012176X0260Y    R090 S2      
017m2192                  -    MD0100PA00X+169510Y+012176                       
327m2192            R371  -1          A01X+070850Y+054344X0198Y0197R270 S1      
317m2192            VIA   -    MD0100PA00X+070850Y+055545X0200Y         S0      
317m2192            VIA   -    MD0100PA00X+062472Y+055343X0200Y         S0      
317m2192            VIA   -    MD0100PA00X+056992Y+049073X0200Y         S0      
317m2192            VIA   -    MD0100PA00X+065427Y+041925X0200Y         S0      
317m2193            VIA   -    MD0080PA00X+140815Y+115561X0160Y         S0      
327m2193            U25   -DF40       A01X+140999Y+115457X0177Y    R180 S1      
327m2193            VIA   -    M      A18X+141629Y+119057X0260Y    R180 S2      
317m2193            VIA   -    MD0100PA00X+160834Y+131327X0200Y         S0      
327m2193            R444  -1          A18X+159960Y+129899X0198Y0197R180 S2      
327m2193            R5026 -2   M      A18X+160912Y+130755X0198Y0197R180 S2      
317m2193            VIA   -    MD0100PA00X+070350Y+039086X0200Y    R090 S0      
327m2193            R243  -1          A01X+070350Y+039329X0198Y0197R090 S1      
317m2193            VIA   -    MD0100PA00X+069981Y+034480X0200Y         S0      
317m2193            VIA   -    MD0100PA00X+086617Y+037477X0200Y         S0      
317m2193            VIA   -    MD0100PA00X+091929Y+037450X0200Y         S0      
317m2193            VIA   -    MD0100PA00X+091758Y+054956X0200Y         S0      
327m2194            R1038 -1          A01X+092027Y+027543X0198Y0197R270 S1      
327m2194            VIA   -    M      A01X+092507Y+027234X0300Y    R270 S1      
327m2194            U44   -4          A01X+093135Y+027234X0140Y0490R270 S1      
327m2195            R955  -2          A01X+094926Y+027458X0198Y0197R270 S1      
327m2195            R999  -1   M      A01X+094526Y+027458X0198Y0197R090 S1      
327m2195            VIA   -    M      A01X+094526Y+026978X0300Y    R270 S1      
327m2195            U44   -2          A01X+093879Y+026978X0140Y0490R270 S1      
317m2196            VIA   -    MD0100PA00X+091627Y+026986X0200Y    R090 S0      
327m2196            R1038 -2          A01X+092027Y+027228X0198Y0197R270 S1      
327m2196            R1000 -1   M      A01X+091627Y+027228X0198Y0197R090 S1      
327m2196            J90   -A10        A01X+091339Y+018884X0150Y0500R090 S1      
317m2196            VIA   -           A01X+087517Y+018511X0200Y         S2      
017m2196            VIA   -           A18X+087517Y+018511X0260Y         S2      
017m2196                  -     D0100PA00X+087517Y+018511                       
317m2196            VIA   -    MD0100PA00X+090862Y+018890X0200Y         S0      
327m2197            R955  -1          A01X+094926Y+027773X0198Y0197R270 S1      
317m2197            VIA   -    M      A01X+094918Y+028013X0200Y    R270 S2      
017m2197            VIA   -    M      A18X+094918Y+028013X0260Y    R270 S2      
017m2197                  -    MD0100PA00X+094918Y+028013                       
327m2197            U18   -E10        A01X+070993Y+044824X0160Y    R090 S1      
317m2197            VIA   -    MD0100PA00X+070840Y+044670X0180Y    R090 S0      
317m2197            VIA   -    MD0100PA00X+095810Y+045785X0200Y         S0      
327m2198            U18   -U8         A01X+074772Y+044194X0160Y    R090 S1      
317m2198            VIA   -    MD0100PA00X+074926Y+044040X0180Y    R090 S0      
327m2198            R5099 -2          A01X+082084Y+044355X0198Y0197R180 S1      
317m2198            VIA   -    M      A01X+081612Y+044355X0200Y         S2      
017m2198            VIA   -    M      A18X+081612Y+044355X0260Y         S2      
017m2198                  -    MD0100PA00X+081612Y+044355                       
327m2199            SW1   -2          A01X+166910Y+016176X0300Y0500R270 S1      
327m2199            VIA   -    M      A01X+166290Y+016176X0300Y    R180 S1      
327m2199            R5071 -2          A01X+165810Y+016176X0198Y0197     S1      
317m2200            VIA   -    MD0080PA00X+052451Y+116199X0160Y         S0      
327m2200            U26   -DH16       A01X+052267Y+116095X0177Y    R180 S1      
317m2200            VIA   -    MD0100PA00X+055869Y+122615X0200Y    R180 S0      
327m2200            R546  -1          A18X+056903Y+124596X0198Y0197R180 S2      
327m2200            R5030 -2   M      A18X+056473Y+124593X0198Y0197R180 S2      
317m2200            VIA   -    MD0100PA00X+042402Y+126964X0200Y         S0      
317m2200            VIA   -    M      A01X+061190Y+053818X0200Y         S2      
017m2200            VIA   -    M      A18X+061190Y+053818X0260Y         S2      
017m2200                  -    MD0100PA00X+061190Y+053818                       
317m2200            VIA   -    MD0100PA00X+057534Y+043715X0200Y         S0      
327m2200            R189  -1          A01X+071150Y+039329X0198Y0197R090 S1      
317m2200            VIA   -    MD0100PA00X+071150Y+039086X0200Y    R090 S0      
317FM_BMC_READY_N   VIA   -    MD0080PA00X+043386Y+115243X0160Y         S0      
327FM_BMC_READY_N   U26   -DE40       A01X+043570Y+115138X0177Y    R180 S1      
317FM_BMC_READY_N   VIA   -    M      A01X+063410Y+040465X0200Y         S2      
017FM_BMC_READY_N   VIA   -    M      A18X+063410Y+040465X0260Y         S2      
017FM_BMC_READY_N         -    MD0100PA00X+063410Y+040465                       
327FM_BMC_READY_N   R188  -1          A18X+069550Y+039329X0198Y0197R270 S2      
317FM_BMC_READY_N   VIA   -    MD0100PA00X+069550Y+038686X0200Y    R090 S0      
327FM_BMC_READY_N   R545  -1          A18X+037358Y+119586X0198Y0197     S2      
327FM_BMC_READY_N   R5031 -2   M      A18X+037351Y+119965X0198Y0197R180 S2      
317m2201            VIA   -    M      A01X+075514Y+036891X0200Y         S2      
017m2201            VIA   -    M      A18X+075514Y+036891X0260Y         S2      
017m2201                  -    MD0100PA00X+075514Y+036891                       
327m2201            R6052 -1          A01X+075900Y+036694X0198Y0197R270 S1      
327m2201            U18   -U3         A01X+074772Y+042619X0160Y    R090 S1      
317m2201            VIA   -    MD0100PA00X+074926Y+042466X0180Y    R090 S0      
327E1S_0_P3V3_EN    R3946 -1          A01X+079134Y+027482X0198Y0197R180 S1      
327E1S_0_P3V3_EN    R648  -1          A18X+079273Y+047534X0198Y0197     S2      
327E1S_0_P3V3_EN    R757  -1   M      A18X+082027Y+047616X0198Y0197R180 S2      
317E1S_0_P3V3_EN    VIA   -    MD0100PA00X+086030Y+049162X0200Y         S0      
317E1S_0_P3V3_EN    VIA   -    MD0100PA00X+080134Y+027914X0200Y         S0      
327E1S_0_P3V3_EN    R4063 -1          A01X+098488Y+027144X0198Y0197     S1      
317E1S_0_P3V3_EN    VIA   -    M      A01X+098246Y+027144X0200Y         S2      
017E1S_0_P3V3_EN    VIA   -    M      A18X+098246Y+027144X0260Y         S2      
017E1S_0_P3V3_EN          -    MD0100PA00X+098246Y+027144                       
317E1S_0_P12V_EN    VIA   -    MD0100PA00X+102052Y+019450X0200Y         S0      
327E1S_0_P12V_EN    R3943 -1          A01X+101690Y+019450X0198Y0197R180 S1      
327E1S_0_P12V_EN    R4064 -1          A01X+098488Y+026078X0198Y0197     S1      
317E1S_0_P12V_EN    VIA   -    M      A01X+098246Y+026078X0200Y         S2      
017E1S_0_P12V_EN    VIA   -    M      A18X+098246Y+026078X0260Y         S2      
017E1S_0_P12V_EN          -    MD0100PA00X+098246Y+026078                       
317E1S_0_P12V_EN    VIA   -    MD0100PA00X+095805Y+045391X0200Y         S0      
317E1S_0_P12V_EN    VIA   -    MD0100PA00X+079720Y+044734X0200Y         S0      
327E1S_0_P12V_EN    R1314 -1   M      A01X+079273Y+044734X0198Y0197R180 S1      
327E1S_0_P12V_EN    R199  -1          A01X+077823Y+045134X0198Y0197R180 S1      
327m2202            R1517 -1          A18X+040443Y+163122X0198Y0197R180 S2      
317m2202            VIA   -    MD0100PA00X+014164Y+049415X0200Y    R180 S0      
327m2202            R3341 -1          A01X+005290Y+050451X0198Y0197R090 S1      
317m2202            VIA   -    M      A01X+058695Y+006344X0200Y         S2      
017m2202            VIA   -    M      A18X+058695Y+006344X0260Y         S2      
017m2202                  -    MD0100PA00X+058695Y+006344                       
327m2202            R2418 -1          A18X+059010Y+005576X0198Y0197R090 S2      
327m2202            R2213 -1          A18X+058944Y+006809X0198Y0197R270 S2      
317m2202            VIA   -    MD0100PA00X+015284Y+156267X0200Y         S0      
317m2202            VIA   -    MD0100PA00X+040534Y+162861X0200Y         S0      
327m2203            R1516 -1          A18X+039942Y+162680X0198Y0197R180 S2      
317m2203            VIA   -    MD0100PA00X+040544Y+162027X0200Y         S0      
317m2203            VIA   -    MD0100PA00X+014164Y+048868X0200Y    R180 S0      
327m2203            R3340 -1          A01X+004850Y+050470X0198Y0197R090 S1      
317m2203            VIA   -    M      A01X+059107Y+006020X0200Y         S2      
017m2203            VIA   -    M      A18X+059107Y+006020X0260Y         S2      
017m2203                  -    MD0100PA00X+059107Y+006020                       
327m2203            R2212 -1          A18X+059444Y+006809X0198Y0197R270 S2      
327m2203            R2417 -1          A18X+059440Y+005576X0198Y0197R090 S2      
317m2203            VIA   -    MD0100PA00X+015284Y+155915X0200Y         S0      
327m2204            U26   -DJ45       A01X+041720Y+116414X0177Y    R180 S1      
327m2204            R4305 -1          A01X+048350Y+126479X0198Y0197R090 S1      
327m2205            U26   -DJ44       A01X+042090Y+116414X0177Y    R180 S1      
327m2205            R4306 -1          A01X+048750Y+126479X0198Y0197R090 S1      
327m2206            VIA   -    M      A01X+048486Y+134092X0160Y0041R090 S1      
327m2206            R4305 -2          A01X+048350Y+126794X0198Y0197R090 S1      
317m2206            VIA   -    MD0100PA00X+055888Y+145830X0200Y         S0      
317m2206            VIA   -    MD0100PA00X+070477Y+016779X0200Y         S0      
327m2206            J59   -55         A01X+069728Y+016850X0110Y0630R270 S1      
327m2207            VIA   -    M      A01X+048614Y+135143X0160Y0041R090 S1      
327m2207            R4306 -2          A01X+048750Y+126794X0198Y0197R090 S1      
317m2207            VIA   -    MD0100PA00X+055888Y+145490X0200Y         S0      
317m2207            VIA   -    MD0100PA00X+070477Y+017119X0200Y         S0      
327m2207            J59   -53         A01X+069728Y+017047X0110Y0630R270 S1      
327m2208            U26   -B9         A01X+054739Y+087748X0177Y    R180 S1      
327m2208            VIA   -    M      A01X+059685Y+076550X0160Y0041R090 S1      
327m2208            R3200 -1          A01X+059549Y+075494X0198Y0197R270 S1      
327m2209            U26   -C9         A01X+054554Y+088067X0177Y    R180 S1      
327m2209            VIA   -    M      A01X+059812Y+075950X0160Y0041R090 S1      
327m2209            R3201 -1          A01X+059949Y+075494X0198Y0197R270 S1      
327m2210            R3200 -2          A01X+059549Y+075179X0198Y0197R270 S1      
317m2210            VIA   -    MD0100PA00X+064636Y+059032X0200Y         S2      
317m2210            VIA   -    MD0100PA00X+028083Y+002594X0200Y         S0      
327m2210            J35   -OA12       A01X+028135Y+003276X0150Y0570R180 S1      
327m2211            R3201 -2          A01X+059949Y+075179X0198Y0197R270 S1      
317m2211            VIA   -    MD0100PA00X+065026Y+059032X0200Y         S2      
317m2211            VIA   -    MD0100PA00X+028423Y+002594X0200Y         S0      
327m2211            J35   -OA11       A01X+028371Y+003276X0150Y0570R180 S1      
327m2212            U26   -B12        A01X+053629Y+087748X0177Y    R180 S1      
327m2212            VIA   -    M      A01X+058049Y+076910X0160Y0041R090 S1      
327m2212            R3198 -1          A01X+057912Y+075494X0198Y0197R270 S1      
327m2213            U26   -C12        A01X+053444Y+088067X0177Y    R180 S1      
327m2213            VIA   -    M      A01X+058176Y+075970X0160Y0041R090 S1      
327m2213            R3199 -1          A01X+058312Y+075494X0198Y0197R270 S1      
327m2214            R3198 -2          A01X+057912Y+075179X0198Y0197R270 S1      
317m2214            VIA   -    MD0100PA00X+064441Y+057117X0200Y         S2      
317m2214            VIA   -    MD0100PA00X+028083Y+005065X0200Y         S0      
327m2214            J35   -OB12       A01X+028135Y+004437X0150Y0570R180 S1      
327m2215            R3199 -2          A01X+058312Y+075179X0198Y0197R270 S1      
317m2215            VIA   -    MD0100PA00X+064831Y+057117X0200Y         S2      
317m2215            VIA   -    MD0100PA00X+028423Y+005065X0200Y    R180 S0      
327m2215            J35   -OB11       A01X+028371Y+004437X0150Y0570R180 S1      
327m2216            U26   -A10        A01X+054184Y+087429X0177Y    R180 S1      
327m2216            VIA   -    M      A01X+059016Y+075940X0160Y0041R090 S1      
327m2216            R3196 -1          A01X+059152Y+075501X0198Y0197R270 S1      
327m2217            U26   -A11        A01X+053814Y+087429X0177Y    R180 S1      
327m2217            VIA   -    M      A01X+058889Y+076920X0160Y0041R090 S1      
327m2217            R3197 -1          A01X+058752Y+075501X0198Y0197R270 S1      
327m2218            R3196 -2          A01X+059152Y+075186X0198Y0197R270 S1      
317m2218            VIA   -    MD0100PA00X+063869Y+059050X0200Y         S2      
327m2218            J35   -A15        A01X+022625Y+003276X0150Y0570R180 S1      
317m2218            VIA   -    MD0100PA00X+022573Y+002648X0200Y         S0      
327m2219            R3197 -2          A01X+058752Y+075186X0198Y0197R270 S1      
317m2219            VIA   -    MD0100PA00X+063479Y+059050X0200Y         S2      
327m2219            J35   -A14        A01X+022861Y+003276X0150Y0570R180 S1      
317m2219            VIA   -    MD0100PA00X+022913Y+002648X0200Y         S0      
327m2220            U26   -B6         A01X+055850Y+087748X0177Y    R180 S1      
327m2220            VIA   -    M      A01X+060706Y+077139X0160Y0041R292 S1      
327m2220            R3194 -1          A01X+061144Y+075497X0198Y0197R270 S1      
327m2221            U26   -C6         A01X+055664Y+088067X0177Y    R180 S1      
327m2221            VIA   -    M      A01X+061347Y+075923X0160Y0041R292 S1      
327m2221            R3195 -1          A01X+061544Y+075497X0198Y0197R270 S1      
327m2222            R3194 -2          A01X+061144Y+075182X0198Y0197R270 S1      
317m2222            VIA   -    M      A01X+063557Y+067177X0200Y         S2      
017m2222            VIA   -    M      A18X+063557Y+067177X0260Y         S2      
017m2222                  -    MD0100PA00X+063557Y+067177                       
327m2222            J35   -B15        A01X+022625Y+004437X0150Y0570R180 S1      
317m2222            VIA   -    MD0100PA00X+022573Y+005065X0200Y    R180 S0      
327m2223            R3195 -2          A01X+061544Y+075182X0198Y0197R270 S1      
317m2223            VIA   -    M      A01X+063897Y+067177X0300Y         S1      
017m2223            VIA   -    M      A18X+063897Y+067177X0200Y         S1      
017m2223                  -    MD0100PA00X+063897Y+067177                       
327m2223            J35   -B14        A01X+022861Y+004437X0150Y0570R180 S1      
317m2223            VIA   -    MD0100PA00X+022913Y+005065X0200Y         S0      
327m2224            R3354 -1          A01X+060346Y+075495X0198Y0197R270 S1      
327m2224            U26   -A8         A01X+054924Y+087429X0177Y    R180 S1      
327m2224            VIA   -    M      A01X+060065Y+077293X0160Y0041R315 S1      
327m2225            U26   -A7         A01X+055294Y+087429X0177Y    R180 S1      
327m2225            VIA   -    M      A01X+060609Y+076039X0160Y0041R090 S1      
327m2225            R3355 -1          A01X+060746Y+075495X0198Y0197R270 S1      
317m2226            J112  -P1   D0142PA01X+023090Y+166335X0302Y    R180 S3      
317m2226            VIA   -    MD0100PA01X+081430Y+138744X0200Y         S0      
327m2226            VIA   -    M      A01X+082917Y+132319X0160Y0041R090 S1      
327m2226            R3354 -2          A01X+060346Y+075180X0198Y0197R270 S1      
317m2227            J112  -O1   D0142PA01X+023090Y+166807X0302Y    R180 S3      
317m2227            VIA   -    MD0100PA01X+081430Y+138404X0200Y         S0      
327m2227            VIA   -    M      A01X+082790Y+131268X0160Y0041R090 S1      
327m2227            R3355 -2          A01X+060746Y+075180X0198Y0197R270 S1      
327m2228            U25   -DJ45       A01X+139334Y+116413X0177Y    R180 S1      
317m2228            VIA   -    MD0100PA00X+134095Y+117768X0200Y         S0      
327m2228            R4303 -1          A18X+135242Y+118705X0198Y0197R270 S2      
327m2229            U25   -DJ44       A01X+139704Y+116413X0177Y    R180 S1      
317m2229            VIA   -    MD0100PA00X+134095Y+118168X0200Y         S0      
327m2229            R4304 -1          A18X+134842Y+118705X0198Y0197R270 S2      
327m2230            J90   -B15        A01X+093150Y+020065X0150Y0500R090 S1      
317m2230            VIA   -    MD0100PA00X+102549Y+076182X0200Y         S2      
327m2230            R4303 -2          A18X+135242Y+119020X0198Y0197R270 S2      
317m2231            VIA   -    MD0100PA00X+102549Y+076572X0200Y         S2      
327m2231            J90   -B14        A01X+093150Y+019829X0150Y0500R090 S1      
327m2231            R4304 -2          A18X+134842Y+119020X0198Y0197R270 S2      
317m2232            VIA   -    MD0100PA00X+070840Y+047182X0180Y    R090 S2      
317m2232            VIA   -    MD0100PA00X+065111Y+047388X0200Y         S0      
327m2232            R6031 -2          A01X+064624Y+047390X0198Y0197     S1      
327m2232            U18   -E17        A01X+070993Y+047029X0160Y    R090 S1      
327m2233            U247  -16         A01X+006072Y+052870X0100Y0220R270 S1      
327m2233            VIA   -           A18X+006539Y+052455X0260Y         S2      
317m2233            VIA   -    MD0100PA00X+006363Y+052823X0200Y    R090 S0      
327m2233            R4077 -2          A18X+006077Y+053184X0198Y0197R090 S2      
327m2233            C1884 -1          A18X+006082Y+052437X0198Y0197R090 S2      
327m2233            C97   -1          A18X+006080Y+052820X0198Y0197     S2      
327VFG3P3_CLK_GEN   U247  -11         A01X+005629Y+052033X0100Y0220     S1      
327VFG3P3_CLK_GEN   U247  -20         A01X+005629Y+053510X0100Y0220     S1      
327VFG3P3_CLK_GEN   U247  -7          A01X+004841Y+052033X0100Y0220     S1      
327VFG3P3_CLK_GEN   U247  -3          A01X+004595Y+052870X0100Y0220R270 S1      
327VFG3P3_CLK_GEN   C95   -1          A18X+005374Y+053484X0198Y0197R090 S2      
327VFG3P3_CLK_GEN   C1886 -1          A18X+004610Y+052030X0198Y0197R270 S2      
317VFG3P3_CLK_GEN   VIA   -    MD0100PA00X+004781Y+051764X0200Y    R180 S0      
317VFG3P3_CLK_GEN   VIA   -    MD0100PA00X+005568Y+051760X0200Y    R180 S0      
327VFG3P3_CLK_GEN   C1889 -1          A18X+004577Y+052830X0198Y0197R180 S2      
327VFG3P3_CLK_GEN   C2257 -1          A18X+004591Y+053398X0198Y0197R180 S2      
327VFG3P3_CLK_GEN   C1883 -1          A18X+004636Y+053928X0400Y0500R180 S2      
317VFG3P3_CLK_GEN   VIA   -    MD0100PA00X+004281Y+052807X0200Y    R180 S0      
327VFG3P3_CLK_GEN   R4077 -1          A18X+006077Y+053499X0198Y0197R090 S2      
317VFG3P3_CLK_GEN   VIA   -    MD0100PA00X+005619Y+053780X0200Y    R180 S0      
327VFG3P3_CLK_GEN   L17   -2          A18X+004629Y+054700X0440Y0540     S2      
317VFG3P3_CLK_GEN   VIA   -           A01X+006214Y+053950X0200Y    R180 S2      
017VFG3P3_CLK_GEN   VIA   -           A18X+006214Y+053950X0260Y    R180 S2      
017VFG3P3_CLK_GEN         -     D0100PA00X+006214Y+053950                       
317m2234            VIA   -    MD0080PA01X+146431Y+087962X0160Y    R180 S0      
327m2234            C6003 -1   M      A01X+057336Y+012278X0180Y0200R270 S1      
327m2234            C6013 -1   M      A01X+057336Y+012278X0180Y0200R090 S1      
327m2234            R341  -1   M      A01X+057336Y+012278X0180Y0200R180 S1      
317m2234            VIA   -    MD0100PA01X+057086Y+012471X0200Y         S0      
327m2234            U25   -C25        A01X+146247Y+088067X0177Y    R180 S1      
317m2235            VIA   -    MD0080PA01X+146061Y+087962X0160Y    R180 S0      
327m2235            C6004 -1   M      A01X+056836Y+012278X0180Y0200R270 S1      
327m2235            C6014 -1   M      A01X+056836Y+012278X0180Y0200R090 S1      
327m2235            R342  -1   M      A01X+056836Y+012278X0180Y0200     S1      
317m2235            VIA   -    MD0100PA01X+057086Y+012131X0200Y         S0      
327m2235            U25   -C26        A01X+145877Y+088067X0177Y    R180 S1      
327m2236            J41   -B59        A01X+053680Y+006516X0150Y0570R180 S1      
327m2236            C6025 -2          A01X+048408Y+014439X0180Y0200R180 S1      
327m2236            C6023 -2   M      A01X+048408Y+014439X0180Y0200     S1      
317m2236            VIA   -    MD0100PA01X+048238Y+014194X0200Y         S0      
317m2236            VIA   -    MD0100PA01X+054062Y+008821X0200Y         S0      
327m2237            J41   -B60        A01X+053444Y+006516X0150Y0570R180 S1      
327m2237            C6026 -2          A01X+048408Y+013949X0180Y0200R180 S1      
327m2237            C6024 -2   M      A01X+048408Y+013949X0180Y0200     S1      
317m2237            VIA   -    MD0100PA01X+048578Y+014194X0200Y         S0      
317m2237            VIA   -    MD0100PA01X+053821Y+009062X0200Y         S0      
327m2238            J41   -A59        A01X+053680Y+005354X0150Y0570R180 S1      
317m2238            VIA   -    MD0100PA01X+049378Y+013144X0200Y         S0      
317m2238            VIA   -    MD0100PA01X+053732Y+004707X0200Y         S0      
327m2238            C6019 -1          A01X+049208Y+012894X0180Y0200R180 S1      
327m2238            C6021 -1   M      A01X+049208Y+012894X0180Y0200     S1      
327m2239            J41   -A60        A01X+053444Y+005354X0150Y0570R180 S1      
317m2239            VIA   -    MD0100PA01X+049038Y+013144X0200Y         S0      
317m2239            VIA   -    MD0100PA01X+053392Y+004707X0200Y         S0      
327m2239            C6020 -1          A01X+049208Y+013394X0180Y0200R180 S1      
327m2239            C6022 -1   M      A01X+049208Y+013394X0180Y0200     S1      
317UART_VCC_J8      VIA   -    M      A01X+124915Y+007290X0200Y         S2      
017UART_VCC_J8      VIA   -    M      A18X+124915Y+007290X0260Y         S2      
017UART_VCC_J8            -    MD0100PA00X+124915Y+007290                       
317UART_VCC_J8      J8    -1    D0320PA00X+124915Y+006038X0480Y0480     S3      
327UART_VCC_J8      R131  -2   M      A01X+125947Y+008729X0198Y0197R270 S1      
327UART_VCC_J8      R130  -1          A01X+126347Y+008729X0198Y0197R090 S1      
327m2240            U181  -7          A01X+072702Y+164333X0160Y0540     S1      
327m2241            U181  -6          A01X+072446Y+164333X0160Y0540     S1      
327m2242            J41   -B28        A01X+064042Y+006516X0150Y0570R180 S1      
327m2242            VIA   -           A01X+064254Y+007844X0300Y         S1      
327TP_BEEP_LED      J41   -B69        A01X+051318Y+006516X0150Y0570R180 S1      
327TP_BEEP_LED      VIA   -           A01X+051048Y+007777X0300Y         S1      
327TCA9539_0_ADD1   VIA   -    M      A01X+070800Y+163077X0300Y         S1      
327TCA9539_0_ADD1   R2693 -2          A01X+069980Y+163077X0198Y0197R090 S1      
327TCA9539_0_ADD1   U181  -2          A01X+071422Y+164333X0160Y0540     S1      
327TCA9539_0_ADD1   R2694 -1   M      A01X+070380Y+163077X0198Y0197R270 S1      
327TCA9539_0_ADD0   VIA   -    M      A01X+070466Y+167847X0300Y         S1      
327TCA9539_0_ADD0   U181  -21         A01X+071934Y+166636X0160Y0540     S1      
327TCA9539_0_ADD0   R2695 -2   M      A01X+069991Y+167847X0198Y0197     S1      
327TCA9539_0_ADD0   R2696 -1          A01X+069991Y+168200X0198Y0197R180 S1      
317m2243            VIA   -    M      A01X+105696Y+048226X0200Y         S2      
017m2243            VIA   -    M      A18X+105696Y+048226X0260Y         S2      
017m2243                  -    MD0100PA00X+105696Y+048226                       
327m2243            U39   -23         A01X+105108Y+048084X0120Y0630R270 S1      
327m2243            R3712 -2          A01X+106569Y+048766X0198Y0197R180 S1      
327m2244            R3711 -2          A01X+106569Y+048366X0198Y0197R180 S1      
317m2244            VIA   -    M      A01X+106225Y+048467X0200Y         S2      
017m2244            VIA   -    M      A18X+106225Y+048467X0260Y         S2      
017m2244                  -    MD0100PA00X+106225Y+048467                       
327m2244            U39   -22         A01X+105108Y+047828X0120Y0630R270 S1      
327m2245            U39   -4          A01X+102904Y+047572X0120Y0630R270 S1      
327m2245            R3714 -1          A01X+101434Y+048016X0198Y0197R180 S1      
317m2245            VIA   -    M      A01X+101921Y+048016X0200Y         S2      
017m2245            VIA   -    M      A18X+101921Y+048016X0260Y         S2      
017m2245                  -    MD0100PA00X+101921Y+048016                       
327m2246            R3713 -1          A01X+101434Y+047616X0198Y0197R180 S1      
327m2246            U39   -5          A01X+102904Y+047316X0120Y0630R270 S1      
317m2246            VIA   -    M      A01X+102287Y+047454X0200Y         S2      
017m2246            VIA   -    M      A18X+102287Y+047454X0260Y         S2      
017m2246                  -    MD0100PA00X+102287Y+047454                       
327m2247            R2424 -1          A18X+064522Y+005534X0198Y0197R090 S2      
327m2247            R329  -1          A18X+064783Y+006857X0198Y0197R180 S2      
327m2247            VIA   -    M      A18X+064581Y+006005X0260Y         S2      
327m2247            R2996 -1   M      A18X+064786Y+006474X0198Y0197R180 S2      
327m2248            R2423 -1          A18X+064922Y+005534X0198Y0197R090 S2      
327m2248            VIA   -    M      A18X+065389Y+005431X0260Y         S2      
327m2248            R1386 -1          A18X+066286Y+005538X0198Y0197R270 S2      
327m2248            R2995 -1   M      A18X+065874Y+005536X0198Y0197R270 S2      
327m2249            U36   -10         A01X+111861Y+046036X0120Y0630R270 S1      
327m2249            R3527 -1          A01X+110202Y+045136X0198Y0197R180 S1      
327m2249            VIA   -    M      A01X+110904Y+045286X0300Y         S1      
327m2250            U36   -8          A01X+111861Y+046548X0120Y0630R270 S1      
327m2250            R2968 -1          A01X+110202Y+045936X0198Y0197R180 S1      
317m2250            VIA   -    M      A01X+111108Y+046439X0200Y         S2      
017m2250            VIA   -    M      A18X+111108Y+046439X0260Y         S2      
017m2250                  -    MD0100PA00X+111108Y+046439                       
327m2251            U36   -23         A01X+114066Y+048084X0120Y0630R270 S1      
317m2251            VIA   -    M      A01X+115876Y+048952X0200Y         S2      
017m2251            VIA   -    M      A18X+115876Y+048952X0260Y         S2      
017m2251                  -    MD0100PA00X+115876Y+048952                       
317m2251            VIA   -    MD0100PA00X+064496Y+002914X0200Y         S0      
327m2251            R55   -2          A18X+064767Y+003391X0198Y0197R090 S2      
327m2252            U36   -11         A01X+111861Y+045780X0120Y0630R270 S1      
327m2252            R3526 -1          A01X+110202Y+044736X0198Y0197R180 S1      
327m2252            VIA   -    M      A01X+110704Y+044736X0300Y         S1      
327m2253            U36   -9          A01X+111861Y+046292X0120Y0630R270 S1      
317m2253            VIA   -    M      A01X+110730Y+045694X0200Y         S2      
017m2253            VIA   -    M      A18X+110730Y+045694X0260Y         S2      
017m2253                  -    MD0100PA00X+110730Y+045694                       
327m2253            R2967 -1          A01X+110202Y+045536X0198Y0197R180 S1      
317m2254            VIA   -    MD0100PA00X+116214Y+048763X0200Y         S0      
327m2254            U36   -22         A01X+114066Y+047828X0120Y0630R270 S1      
327m2254            R65   -2          A18X+065191Y+003391X0198Y0197R090 S2      
317m2254            VIA   -    M      A01X+065412Y+002910X0200Y         S2      
017m2254            VIA   -    M      A18X+065412Y+002910X0260Y         S2      
017m2254                  -    MD0100PA00X+065412Y+002910                       
327m2255            U39   -13         A01X+105108Y+045524X0120Y0630R270 S1      
327m2255            R3722 -1          A01X+106569Y+044966X0198Y0197     S1      
317m2255            VIA   -    M      A01X+106264Y+044916X0200Y         S2      
017m2255            VIA   -    M      A18X+106264Y+044916X0260Y         S2      
017m2255                  -    MD0100PA00X+106264Y+044916                       
327m2256            R3721 -1          A01X+106569Y+045366X0198Y0197     S1      
317m2256            VIA   -    M      A01X+105728Y+045816X0200Y         S2      
017m2256            VIA   -    M      A18X+105728Y+045816X0260Y         S2      
017m2256                  -    MD0100PA00X+105728Y+045816                       
327m2256            U39   -14         A01X+105108Y+045780X0120Y0630R270 S1      
327m2257            U39   -10         A01X+102904Y+046036X0120Y0630R270 S1      
317m2257            VIA   -    M      A01X+101920Y+045769X0200Y         S2      
017m2257            VIA   -    M      A18X+101920Y+045769X0260Y         S2      
017m2257                  -    MD0100PA00X+101920Y+045769                       
327m2257            R3720 -1          A01X+101434Y+045616X0198Y0197R180 S1      
327m2258            U39   -11         A01X+102904Y+045780X0120Y0630R270 S1      
317m2258            VIA   -    M      A01X+102352Y+045440X0200Y         S2      
017m2258            VIA   -    M      A18X+102352Y+045440X0260Y         S2      
017m2258                  -    MD0100PA00X+102352Y+045440                       
327m2258            R3719 -1          A01X+101434Y+045216X0198Y0197R180 S1      
327m2259            U39   -8          A01X+102904Y+046548X0120Y0630R270 S1      
327m2259            R3718 -1          A01X+101434Y+046416X0198Y0197R180 S1      
317m2259            VIA   -    M      A01X+101722Y+046416X0200Y         S2      
017m2259            VIA   -    M      A18X+101722Y+046416X0260Y         S2      
017m2259                  -    MD0100PA00X+101722Y+046416                       
327m2260            U39   -9          A01X+102904Y+046292X0120Y0630R270 S1      
327m2260            R3717 -1          A01X+101434Y+046016X0198Y0197R180 S1      
317m2260            VIA   -    M      A01X+102342Y+046292X0200Y         S2      
017m2260            VIA   -    M      A18X+102342Y+046292X0260Y         S2      
017m2260                  -    MD0100PA00X+102342Y+046292                       
327m2261            U39   -6          A01X+102904Y+047060X0120Y0630R270 S1      
327m2261            R3716 -1          A01X+101434Y+047216X0198Y0197R180 S1      
317m2261            VIA   -    M      A01X+101735Y+047216X0200Y         S2      
017m2261            VIA   -    M      A18X+101735Y+047216X0260Y         S2      
017m2261                  -    MD0100PA00X+101735Y+047216                       
327m2262            R3715 -1          A01X+101434Y+046816X0198Y0197R180 S1      
327m2262            U39   -7          A01X+102904Y+046804X0120Y0630R270 S1      
317m2262            VIA   -    M      A01X+102342Y+046804X0200Y         S2      
017m2262            VIA   -    M      A18X+102342Y+046804X0260Y         S2      
017m2262                  -    MD0100PA00X+102342Y+046804                       
327m2263            R2983 -2          A01X+069999Y+167041X0198Y0197     S1      
327m2263            VIA   -    M      A01X+070402Y+167151X0300Y         S1      
327m2263            U181  -23         A01X+071422Y+166636X0160Y0540     S1      
327m2264            U36   -6          A01X+111861Y+047060X0120Y0630R270 S1      
327m2264            R3394 -1          A01X+110202Y+046736X0198Y0197R180 S1      
327m2264            VIA   -    M      A01X+111104Y+047186X0300Y         S1      
327m2265            R2983 -1          A01X+069684Y+167041X0198Y0197     S1      
317m2265            VIA   -    M      A01X+108585Y+046598X0200Y         S2      
017m2265            VIA   -    M      A18X+108585Y+046598X0260Y         S2      
017m2265                  -    MD0100PA00X+108585Y+046598                       
317m2265            VIA   -    MD0100PA00X+026633Y+052246X0200Y    R090 S0      
327m2265            R3394 -2          A01X+109887Y+046736X0198Y0197R180 S1      
327m2265            R3583 -2   M      A01X+109351Y+046810X0198Y0197     S1      
317m2265            VIA   -    MD0100PA00X+069361Y+167108X0200Y         S0      
317m2265            VIA   -    MD0100PA00X+037240Y+167745X0200Y         S0      
317m2265            VIA   -    MD0100PA00X+011766Y+162177X0200Y         S0      
327m2266            R2982 -2          A01X+070003Y+167443X0198Y0197     S1      
327m2266            VIA   -    M      A01X+070952Y+167443X0300Y         S1      
327m2266            U181  -22         A01X+071678Y+166636X0160Y0540     S1      
327m2267            U36   -7          A01X+111861Y+046804X0120Y0630R270 S1      
327m2267            R3393 -1          A01X+110202Y+046336X0198Y0197R180 S1      
327m2267            VIA   -    M      A01X+110704Y+046804X0300Y         S1      
327m2268            R2982 -1          A01X+069688Y+167443X0198Y0197     S1      
317m2268            VIA   -    MD0100PA00X+069348Y+167394X0200Y         S0      
317m2268            VIA   -    MD0100PA00X+037245Y+168052X0200Y         S0      
317m2268            VIA   -    MD0100PA00X+011462Y+162454X0200Y         S0      
317m2268            VIA   -    M      A01X+108484Y+046000X0200Y         S2      
017m2268            VIA   -    M      A18X+108484Y+046000X0260Y         S2      
017m2268                  -    MD0100PA00X+108484Y+046000                       
317m2268            VIA   -    MD0100PA00X+026957Y+052237X0200Y    R090 S0      
327m2268            R3393 -2          A01X+109887Y+046336X0198Y0197R180 S1      
327m2268            R3582 -2   M      A01X+109351Y+046260X0198Y0197     S1      
327m2269            R3581 -1          A01X+115756Y+046569X0198Y0197     S1      
327m2269            U36   -17         A01X+114066Y+046548X0120Y0630R270 S1      
327m2269            VIA   -    M      A01X+115254Y+046548X0300Y         S1      
327m2270            R1345 -1   M      A01X+118000Y+043058X0198Y0197R270 S1      
327m2270            R1347 -1          A01X+057548Y+019748X0198Y0197     S1      
317m2270            VIA   -    MD0100PA00X+118000Y+043600X0200Y         S0      
327m2270            R3587 -1          A01X+118085Y+046162X0198Y0197R090 S1      
327m2270            R3581 -2          A01X+116071Y+046569X0198Y0197     S1      
327m2270            R3396 -2   M      A01X+116963Y+046434X0198Y0197R180 S1      
317m2270            VIA   -    MD0100PA00X+117834Y+046162X0200Y         S0      
317m2270            VIA   -    MD0100PA00X+085422Y+012936X0200Y         S0      
327m2270            R3593 -1          A01X+085180Y+012936X0198Y0197R180 S1      
327m2270            R3589 -1          A01X+084022Y+018479X0198Y0197R090 S1      
317m2270            VIA   -    MD0100PA00X+084272Y+018136X0200Y         S0      
317m2270            VIA   -    M      A01X+059729Y+019319X0200Y         S2      
017m2270            VIA   -    M      A18X+059729Y+019319X0260Y         S2      
017m2270                  -    MD0100PA00X+059729Y+019319                       
327m2270            R3591 -1   M      A01X+059829Y+019819X0198Y0197R090 S1      
327m2270            R3595 -1          A01X+060229Y+019819X0198Y0197R090 S1      
317m2270            VIA   -    MD0100PA00X+057544Y+020078X0200Y         S0      
327m2270            R1349 -1          A01X+118400Y+042900X0198Y0197R270 S1      
327m2271            R3580 -1          A01X+115756Y+046969X0198Y0197     S1      
327m2271            U36   -18         A01X+114066Y+046804X0120Y0630R270 S1      
327m2271            VIA   -    M      A01X+114804Y+046804X0300Y         S1      
327m2272            R1348 -1          A01X+117200Y+043058X0198Y0197R270 S1      
327m2272            R1344 -1   M      A01X+117600Y+043058X0198Y0197R270 S1      
327m2272            R1346 -1          A01X+057546Y+019352X0198Y0197     S1      
317m2272            VIA   -    MD0100PA00X+057542Y+018984X0200Y         S0      
317m2272            VIA   -    MD0100PA00X+117600Y+043650X0200Y         S0      
327m2272            R3586 -1          A01X+117834Y+046959X0198Y0197R090 S1      
327m2272            R3580 -2          A01X+116071Y+046969X0198Y0197     S1      
327m2272            R3395 -2   M      A01X+116963Y+046984X0198Y0197R180 S1      
317m2272            VIA   -    MD0100PA00X+117834Y+046716X0200Y         S0      
317m2272            VIA   -    MD0100PA00X+085422Y+013586X0200Y         S0      
327m2272            R3592 -1          A01X+085180Y+013586X0198Y0197R180 S1      
327m2272            R3588 -1          A01X+084422Y+018479X0198Y0197R090 S1      
317m2272            VIA   -    MD0100PA00X+084572Y+018136X0200Y         S0      
317m2272            VIA   -    M      A01X+060429Y+019318X0200Y         S2      
017m2272            VIA   -    M      A18X+060429Y+019318X0260Y         S2      
017m2272                  -    MD0100PA00X+060429Y+019318                       
327m2272            R3594 -1          A01X+060879Y+019819X0198Y0197R090 S1      
327m2272            R3590 -1   M      A01X+060879Y+019434X0198Y0197R270 S1      
327m2273            U36   -15         A01X+114066Y+046036X0120Y0630R270 S1      
327m2273            R2566 -1          A01X+115756Y+045769X0198Y0197     S1      
327m2273            VIA   -    M      A01X+115254Y+045986X0300Y         S1      
327m2274            R2565 -1          A01X+115756Y+046169X0198Y0197     S1      
327m2274            U36   -16         A01X+114066Y+046292X0120Y0630R270 S1      
327m2274            VIA   -    M      A01X+114804Y+046292X0300Y         S1      
317m2275            VIA   -    M      A01X+074652Y+030880X0200Y         S2      
017m2275            VIA   -    M      A18X+074652Y+030880X0260Y         S2      
017m2275                  -    MD0100PA00X+074652Y+030880                       
327m2275            U96   -6          A18X+096028Y+086994X0170Y0460     S2      
317m2275            VIA   -    MD0100PA00X+095800Y+086200X0200Y         S0      
317m2275            VIA   -    MD0100PA00X+069522Y+006046X0200Y         S0      
327m2275            R4507 -1   M      A18X+069440Y+005576X0198Y0197R090 S2      
327m2275            R1385 -1          A18X+069029Y+005791X0198Y0197R090 S2      
317m2276            VIA   -    M      A01X+074759Y+031911X0200Y         S2      
017m2276            VIA   -    M      A18X+074759Y+031911X0260Y         S2      
017m2276                  -    MD0100PA00X+074759Y+031911                       
327m2276            U96   -7          A18X+095772Y+086994X0170Y0460     S2      
317m2276            VIA   -    MD0100PA00X+095800Y+086550X0200Y         S0      
317m2276            VIA   -    MD0100PA00X+069846Y+006068X0200Y         S0      
327m2276            R1384 -1          A18X+070248Y+005573X0198Y0197R090 S2      
327m2276            R4506 -1   M      A18X+069860Y+005576X0198Y0197R090 S2      
327m2277            R150  -1          A18X+092158Y+089800X0180Y0200     S2      
327m2277            R162  -1   M      A18X+092158Y+089800X0180Y0200R180 S2      
317m2277            VIA   -    MD0100PA00X+092300Y+089550X0200Y         S0      
317m2277            VIA   -    M      A01X+081207Y+034159X0200Y         S2      
017m2277            VIA   -    M      A18X+081207Y+034159X0260Y         S2      
017m2277                  -    MD0100PA00X+081207Y+034159                       
327m2277            R3062 -1          A18X+071067Y+009156X0198Y0197R270 S2      
317m2277            VIA   -    MD0100PA00X+071272Y+008471X0200Y         S0      
327m2277            R2420 -1          A18X+071204Y+008180X0198Y0197R090 S2      
327m2278            R140  -1          A18X+092158Y+089300X0180Y0200     S2      
327m2278            R151  -1   M      A18X+092158Y+089300X0180Y0200R180 S2      
317m2278            VIA   -    MD0100PA00X+092000Y+089550X0200Y         S0      
317m2278            VIA   -    M      A01X+081623Y+034158X0300Y         S1      
017m2278            VIA   -    M      A18X+081623Y+034158X0200Y         S1      
017m2278                  -    MD0100PA00X+081623Y+034158                       
327m2278            R1319 -1          A18X+071467Y+009156X0198Y0197R270 S2      
317m2278            VIA   -    MD0100PA00X+071574Y+008630X0200Y         S0      
327m2278            R2419 -1          A18X+071603Y+008180X0198Y0197R090 S2      
327m2279            U36   -13         A01X+114066Y+045524X0120Y0630R270 S1      
327m2279            R2704 -1          A01X+115756Y+044969X0198Y0197     S1      
327m2279            VIA   -    M      A01X+115204Y+045312X0300Y         S1      
317m2280            VIA   -    M      A01X+093922Y+066477X0200Y         S2      
017m2280            VIA   -    M      A18X+093922Y+066477X0260Y         S2      
017m2280                  -    MD0100PA00X+093922Y+066477                       
317m2280            VIA   -    MD0100PA00X+117834Y+044223X0200Y         S0      
317m2280            VIA   -    MD0100PA00X+065876Y+170715X0200Y         S0      
327m2280            R3106 -1          A01X+065638Y+170818X0198Y0197R180 S1      
317m2280            VIA   -    MD0100PA00X+090639Y+081572X0200Y         S0      
327m2280            R2985 -2   M      A01X+116963Y+044234X0198Y0197R180 S1      
327m2280            R2704 -2          A01X+116071Y+044969X0198Y0197     S1      
327m2281            U36   -14         A01X+114066Y+045780X0120Y0630R270 S1      
327m2281            R2703 -1          A01X+115756Y+045369X0198Y0197     S1      
327m2281            VIA   -    M      A01X+114804Y+045686X0300Y         S1      
317m2282            VIA   -    M      A01X+117834Y+044773X0200Y         S2      
017m2282            VIA   -    M      A18X+117834Y+044773X0260Y         S2      
017m2282                  -    MD0100PA00X+117834Y+044773                       
317m2282            VIA   -    MD0100PA00X+065315Y+168326X0200Y         S0      
317m2282            VIA   -    MD0100PA00X+090639Y+082122X0200Y         S0      
327m2282            R2984 -2   M      A01X+116963Y+044784X0198Y0197R180 S1      
327m2282            R2703 -2          A01X+116071Y+045369X0198Y0197     S1      
317m2282            VIA   -    MD0100PA00X+094148Y+066865X0200Y         S0      
327m2282            R3105 -1          A01X+065578Y+168740X0198Y0197R180 S1      
317m2283            VIA   -    M      A01X+065114Y+170616X0200Y         S2      
017m2283            VIA   -    M      A18X+065114Y+170616X0260Y         S2      
017m2283                  -    MD0100PA00X+065114Y+170616                       
327m2283            R2724 -1          A01X+065322Y+171208X0198Y0197     S1      
327m2283            R3106 -2   M      A01X+065322Y+170818X0198Y0197R180 S1      
327m2283            U175  -6          A01X+064400Y+170973X0140Y0560     S1      
317m2284            VIA   -    M      A01X+065016Y+168719X0200Y         S2      
017m2284            VIA   -    M      A18X+065016Y+168719X0260Y         S2      
017m2284                  -    MD0100PA00X+065016Y+168719                       
327m2284            R3105 -2          A01X+065262Y+168740X0198Y0197R180 S1      
327m2284            R2705 -1   M      A01X+065280Y+169122X0198Y0197R090 S1      
327m2284            U175  -3          A01X+064400Y+169216X0140Y0560     S1      
317m2285            VIA   -    M      A01X+112409Y+168398X0200Y         S2      
017m2285            VIA   -    M      A18X+112409Y+168398X0260Y         S2      
017m2285                  -    MD0100PA00X+112409Y+168398                       
327m2285            R2676 -2          A18X+112893Y+168256X0198Y0197     S2      
327m2285            U176  -1          A01X+112889Y+168241X0140Y0560R270 S1      
327m2286            VIA   -           A01X+063333Y+169216X0300Y         S1      
327m2286            R2707 -2          A01X+065322Y+170240X0198Y0197R180 S1      
327m2286            U175  -1   M      A01X+063888Y+169216X0140Y0560     S1      
317SMB_BMC_SWB_EN   VIA   -    MD0100PA00X+087121Y+146654X0200Y         S0      
317SMB_BMC_SWB_EN   VIA   -    MD0100PA00X+112550Y+148729X0200Y         S0      
317SMB_BMC_SWB_EN   VIA   -    MD0100PA00X+113218Y+169004X0200Y         S0      
327SMB_BMC_SWB_EN   R2676 -1          A18X+113208Y+168256X0198Y0197     S2      
327SMB_BMC_SWB_EN   R2666 -1   M      A18X+113208Y+168606X0198Y0197     S2      
327SMB_BMC_SWB_EN   R2707 -1          A01X+065638Y+170240X0198Y0197R180 S1      
317SMB_BMC_SWB_EN   VIA   -    M      A01X+070842Y+065039X0200Y         S2      
017SMB_BMC_SWB_EN   VIA   -    M      A18X+070842Y+065039X0260Y         S2      
017SMB_BMC_SWB_EN         -    MD0100PA00X+070842Y+065039                       
317SMB_BMC_SWB_EN   VIA   -    MD0100PA00X+082279Y+077251X0200Y         S0      
317SMB_BMC_SWB_EN   VIA   -    MD0100PA00X+076053Y+067772X0200Y         S0      
327SMB_BMC_SWB_EN   U18   -A21        A01X+069733Y+048288X0160Y    R090 S1      
317SMB_BMC_SWB_EN   VIA   -    MD0100PA00X+069580Y+048442X0180Y    R090 S0      
317SMB_BMC_SWB_EN   VIA   -    MD0100PA00X+067100Y+169602X0200Y         S0      
327m2287            VIA   -    M      A01X+066065Y+170478X0300Y         S1      
327m2287            R2672 -1   M      A01X+066242Y+170818X0198Y0197     S1      
327m2287            U175  -7          A01X+064144Y+170973X0140Y0560     S1      
327m2287            R2669 -2   M      A01X+066242Y+171208X0198Y0197R180 S1      
327m2287            R2724 -2          A01X+065638Y+171208X0198Y0197     S1      
327m2288            VIA   -           A01X+063452Y+168655X0300Y         S1      
327m2288            R2667 -2          A01X+065680Y+169438X0198Y0197R090 S1      
327m2288            R2705 -2   M      A01X+065280Y+169438X0198Y0197R090 S1      
327m2288            R2671 -1   M      A01X+065322Y+169840X0198Y0197     S1      
327m2288            U175  -2   M      A01X+064144Y+169216X0140Y0560     S1      
317m2289            VIA   -    M      A01X+012518Y+171674X0200Y         S2      
017m2289            VIA   -    M      A18X+012518Y+171674X0260Y         S2      
017m2289                  -    MD0100PA00X+012518Y+171674                       
327m2289            R2992 -2          A01X+013269Y+171824X0198Y0197R180 S1      
327m2289            U200  -1          A01X+012016Y+171844X0140Y0560R090 S1      
327m2290            R2899 -2          A01X+010742Y+171245X0198Y0197R180 S1      
317m2290            VIA   -    M      A01X+010750Y+170745X0200Y         S2      
017m2290            VIA   -    M      A18X+010750Y+170745X0260Y         S2      
017m2290                  -    MD0100PA00X+010750Y+170745                       
327m2290            U194  -1          A01X+010253Y+170650X0140Y0560R270 S1      
317SMB_BMC_GPU_EN   VIA   -    MD0100PA00X+011896Y+163524X0200Y         S0      
317SMB_BMC_GPU_EN   VIA   -    MD0100PA00X+072729Y+042781X0180Y    R090 S0      
327SMB_BMC_GPU_EN   U18   -L4         A01X+072883Y+042934X0160Y    R090 S1      
317SMB_BMC_GPU_EN   VIA   -    M      A01X+027499Y+052205X0200Y    R090 S2      
017SMB_BMC_GPU_EN   VIA   -    M      A18X+027499Y+052205X0260Y    R090 S2      
017SMB_BMC_GPU_EN         -    MD0100PA00X+027499Y+052205                       
317SMB_BMC_GPU_EN   VIA   -    MD0100PA00X+013572Y+171567X0200Y         S0      
327SMB_BMC_GPU_EN   R2992 -1          A01X+013584Y+171824X0198Y0197R180 S1      
327SMB_BMC_GPU_EN   R2899 -1          A01X+011058Y+171245X0198Y0197R180 S1      
327SMB_BMC_GPU_EN   R4603 -1   M      A01X+011442Y+171245X0198Y0197     S1      
317m2291            VIA   -    M      A01X+009546Y+172524X0200Y         S2      
017m2291            VIA   -    M      A18X+009546Y+172524X0260Y         S2      
017m2291                  -    MD0100PA00X+009546Y+172524                       
327m2291            R3108 -2          A01X+008833Y+172433X0198Y0197     S1      
327m2291            R2987 -1   M      A01X+009226Y+172441X0198Y0197R270 S1      
327m2291            U200  -6          A01X+010258Y+172356X0140Y0560R090 S1      
317m2292            VIA   -    M      A01X+012902Y+172674X0200Y         S2      
017m2292            VIA   -    M      A18X+012902Y+172674X0260Y         S2      
017m2292                  -    MD0100PA00X+012902Y+172674                       
327m2292            U200  -3          A01X+012016Y+172356X0140Y0560R090 S1      
327m2292            R3107 -2          A01X+013969Y+172624X0198Y0197R180 S1      
327m2292            R2986 -1   M      A01X+013277Y+172632X0198Y0197R270 S1      
317m2293            VIA   -    M      A01X+009540Y+171974X0200Y         S2      
017m2293            VIA   -    M      A18X+009540Y+171974X0260Y         S2      
017m2293                  -    MD0100PA00X+009540Y+171974                       
327m2293            R2991 -1          A01X+008833Y+171633X0198Y0197R180 S1      
327m2293            U200  -7          A01X+010258Y+172100X0140Y0560R090 S1      
327m2293            R3522 -2   M      A01X+008833Y+172033X0198Y0197     S1      
327m2293            R2987 -2   M      A01X+009226Y+172126X0198Y0197R270 S1      
317m2294            VIA   -    M      A01X+012717Y+172170X0200Y         S2      
017m2294            VIA   -    M      A18X+012717Y+172170X0260Y         S2      
017m2294                  -    MD0100PA00X+012717Y+172170                       
327m2294            U200  -2          A01X+012016Y+172100X0140Y0560R090 S1      
327m2294            R2990 -1          A01X+013969Y+171824X0198Y0197     S1      
327m2294            R3521 -2   M      A01X+013969Y+172224X0198Y0197R180 S1      
327m2294            R2986 -2   M      A01X+013277Y+172317X0198Y0197R270 S1      
317m2295            VIA   -    M      A01X+012771Y+170017X0200Y         S2      
017m2295            VIA   -    M      A18X+012771Y+170017X0260Y         S2      
017m2295                  -    MD0100PA00X+012771Y+170017                       
327m2295            R3110 -2          A01X+013684Y+170101X0198Y0197R180 S1      
327m2295            R2894 -1   M      A01X+013242Y+170144X0198Y0197R090 S1      
327m2295            U194  -6          A01X+012011Y+170139X0140Y0560R270 S1      
327m2296            R3109 -2          A01X+008850Y+169851X0198Y0197     S1      
327m2296            R2893 -1   M      A01X+009250Y+169888X0198Y0197R090 S1      
317m2296            VIA   -    M      A01X+009610Y+169647X0200Y         S2      
017m2296            VIA   -    M      A18X+009610Y+169647X0260Y         S2      
017m2296                  -    MD0100PA00X+009610Y+169647                       
327m2296            U194  -3          A01X+010253Y+170139X0140Y0560R270 S1      
317m2297            VIA   -    M      A01X+012729Y+170567X0200Y         S2      
017m2297            VIA   -    M      A18X+012729Y+170567X0260Y         S2      
017m2297                  -    MD0100PA00X+012729Y+170567                       
327m2297            R2894 -2   M      A01X+013242Y+170459X0198Y0197R090 S1      
327m2297            R2898 -1          A01X+013674Y+170917X0198Y0197     S1      
327m2297            R3524 -2   M      A01X+013674Y+170517X0198Y0197R180 S1      
327m2297            U194  -7          A01X+012011Y+170395X0140Y0560R270 S1      
327m2298            U194  -2          A01X+010253Y+170395X0140Y0560R270 S1      
317m2298            VIA   -    M      A01X+009656Y+170551X0200Y         S2      
017m2298            VIA   -    M      A18X+009656Y+170551X0260Y         S2      
017m2298                  -    MD0100PA00X+009656Y+170551                       
327m2298            R2893 -2   M      A01X+009250Y+170202X0198Y0197R090 S1      
327m2298            R2897 -1          A01X+008850Y+170651X0198Y0197R180 S1      
327m2298            R3523 -2   M      A01X+008850Y+170251X0198Y0197     S1      
327m2299            J41   -B39        A01X+060101Y+006516X0150Y0570R180 S1      
317m2299            VIA   -    M      A01X+059607Y+010680X0200Y         S2      
017m2299            VIA   -    M      A18X+059607Y+010680X0260Y         S2      
017m2299                  -    MD0100PA00X+059607Y+010680                       
327m2299            R6025 -2          A01X+067280Y+037179X0198Y0197R270 S1      
317m2299            VIA   -    MD0100PA00X+067280Y+036936X0200Y         S0      
327m2300            J41   -B37        A01X+060574Y+006516X0150Y0570R180 S1      
317m2300            VIA   -    M      A01X+059728Y+009492X0200Y         S2      
017m2300            VIA   -    M      A18X+059728Y+009492X0260Y         S2      
017m2300                  -    MD0100PA00X+059728Y+009492                       
327m2300            R6015 -2          A01X+068080Y+037179X0198Y0197R270 S1      
317m2300            VIA   -    MD0100PA00X+068080Y+036936X0200Y         S0      
327m2301            J41   -B32        A01X+061755Y+006516X0150Y0570R180 S1      
317m2301            VIA   -    M      A01X+061428Y+009587X0200Y         S2      
017m2301            VIA   -    M      A18X+061428Y+009587X0260Y         S2      
017m2301                  -    MD0100PA00X+061428Y+009587                       
317m2301            VIA   -    MD0100PA00X+067550Y+039086X0200Y         S0      
327m2301            R6011 -2          A01X+067550Y+039329X0198Y0197R270 S1      
327m2302            J41   -B34        A01X+061282Y+006516X0150Y0570R180 S1      
327m2302            R6012 -2          A01X+067950Y+039329X0198Y0197R270 S1      
317m2302            VIA   -    MD0100PA00X+067950Y+039086X0200Y         S0      
317m2302            VIA   -    M      A01X+061001Y+010075X0200Y         S2      
017m2302            VIA   -    M      A18X+061001Y+010075X0260Y         S2      
017m2302                  -    MD0100PA00X+061001Y+010075                       
327m2303            J41   -B29        A01X+062463Y+006516X0150Y0570R180 S1      
317m2303            VIA   -    M      A01X+062621Y+010086X0200Y         S2      
017m2303            VIA   -    M      A18X+062621Y+010086X0260Y         S2      
017m2303                  -    MD0100PA00X+062621Y+010086                       
327m2303            R6008 -2          A01X+068350Y+039329X0198Y0197R270 S1      
317m2303            VIA   -    MD0100PA00X+068350Y+039086X0200Y         S0      
327m2304            J41   -B36        A01X+060810Y+006516X0150Y0570R180 S1      
327m2304            VIA   -    M      A01X+060229Y+008507X0300Y         S1      
327m2304            R6014 -2          A01X+060228Y+009010X0198Y0197R270 S1      
327m2305            J41   -B31        A01X+061991Y+006516X0150Y0570R180 S1      
327m2305            VIA   -    M      A01X+061804Y+008458X0300Y         S1      
327m2305            R6010 -2          A01X+061818Y+009010X0198Y0197R270 S1      
327m2306            J41   -B35        A01X+061046Y+006516X0150Y0570R180 S1      
317m2306            VIA   -    M      A01X+060618Y+009587X0200Y         S2      
017m2306            VIA   -    M      A18X+060618Y+009587X0260Y         S2      
017m2306                  -    MD0100PA00X+060618Y+009587                       
327m2306            R6013 -2          A01X+067680Y+037179X0198Y0197R270 S1      
317m2306            VIA   -    MD0100PA00X+067680Y+036936X0200Y         S0      
327m2307            J41   -B30        A01X+062227Y+006516X0150Y0570R180 S1      
327m2307            R6009 -2          A01X+068480Y+037179X0198Y0197R270 S1      
317m2307            VIA   -    MD0100PA00X+068480Y+036936X0200Y         S0      
317m2307            VIA   -    M      A01X+062216Y+009595X0200Y         S2      
017m2307            VIA   -    M      A18X+062216Y+009595X0260Y         S2      
017m2307                  -    MD0100PA00X+062216Y+009595                       
317m2308            VIA   -    M      A01X+067600Y+037810X0200Y         S2      
017m2308            VIA   -    M      A18X+067600Y+037810X0260Y         S2      
017m2308                  -    MD0100PA00X+067600Y+037810                       
327m2308            R6021 -2          A18X+067550Y+038479X0198Y0197R090 S2      
327m2308            R6013 -1          A01X+067680Y+037494X0198Y0197R270 S1      
327m2308            U18   -D18        A01X+070678Y+047344X0160Y    R090 S1      
317m2308            VIA   -    MD0100PA00X+070524Y+047497X0180Y    R090 S0      
317m2309            VIA   -    M      A01X+068520Y+037782X0200Y         S2      
017m2309            VIA   -    M      A18X+068520Y+037782X0260Y         S2      
017m2309                  -    MD0100PA00X+068520Y+037782                       
327m2309            R6017 -2          A18X+068350Y+038479X0198Y0197R090 S2      
327m2309            R6009 -1          A01X+068480Y+037494X0198Y0197R270 S1      
327m2309            U18   -D6         A01X+070678Y+043564X0160Y    R090 S1      
317m2309            VIA   -    MD0100PA00X+070524Y+043411X0180Y    R090 S0      
327SCM_VDD_RTC      J41   -B41        A01X+059629Y+006516X0150Y0570R180 S1      
327SCM_VDD_RTC      VIA   -    M      A01X+058639Y+007849X0300Y         S1      
327SCM_VDD_RTC      R364  -2   M      A01X+058639Y+009010X0198Y0197R270 S1      
327SCM_VDD_RTC      C6000 -1          A01X+058219Y+009010X0198Y0197R090 S1      
327m2310            J41   -A49        A01X+056042Y+005354X0150Y0570R180 S1      
327m2310            R6032 -2          A18X+056020Y+005261X0198Y0197R090 S2      
317m2310            VIA   -    M      A01X+056172Y+004102X0200Y         S2      
017m2310            VIA   -    M      A18X+056172Y+004102X0260Y         S2      
017m2310                  -    MD0100PA00X+056172Y+004102                       
327RST_SWB_BIC_N    VIA   -    M      A01X+072190Y+163662X0300Y         S1      
327RST_SWB_BIC_N    U181  -5          A01X+072190Y+164333X0160Y0540     S1      
327RST_SWB_BIC_N    R2848 -1          A01X+072472Y+163010X0198Y0197R270 S1      
327PU_U181_INT      VIA   -    M      A01X+069795Y+163410X0300Y         S1      
327PU_U181_INT      U181  -1          A01X+071127Y+164333X0240Y0540     S1      
327PU_U181_INT      R2923 -2          A01X+069603Y+163085X0198Y0197R090 S1      
327m2311            VIA   -    M      A01X+071515Y+163426X0300Y         S1      
327m2311            U181  -3          A01X+071678Y+164333X0160Y0540     S1      
327m2311            R2922 -2          A01X+071515Y+163066X0198Y0197R090 S1      
327m2312            R3710 -2          A01X+101434Y+048416X0198Y0197     S1      
327m2312            U39   -3          A01X+102904Y+047828X0120Y0630R270 S1      
327m2312            VIA   -    M      A01X+101941Y+048558X0300Y         S1      
327m2313            U36   -3          A01X+111861Y+047828X0120Y0630R270 S1      
327m2313            VIA   -    M      A01X+110700Y+048136X0300Y         S1      
327m2313            R2268 -2          A01X+110202Y+047936X0198Y0197     S1      
327m2314            U36   -21         A01X+114066Y+047572X0120Y0630R270 S1      
327m2314            VIA   -    M      A01X+115284Y+048237X0300Y         S1      
327m2314            R316  -2          A01X+116963Y+048169X0198Y0197R180 S1      
327m2314            R317  -1   M      A01X+115756Y+048169X0198Y0197     S1      
327m2315            VIA   -    M      A01X+111104Y+048577X0300Y         S1      
327m2315            U36   -2          A01X+111861Y+048084X0120Y0630R270 S1      
327m2315            R319  -1   M      A01X+110202Y+048439X0198Y0197R180 S1      
327m2315            R318  -2          A01X+109351Y+048964X0198Y0197     S1      
327m2316            R320  -2          A01X+109351Y+049464X0198Y0197     S1      
327m2316            U36   -1          A01X+111861Y+048339X0120Y0630R270 S1      
327m2316            VIA   -    M      A01X+110704Y+048939X0300Y         S1      
327m2316            R587  -1   M      A01X+110202Y+048939X0198Y0197R180 S1      
327m2317            U39   -21         A01X+105108Y+047572X0120Y0630R270 S1      
317m2317            VIA   -    M      A01X+106217Y+047966X0200Y         S2      
017m2317            VIA   -    M      A18X+106217Y+047966X0260Y         S2      
017m2317                  -    MD0100PA00X+106217Y+047966                       
327m2317            R3704 -1   M      A01X+106569Y+047966X0198Y0197     S1      
327m2317            R3703 -2          A01X+106572Y+047552X0198Y0197R180 S1      
327m2318            U39   -2          A01X+102904Y+048084X0120Y0630R270 S1      
327m2318            VIA   -    M      A01X+102276Y+048966X0300Y         S1      
327m2318            R3707 -1   M      A01X+101434Y+048864X0198Y0197R180 S1      
327m2318            R3706 -2          A01X+100391Y+049418X0198Y0197     S1      
327m2319            U39   -1          A01X+102904Y+048339X0120Y0630R270 S1      
327m2319            VIA   -    M      A01X+101926Y+049366X0300Y         S1      
327m2319            R3709 -1   M      A01X+101434Y+049366X0198Y0197R180 S1      
327m2319            R3708 -2          A01X+100391Y+049968X0198Y0197     S1      
327m2320            U247  -22         A01X+005235Y+053510X0100Y0220     S1      
327m2320            VIA   -    M      A01X+005440Y+054203X0300Y    R180 S1      
327m2320            R4080 -2          A01X+005836Y+054668X0198Y0197R270 S1      
317m2321            VIA   -    MD0080PA00X+139402Y+087962X0160Y    R180 S0      
327m2321            U25   -C44        A01X+139586Y+088067X0177Y    R180 S1      
327m2321            C2077 -1          A01X+063015Y+008006X0120Y0150R270 S1      
317m2321            VIA   -    MD0100PA00X+085719Y+034221X0200Y         S0      
317m2322            VIA   -    MD0080PA00X+139032Y+087962X0160Y    R180 S0      
327m2322            U25   -C45        A01X+139216Y+088067X0177Y    R180 S1      
327m2322            C2078 -1          A01X+063329Y+008006X0120Y0150R270 S1      
317m2322            VIA   -    MD0100PA00X+086059Y+034221X0200Y         S0      
327I3C_SCM_3_SDA    J41   -OA12       A01X+072623Y+005354X0150Y0570R180 S1      
327I3C_SCM_3_SDA    R6007 -1          A18X+071995Y+005197X0198Y0197R270 S2      
317I3C_SCM_3_SDA    VIA   -    M      A01X+071982Y+004586X0200Y         S2      
017I3C_SCM_3_SDA    VIA   -    M      A18X+071982Y+004586X0260Y         S2      
017I3C_SCM_3_SDA          -    MD0100PA00X+071982Y+004586                       
327I3C_SCM_3_SCL    J41   -OA11       A01X+072859Y+005354X0150Y0570R180 S1      
327I3C_SCM_3_SCL    R6006 -1          A18X+072464Y+005197X0198Y0197R270 S2      
317I3C_SCM_3_SCL    VIA   -    M      A01X+072462Y+004006X0200Y         S2      
017I3C_SCM_3_SCL    VIA   -    M      A18X+072462Y+004006X0260Y         S2      
017I3C_SCM_3_SCL          -    MD0100PA00X+072462Y+004006                       
327I3C_SCM_2_SDA    J41   -OA10       A01X+073095Y+005354X0150Y0570R180 S1      
327I3C_SCM_2_SDA    R6005 -1          A18X+072929Y+005197X0198Y0197R270 S2      
317I3C_SCM_2_SDA    VIA   -    M      A01X+072872Y+004356X0200Y         S2      
017I3C_SCM_2_SDA    VIA   -    M      A18X+072872Y+004356X0260Y         S2      
017I3C_SCM_2_SDA          -    MD0100PA00X+072872Y+004356                       
327I3C_SCM_2_SCL    J41   -OA9        A01X+073332Y+005354X0150Y0570R180 S1      
327I3C_SCM_2_SCL    R6004 -1          A18X+073364Y+005197X0198Y0197R270 S2      
317I3C_SCM_2_SCL    VIA   -    M      A01X+073332Y+004086X0200Y         S2      
017I3C_SCM_2_SCL    VIA   -    M      A18X+073332Y+004086X0260Y         S2      
017I3C_SCM_2_SCL          -    MD0100PA00X+073332Y+004086                       
327I3C_SCM_1_SDA    J41   -OA8        A01X+073568Y+005354X0150Y0570R180 S1      
327I3C_SCM_1_SDA    R6003 -1          A18X+073760Y+005197X0198Y0197R270 S2      
317I3C_SCM_1_SDA    VIA   -    M      A01X+073662Y+004526X0200Y         S2      
017I3C_SCM_1_SDA    VIA   -    M      A18X+073662Y+004526X0260Y         S2      
017I3C_SCM_1_SDA          -    MD0100PA00X+073662Y+004526                       
327I3C_SCM_1_SCL    J41   -OA7        A01X+073804Y+005354X0150Y0570R180 S1      
327I3C_SCM_1_SCL    R6002 -1          A18X+074138Y+005197X0198Y0197R270 S2      
317I3C_SCM_1_SCL    VIA   -    M      A01X+074010Y+004116X0200Y         S2      
017I3C_SCM_1_SCL    VIA   -    M      A18X+074010Y+004116X0260Y         S2      
017I3C_SCM_1_SCL          -    MD0100PA00X+074010Y+004116                       
327I3C_SCM_0_SDA    J41   -OA6        A01X+074040Y+005354X0150Y0570R180 S1      
327I3C_SCM_0_SDA    R6001 -1          A18X+074548Y+005197X0198Y0197R270 S2      
317I3C_SCM_0_SDA    VIA   -    M      A01X+074590Y+004036X0200Y         S2      
017I3C_SCM_0_SDA    VIA   -    M      A18X+074590Y+004036X0260Y         S2      
017I3C_SCM_0_SDA          -    MD0100PA00X+074590Y+004036                       
327I3C_SCM_0_SCL    J41   -OA5        A01X+074276Y+005354X0150Y0570R180 S1      
327I3C_SCM_0_SCL    R6000 -1          A18X+074948Y+005197X0198Y0197R270 S2      
317I3C_SCM_0_SCL    VIA   -    M      A01X+074610Y+004626X0200Y         S2      
017I3C_SCM_0_SCL    VIA   -    M      A18X+074610Y+004626X0260Y         S2      
017I3C_SCM_0_SCL          -    MD0100PA00X+074610Y+004626                       
327m2323            R3111 -2          A18X+114367Y+167394X0198Y0197R180 S2      
317m2323            VIA   -    M      A01X+115211Y+167252X0200Y         S2      
017m2323            VIA   -    M      A18X+115211Y+167252X0260Y         S2      
017m2323                  -    MD0100PA00X+115211Y+167252                       
327m2323            U176  -6          A01X+114647Y+167729X0140Y0560R270 S1      
327m2323            R2706 -1   M      A18X+114795Y+167583X0198Y0197R270 S2      
317m2324            VIA   -    M      A01X+095189Y+080450X0200Y         S2      
017m2324            VIA   -    M      A18X+095189Y+080450X0260Y         S2      
017m2324                  -    MD0100PA00X+095189Y+080450                       
327m2324            R3112 -2          A18X+067829Y+005526X0198Y0197R270 S2      
317m2324            VIA   -    MD0100PA00X+068337Y+005816X0200Y         S0      
317m2324            VIA   -    MD0100PA00X+084046Y+033537X0200Y         S0      
327m2324            R2725 -1          A18X+112950Y+167542X0198Y0197R270 S2      
327m2324            U176  -3          A01X+112889Y+167729X0140Y0560R270 S1      
317m2324            VIA   -    MD0100PA00X+113321Y+167538X0200Y         S0      
317m2325            VIA   -    M      A01X+115221Y+168237X0200Y         S2      
017m2325            VIA   -    M      A18X+115221Y+168237X0260Y         S2      
017m2325                  -    MD0100PA00X+115221Y+168237                       
327m2325            R2674 -1          A18X+114308Y+167900X0198Y0197     S2      
327m2325            R2706 -2   M      A18X+114795Y+167898X0198Y0197R270 S2      
327m2325            U176  -7          A01X+114647Y+167985X0140Y0560R270 S1      
327m2325            R2668 -2   M      A18X+115200Y+167908X0198Y0197R270 S2      
317m2326            VIA   -    M      A01X+112261Y+167798X0200Y         S2      
017m2326            VIA   -    M      A18X+112261Y+167798X0260Y         S2      
017m2326                  -    MD0100PA00X+112261Y+167798                       
327m2326            U176  -2          A01X+112889Y+167985X0140Y0560R270 S1      
327m2326            R2675 -1          A18X+113342Y+167900X0198Y0197R180 S2      
327m2326            R2670 -2   M      A18X+112600Y+167858X0198Y0197R270 S2      
327m2326            R2725 -2   M      A18X+112950Y+167858X0198Y0197R270 S2      
327m2327            R1522 -1          A01X+060020Y+013227X0198Y0197     S1      
327m2327            R1180 -1   M      A01X+060019Y+013641X0198Y0197     S1      
327m2327            R3264 -1   M      A01X+060019Y+014164X0198Y0197     S1      
327m2327            U235  -5          A01X+058942Y+014923X0240Y0460R090 S1      
327m2327            VIA   -    M      A01X+059539Y+014464X0300Y         S1      
327m2328            R1500 -1          A01X+162237Y+027852X0198Y0197     S1      
327m2328            R1135 -1   M      A01X+162237Y+028273X0198Y0197     S1      
327m2328            R3263 -1   M      A01X+162233Y+028674X0198Y0197     S1      
327m2328            U236  -5          A01X+161166Y+029533X0240Y0460R090 S1      
327m2328            VIA   -    M      A01X+161753Y+028974X0300Y    R270 S1      
327m2329            J41   -A46        A01X+056751Y+005354X0150Y0570R180 S1      
317m2329            VIA   -    M      A01X+056677Y+004113X0200Y         S2      
017m2329            VIA   -    M      A18X+056677Y+004113X0260Y         S2      
017m2329                  -    MD0100PA00X+056677Y+004113                       
327m2329            R6033 -2          A18X+056820Y+005262X0198Y0197R090 S2      
327m2330            R3517 -2          A01X+072563Y+167718X0198Y0197R270 S1      
327m2330            VIA   -    M      A01X+072537Y+167323X0300Y         S1      
327m2330            U181  -18         A01X+072702Y+166636X0160Y0540     S1      
327m2331            R3518 -2          A01X+072962Y+167719X0198Y0197R270 S1      
327m2331            VIA   -    M      A01X+073059Y+167292X0300Y         S1      
327m2331            U181  -17         A01X+072958Y+166636X0160Y0540     S1      
327m2332            R3326 -2          A01X+014142Y+052200X0198Y0197R180 S1      
327m2332            VIA   -    M      A01X+013662Y+052200X0300Y    R180 S1      
327m2332            U248  -1          A01X+013081Y+052437X0400Y0150R180 S1      
327GPU_BASE_ID1_R   VIA   -    M      A01X+073402Y+167682X0300Y         S1      
327GPU_BASE_ID1_R   U181  -16         A01X+073214Y+166636X0160Y0540     S1      
327GPU_BASE_ID1_R   R3499 -2          A01X+073747Y+168053X0198Y0197R270 S1      
327GPU_BASE_ID0_R   R3516 -2          A01X+074133Y+167698X0198Y0197R270 S1      
327GPU_BASE_ID0_R   VIA   -    M      A01X+073853Y+167439X0300Y         S1      
327GPU_BASE_ID0_R   U181  -15         A01X+073469Y+166636X0160Y0540     S1      
327FG_SS_EN         U247  -23         A01X+005038Y+053510X0100Y0220     S1      
327FG_SS_EN         VIA   -    M      A01X+004904Y+054203X0300Y    R180 S1      
327FG_SS_EN         R4078 -2          A01X+005330Y+054672X0198Y0197R270 S1      
327FG_SS_EN         R4079 -1   M      A01X+004863Y+054668X0198Y0197R090 S1      
327m2333            Y8003 -3          A01X+002689Y+052869X0480Y0560     S1      
327m2333            U247  -2          A01X+004595Y+053067X0100Y0220R270 S1      
317m2333            VIA   -    M      A01X+003997Y+052671X0200Y    R180 S2      
017m2333            VIA   -    M      A18X+003997Y+052671X0260Y    R180 S2      
017m2333                  -    MD0100PA00X+003997Y+052671                       
327m2333            C94   -1   M      A01X+003277Y+052894X0198Y0197R270 S1      
327m2334            Y8003 -1          A01X+002059Y+053736X0480Y0560     S1      
317m2334            VIA   -    M      A01X+003056Y+053306X0200Y    R180 S2      
017m2334            VIA   -    M      A18X+003056Y+053306X0260Y    R180 S2      
017m2334                  -    MD0100PA00X+003056Y+053306                       
327m2334            R4501 -1          A01X+003637Y+053122X0198Y0197R090 S1      
327m2334            C71   -1   M      A01X+003285Y+053446X0198Y0197R090 S1      
327m2335            U247  -1          A01X+004595Y+053263X0100Y0220R270 S1      
327m2335            VIA   -    M      A01X+004101Y+053410X0300Y    R180 S1      
327m2335            R4501 -2          A01X+003637Y+053437X0198Y0197R090 S1      
327m2336            U247  -4          A01X+004595Y+052673X0100Y0220R270 S1      
327m2336            VIA   -    M      A01X+003916Y+051991X0300Y    R180 S1      
327m2336            R4081 -2   M      A01X+003439Y+051702X0198Y0197     S1      
327m2336            R4082 -1          A01X+002191Y+051695X0198Y0197R180 S1      
327m2337            U247  -19         A01X+005825Y+053510X0100Y0220     S1      
327m2337            VIA   -    M      A01X+005985Y+054199X0300Y    R180 S1      
327m2337            R4076 -2          A01X+006315Y+054668X0198Y0197R270 S1      
317m2338            VIA   -    M      A01X+067800Y+048286X0200Y         S2      
017m2338            VIA   -    M      A18X+067800Y+048286X0260Y         S2      
017m2338                  -    MD0100PA00X+067800Y+048286                       
327m2338            R6030 -2          A01X+067558Y+048286X0198Y0197     S1      
327m2338            U18   -C20        A01X+070363Y+047974X0160Y    R090 S1      
317m2338            VIA   -    MD0100PA00X+070210Y+048127X0180Y    R090 S0      
327m2339            R4514 -1   M      A01X+014142Y+052700X0198Y0197     S1      
327m2339            R3327 -2          A01X+014142Y+053500X0198Y0197R180 S1      
327m2339            R3322 -2   M      A01X+014142Y+053100X0198Y0197R180 S1      
327m2339            VIA   -    M      A01X+013662Y+052700X0300Y    R180 S1      
327m2339            U248  -2          A01X+013081Y+052692X0400Y0150R180 S1      
327m2340            R6030 -1          A01X+067242Y+048286X0198Y0197     S1      
317m2340            VIA   -    MD0100PA00X+067000Y+048286X0200Y         S0      
327m2340            R3327 -1          A01X+014457Y+053500X0198Y0197R180 S1      
317m2340            VIA   -    M      A01X+022969Y+052245X0200Y         S2      
017m2340            VIA   -    M      A18X+022969Y+052245X0260Y         S2      
017m2340                  -    MD0100PA00X+022969Y+052245                       
317m2341            VIA   -    M      A01X+067800Y+047786X0200Y         S2      
017m2341            VIA   -    M      A18X+067800Y+047786X0260Y         S2      
017m2341                  -    MD0100PA00X+067800Y+047786                       
327m2341            R6029 -2          A01X+067558Y+047786X0198Y0197     S1      
327m2341            U18   -C19        A01X+070363Y+047659X0160Y    R090 S1      
317m2341            VIA   -    MD0100PA00X+070210Y+047812X0180Y    R090 S0      
327m2342            U247  -12         A01X+005825Y+052033X0100Y0220     S1      
327m2342            VIA   -    M      A01X+005825Y+051498X0300Y    R180 S1      
327m2342            R4075 -2          A01X+005840Y+050766X0198Y0197R090 S1      
317m2343            VIA   -    MD0100PA00X+067000Y+047786X0200Y         S0      
327m2343            R6029 -1          A01X+067242Y+047786X0198Y0197     S1      
317m2343            VIA   -    M      A01X+021769Y+052245X0200Y         S2      
017m2343            VIA   -    M      A18X+021769Y+052245X0260Y         S2      
017m2343                  -    MD0100PA00X+021769Y+052245                       
327m2343            R4521 -2   M      A01X+006444Y+050439X0198Y0197R270 S1      
327m2343            R4075 -1          A01X+005840Y+050451X0198Y0197R090 S1      
327m2344            U247  -17         A01X+006072Y+053067X0100Y0220R270 S1      
327m2344            R3337 -1          A01X+007206Y+053931X0198Y0197     S1      
327m2345            U247  -18         A01X+006072Y+053263X0100Y0220R270 S1      
327m2345            R3338 -1          A01X+007206Y+054321X0198Y0197     S1      
317m2346            VIA   -    MD0080PA00X+152537Y+087643X0160Y    R180 S0      
327m2346            U25   -B9         A01X+152354Y+087748X0177Y    R180 S1      
327m2346            R9275 -1          A18X+149196Y+084616X0198Y0197R090 S2      
317m2347            VIA   -    MD0080PA00X+152352Y+087962X0160Y    R180 S0      
327m2347            U25   -C9         A01X+152168Y+088067X0177Y    R180 S1      
327m2347            R9276 -1          A18X+148756Y+084616X0198Y0197R090 S2      
327m2348            R9275 -2          A18X+149196Y+084301X0198Y0197R090 S2      
317m2348            VIA   -    MD0100PA00X+175524Y+002648X0200Y         S0      
327m2348            J38   -OA12       A01X+175576Y+003276X0150Y0570R180 S1      
327m2349            R9276 -2          A18X+148756Y+084301X0198Y0197R090 S2      
317m2349            VIA   -    MD0100PA00X+175864Y+002648X0200Y         S0      
327m2349            J38   -OA11       A01X+175812Y+003276X0150Y0570R180 S1      
317m2350            VIA   -    MD0080PA00X+151427Y+087643X0160Y    R180 S0      
327m2350            U25   -B12        A01X+151243Y+087748X0177Y    R180 S1      
327m2350            R9273 -1          A18X+147436Y+084616X0198Y0197R090 S2      
317m2351            VIA   -    MD0080PA00X+151242Y+087962X0160Y    R180 S0      
327m2351            U25   -C12        A01X+151058Y+088067X0177Y    R180 S1      
327m2351            R9274 -1          A18X+146996Y+084616X0198Y0197R090 S2      
327m2352            R9273 -2          A18X+147436Y+084301X0198Y0197R090 S2      
317m2352            VIA   -    MD0100PA00X+175524Y+005065X0200Y    R180 S0      
327m2352            J38   -OB12       A01X+175576Y+004437X0150Y0570R180 S1      
327m2353            R9274 -2          A18X+146996Y+084301X0198Y0197R090 S2      
317m2353            VIA   -    MD0100PA00X+175864Y+005065X0200Y    R180 S0      
327m2353            J38   -OB11       A01X+175812Y+004437X0150Y0570R180 S1      
317m2354            VIA   -    MD0080PA00X+151982Y+087324X0160Y    R180 S0      
327m2354            U25   -A10        A01X+151798Y+087429X0177Y    R180 S1      
327m2354            R8565 -1          A18X+148316Y+084616X0198Y0197R090 S2      
317m2355            VIA   -    MD0080PA00X+151612Y+087324X0160Y    R180 S0      
327m2355            U25   -A11        A01X+151428Y+087429X0177Y    R180 S1      
327m2355            R8566 -1          A18X+147876Y+084616X0198Y0197R090 S2      
327m2356            R8565 -2          A18X+148316Y+084301X0198Y0197R090 S2      
317m2356            VIA   -    MD0100PA00X+170018Y+002650X0200Y         S0      
327m2356            J38   -A15        A01X+170066Y+003276X0150Y0570R180 S1      
327m2357            R8566 -2          A18X+147876Y+084301X0198Y0197R090 S2      
317m2357            VIA   -    MD0100PA00X+170358Y+002650X0200Y         S0      
327m2357            J38   -A14        A01X+170302Y+003276X0150Y0570R180 S1      
317m2358            VIA   -    MD0080PA00X+153648Y+087643X0160Y    R180 S0      
327m2358            U25   -B6         A01X+153464Y+087748X0177Y    R180 S1      
327m2358            R8563 -1          A18X+150076Y+084616X0198Y0197R090 S2      
317m2359            VIA   -    MD0080PA00X+153462Y+087962X0160Y    R180 S0      
327m2359            U25   -C6         A01X+153279Y+088067X0177Y    R180 S1      
327m2359            R8564 -1          A18X+149636Y+084616X0198Y0197R090 S2      
327m2360            R8563 -2          A18X+150076Y+084301X0198Y0197R090 S2      
317m2360            VIA   -    MD0100PA00X+170014Y+005065X0200Y    R180 S0      
327m2360            J38   -B15        A01X+170066Y+004437X0150Y0570R180 S1      
327m2361            R8564 -2          A18X+149636Y+084301X0198Y0197R090 S2      
317m2361            VIA   -    MD0100PA00X+170354Y+005065X0200Y    R180 S0      
327m2361            J38   -B14        A01X+170302Y+004437X0150Y0570R180 S1      
317m2362            VIA   -    MD0080PA00X+152722Y+087324X0160Y    R180 S0      
327m2362            U25   -A8         A01X+152539Y+087429X0177Y    R180 S1      
327m2362            R4535 -1          A18X+146556Y+084616X0198Y0197R090 S2      
317m2363            VIA   -    MD0080PA00X+153092Y+087324X0160Y    R180 S0      
327m2363            U25   -A7         A01X+152909Y+087429X0177Y    R180 S1      
327m2363            R4536 -1          A18X+146116Y+084616X0198Y0197R090 S2      
327m2364            U247  -13         A01X+006072Y+052279X0100Y0220R270 S1      
327m2364            R3335 -1          A01X+007206Y+052161X0198Y0197     S1      
327m2365            U247  -14         A01X+006072Y+052476X0100Y0220R270 S1      
327m2365            R3336 -1          A01X+007206Y+052551X0198Y0197     S1      
327PU_TEST          VIA   -    M      A01X+014498Y+167186X0300Y    R180 S1      
327PU_TEST          R3291 -1          A01X+014978Y+167009X0198Y0197     S1      
327PU_TEST          U237  -5          A01X+013977Y+167130X0070Y0240R090 S1      
327m2366            C2073 -1          A18X+017486Y+162871X0120Y0150     S2      
317m2366            VIA   -    MD0100PA18X+030726Y+164715X0200Y         S0      
317m2366            J112  -R7   D0142PA01X+027815Y+165390X0302Y    R180 S3      
317m2367            VIA   -    MD0100PA18X+029732Y+165377X0200Y         S0      
327m2367            C2075 -1          A18X+020473Y+163815X0120Y0150     S2      
317m2367            J112  -R8   D0142PA01X+028602Y+165311X0302Y    R180 S3      
327m2368            C2074 -1          A18X+017486Y+162541X0120Y0150     S2      
317m2368            VIA   -    MD0100PA18X+030726Y+164375X0200Y         S0      
317m2368            J112  -S7   D0142PA01X+027815Y+164917X0302Y    R180 S3      
317m2369            VIA   -    MD0100PA18X+029732Y+165717X0200Y         S0      
327m2369            C2076 -1          A18X+020473Y+164145X0120Y0150     S2      
317m2369            J112  -Q8   D0142PA01X+028602Y+165783X0302Y    R180 S3      
327m2370            J59   -13         A01X+069728Y+020984X0110Y0630R270 S1      
327m2370            C1098 -1          A01X+070969Y+020892X0120Y0150     S1      
327m2371            J59   -25         A01X+069728Y+019803X0110Y0630R270 S1      
327m2371            C1100 -1          A01X+070969Y+019709X0120Y0150     S1      
327m2372            J59   -37         A01X+069728Y+018622X0110Y0630R270 S1      
327m2372            C9102 -1          A01X+070969Y+018559X0120Y0150     S1      
327m2373            J59   -49         A01X+069728Y+017441X0110Y0630R270 S1      
327m2373            C9104 -1          A01X+070969Y+017359X0120Y0150     S1      
327m2374            J59   -11         A01X+069728Y+021181X0110Y0630R270 S1      
327m2374            C1099 -1          A01X+070969Y+021252X0120Y0150     S1      
327m2375            J59   -23         A01X+069728Y+020000X0110Y0630R270 S1      
327m2375            C1101 -1          A01X+070969Y+020069X0120Y0150     S1      
327m2376            J59   -35         A01X+069728Y+018819X0110Y0630R270 S1      
327m2376            C9103 -1          A01X+070969Y+018919X0120Y0150     S1      
327m2377            J59   -47         A01X+069728Y+017638X0110Y0630R270 S1      
327m2377            C9105 -1          A01X+070969Y+017719X0120Y0150     S1      
327m2378            J90   -B27        A01X+093150Y+022900X0150Y0500R090 S1      
327m2378            C1989 -1          A01X+094050Y+022964X0120Y0150     S1      
327m2379            C1991 -1          A01X+094720Y+021895X0120Y0150     S1      
327m2379            J90   -B23        A01X+093150Y+021955X0150Y0500R090 S1      
327m2380            C1993 -1          A01X+094050Y+021190X0120Y0150     S1      
327m2380            J90   -B20        A01X+093150Y+021246X0150Y0500R090 S1      
327m2381            C1995 -1          A01X+094050Y+020478X0120Y0150     S1      
327m2381            J90   -B17        A01X+093150Y+020537X0150Y0500R090 S1      
327m2382            J90   -B26        A01X+093150Y+022663X0150Y0500R090 S1      
327m2382            C1990 -1          A01X+094050Y+022604X0120Y0150     S1      
327m2383            C1992 -1          A01X+094720Y+022255X0120Y0150     S1      
327m2383            J90   -B24        A01X+093150Y+022191X0150Y0500R090 S1      
327m2384            C1994 -1          A01X+094050Y+021550X0120Y0150     S1      
327m2384            J90   -B21        A01X+093150Y+021482X0150Y0500R090 S1      
327m2385            C1996 -1          A01X+094050Y+020838X0120Y0150     S1      
327m2385            J90   -B18        A01X+093150Y+020774X0150Y0500R090 S1      
327m2386            C1870 -1          A01X+011392Y+165775X0180Y0200     S1      
327m2386            U237  -24         A01X+012993Y+166658X0070Y0240R270 S1      
327m2387            C1871 -1          A01X+011392Y+166272X0180Y0200     S1      
327m2387            U237  -23         A01X+012993Y+166815X0070Y0240R270 S1      
327m2388            C1868 -1          A01X+015256Y+167938X0180Y0200R180 S1      
327m2388            U237  -9          A01X+013977Y+167760X0070Y0240R090 S1      
327m2389            C1869 -1          A01X+015256Y+167424X0180Y0200R180 S1      
327m2389            U237  -8          A01X+013977Y+167602X0070Y0240R090 S1      
327m2390            J41   -A17        A01X+066641Y+005354X0150Y0570R180 S1      
327m2390            C2077 -2          A01X+063015Y+007796X0120Y0150R270 S1      
327m2391            J41   -A18        A01X+066404Y+005354X0150Y0570R180 S1      
327m2391            C2078 -2          A01X+063329Y+007796X0120Y0150R270 S1      
327FM_P2E_SWB       U237  -12         A01X+013643Y+168094X0070Y0240R180 S1      
327FM_P2E_SWB       VIA   -    M      A01X+013743Y+168634X0300Y    R180 S1      
327FM_P2E_SWB       R3287 -1   M      A01X+013935Y+169051X0198Y0197R090 S1      
327FM_P2E_SWB       R3286 -2          A01X+014725Y+169051X0198Y0197R270 S1      
327FM_P2E_SWB       R3285 -1   M      A01X+014335Y+169051X0198Y0197R090 S1      
327FM_P2E_SWA       U237  -29         A01X+013643Y+166323X0070Y0240     S1      
327FM_P2E_SWA       VIA   -    M      A01X+014425Y+165584X0300Y    R180 S1      
327FM_P2E_SWA       R3288 -1   M      A01X+014425Y+165216X0198Y0197R270 S1      
327FM_P2E_SWA       R3289 -2          A01X+013635Y+165216X0198Y0197R090 S1      
327FM_P2E_SWA       R3290 -1   M      A01X+014035Y+165216X0198Y0197R270 S1      
327FM_P2E_MODE      U237  -30         A01X+013800Y+166323X0070Y0240     S1      
327FM_P2E_MODE      VIA   -    M      A01X+015234Y+165576X0300Y    R180 S1      
327FM_P2E_MODE      R3293 -1          A01X+014835Y+165216X0198Y0197R270 S1      
327FM_P2E_MODE      R3266 -2   M      A01X+015235Y+165216X0198Y0197R090 S1      
327FM_P2E_FGB       U237  -14         A01X+013328Y+168094X0070Y0240R180 S1      
327FM_P2E_FGB       VIA   -    M      A01X+013243Y+168634X0300Y    R180 S1      
327FM_P2E_FGB       R3267 -1   M      A01X+013535Y+169051X0198Y0197R090 S1      
327FM_P2E_FGB       R3270 -1   M      A01X+013135Y+169051X0198Y0197R090 S1      
327FM_P2E_FGB       R3269 -2          A01X+012735Y+169051X0198Y0197R270 S1      
327FM_P2E_FGA       VIA   -    M      A01X+013235Y+165577X0300Y    R180 S1      
327FM_P2E_FGA       R3275 -2   M      A01X+013235Y+165216X0198Y0197R090 S1      
327FM_P2E_FGA       R3276 -1          A01X+012435Y+165216X0198Y0197R270 S1      
327FM_P2E_FGA       R3273 -1   M      A01X+012835Y+165216X0198Y0197R270 S1      
327FM_P2E_FGA       U237  -27         A01X+013328Y+166323X0070Y0240     S1      
327FM_P2E_EQB1      VIA   -    M      A01X+012335Y+168684X0300Y    R180 S1      
327FM_P2E_EQB1      R3279 -1          A01X+011535Y+169039X0198Y0197R090 S1      
327FM_P2E_EQB1      R3281 -1   M      A01X+011935Y+169039X0198Y0197R090 S1      
327FM_P2E_EQB1      R3280 -2   M      A01X+012335Y+169039X0198Y0197R270 S1      
327FM_P2E_EQB1      U237  -15         A01X+013170Y+168094X0070Y0240R180 S1      
327FM_P2E_EQB0      R3283 -2   M      A01X+011593Y+167431X0198Y0197     S1      
327FM_P2E_EQB0      VIA   -    M      A01X+011993Y+167484X0300Y    R180 S1      
327FM_P2E_EQB0      U237  -20         A01X+012993Y+167287X0070Y0240R270 S1      
327FM_P2E_EQB0      R3282 -1   M      A01X+010706Y+167956X0198Y0197R180 S1      
327FM_P2E_EQB0      R3284 -1          A01X+010706Y+167556X0198Y0197R180 S1      
327FM_P2E_EQA1      U237  -26         A01X+013170Y+166323X0070Y0240     S1      
327FM_P2E_EQA1      VIA   -    M      A01X+012035Y+165584X0300Y    R180 S1      
327FM_P2E_EQA1      R3271 -2          A01X+011235Y+165216X0198Y0197R090 S1      
327FM_P2E_EQA1      R3268 -1   M      A01X+011635Y+165216X0198Y0197R270 S1      
327FM_P2E_EQA1      R3272 -1   M      A01X+012035Y+165216X0198Y0197R270 S1      
327FM_P2E_EQA0      R3277 -2   M      A01X+011593Y+167031X0198Y0197     S1      
327FM_P2E_EQA0      VIA   -    M      A01X+011993Y+166984X0300Y    R180 S1      
327FM_P2E_EQA0      U237  -21         A01X+012993Y+167130X0070Y0240R270 S1      
327FM_P2E_EQA0      R3274 -1          A01X+010706Y+167136X0198Y0197R180 S1      
327FM_P2E_EQA0      R3278 -1   M      A01X+010706Y+166736X0198Y0197R180 S1      
327FM_P2E_EN_N      VIA   -    M      A01X+015135Y+168684X0300Y    R180 S1      
327FM_P2E_EN_N      U237  -11         A01X+013800Y+168094X0070Y0240R180 S1      
327FM_P2E_EN_N      R4537 -1          A01X+015135Y+169051X0198Y0197R090 S1      
327m2392            R6162 -2          A01X+004505Y+168164X0198Y0197R180 S1      
317m2392            VIA   -    MD0100PA00X+004505Y+168428X0200Y    R270 S0      
317m2392            VIA   -    MD0100PA00X+005663Y+058582X0200Y         S0      
327m2392            R4076 -1   M      A01X+006315Y+054984X0198Y0197R270 S1      
327m2392            U248  -4          A01X+012381Y+052948X0400Y0150R180 S1      
327m2392            R3292 -2   M      A01X+015535Y+169366X0198Y0197R090 S1      
327m2392            R3265 -1   M      A01X+015943Y+169366X0198Y0197R270 S1      
327m2392            R4537 -2          A01X+015135Y+169366X0198Y0197R090 S1      
317m2392            VIA   -    M      A01X+015943Y+169665X0200Y    R090 S2      
017m2392            VIA   -    M      A18X+015943Y+169665X0260Y    R090 S2      
017m2392                  -    MD0100PA00X+015943Y+169665                       
327m2393            R3758 -2          A01X+086532Y+022776X0198Y0197R180 S1      
327m2393            C2071 -1   M      A01X+085878Y+022756X0198Y0197R270 S1      
327m2393            U276  -13         A01X+085043Y+021990X0090Y0240     S1      
327m2394            C2071 -2   M      A01X+085878Y+022441X0198Y0197R270 S1      
327m2394            R3760 -2          A01X+086532Y+022376X0198Y0197R180 S1      
327m2394            U276  -12         A01X+085299Y+021734X0090Y0240R270 S1      
327m2395            R3602 -2          A01X+170487Y+036977X0198Y0197     S1      
327m2395            C2027 -1   M      A01X+171462Y+036496X0198Y0197     S1      
327m2395            U266  -13         A01X+173204Y+036487X0090Y0240R180 S1      
327m2396            R3603 -2          A01X+170487Y+037377X0198Y0197     S1      
327m2396            C2027 -2   M      A01X+171776Y+036496X0198Y0197     S1      
327m2396            U266  -12         A01X+172948Y+036743X0090Y0240R090 S1      
317m2397            VIA   -    MD0100PA00X+081453Y+013985X0200Y         S0      
327m2397            U265  -13         A01X+081800Y+013985X0090Y0240R090 S1      
327m2397            C2022 -1   M      A18X+080822Y+014314X0198Y0197R090 S2      
327m2397            R3578 -2          A18X+080210Y+014426X0198Y0197R180 S2      
327m2398            C2022 -2   M      A18X+080822Y+013999X0198Y0197R090 S2      
327m2398            R3579 -2          A18X+080210Y+013926X0198Y0197R180 S2      
327m2398            U265  -12         A01X+082056Y+014241X0090Y0240     S1      
317m2398            VIA   -    MD0100PA00X+081457Y+014595X0200Y         S0      
327m2399            U264  -13         A01X+061318Y+023039X0090Y0240     S1      
327m2399            R3574 -2          A01X+063453Y+023098X0198Y0197R180 S1      
327m2399            C2021 -1   M      A01X+063061Y+023055X0198Y0197R270 S1      
327m2400            R3575 -2          A01X+063453Y+022698X0198Y0197R180 S1      
327m2400            U264  -12         A01X+061574Y+022783X0090Y0240R270 S1      
327m2400            C2021 -2   M      A01X+063061Y+022740X0198Y0197R270 S1      
327m2401            U263  -13         A01X+028921Y+016032X0090Y0240     S1      
327m2401            R3570 -2          A01X+031426Y+023185X0198Y0197R180 S1      
327m2401            C2020 -1   M      A01X+031034Y+023143X0198Y0197R270 S1      
327m2402            U263  -12         A01X+029176Y+015776X0090Y0240R270 S1      
327m2402            R3571 -2          A01X+031426Y+022785X0198Y0197R180 S1      
327m2402            C2020 -2   M      A01X+031034Y+022828X0198Y0197R270 S1      
317VR_P5V_EN_N      VIA   -    MD0100PA00X+161646Y+045751X0200Y         S0      
317VR_P5V_EN_N      VIA   -    MD0100PA00X+157349Y+054700X0200Y         S0      
327VR_P5V_EN_N      U324  -G          A18X+155189Y+060282X0320Y0360R270 S2      
317VR_P5V_EN_N      VIA   -    M      A01X+086342Y+042936X0200Y         S2      
017VR_P5V_EN_N      VIA   -    M      A18X+086342Y+042936X0260Y         S2      
017VR_P5V_EN_N            -    MD0100PA00X+086342Y+042936                       
317VR_P5V_EN_N      VIA   -    MD0100PA00X+146661Y+045861X0200Y         S0      
317VR_P5V_EN_N      VIA   -    MD0100PA00X+056871Y+043423X0200Y    R180 S0      
327VR_P5V_EN_N      R336  -2   M      A01X+055625Y+042395X0198Y0197     S1      
327VR_P5V_EN_N      Q37   -5   M      A01X+056591Y+042395X0170Y0200R270 S1      
327VR_P5V_EN_N      Q37   -6          A01X+056591Y+042139X0170Y0200R270 S1      
327VR_P5V_EN_D_R1   Q37   -3          A01X+057339Y+042651X0170Y0200R270 S1      
327VR_P5V_EN_D_R1   R1654 -2          A01X+058307Y+043198X0198Y0197R180 S1      
327VR_P5V_EN_D_R1   VIA   -    M      A01X+057827Y+043198X0300Y    R180 S1      
327VR_P5V_EN_D_R    R335  -2          A18X+157400Y+056858X0198Y0197R270 S2      
317VR_P5V_EN_D_R    VIA   -    MD0100PA00X+161625Y+046504X0200Y         S0      
317VR_P5V_EN_D_R    VIA   -    MD0100PA00X+085950Y+042936X0200Y         S0      
327VR_P5V_EN_D_R    R1654 -1          A01X+058622Y+043198X0198Y0197R180 S1      
317VR_P5V_EN_D_R    VIA   -    MD0100PA00X+058874Y+043198X0200Y    R090 S0      
327VR_P5V_EN_D_R    C9226 -1          A18X+156784Y+057402X0198Y0197R090 S2      
327VR_P5V_EN_D_R    Q57   -4          A01X+157668Y+057402X0280Y0460R270 S1      
317VR_P5V_EN_D_R    VIA   -    M      A01X+157244Y+057402X0200Y    R270 S2      
017VR_P5V_EN_D_R    VIA   -    M      A18X+157244Y+057402X0260Y    R270 S2      
017VR_P5V_EN_D_R          -    MD0100PA00X+157244Y+057402                       
327VR_P5V_EN_D      VIA   -           A18X+157276Y+061147X0260Y         S2      
327VR_P5V_EN_D      VIA   -           A18X+158086Y+061144X0260Y         S2      
327VR_P5V_EN_D      VIA   -           A18X+158978Y+061146X0260Y         S2      
327VR_P5V_EN_D      VIA   -           A18X+156478Y+061142X0260Y         S2      
327VR_P5V_EN_D      U324  -D          A18X+155976Y+060656X0320Y0360R270 S2      
327VR_P5V_EN_D      R4641 -2          A18X+158451Y+060587X0400Y0630R270 S2      
327VR_P5V_EN_D      R4639 -2          A18X+159281Y+060587X0400Y0630R270 S2      
327VR_P5V_EN_D      R4638 -2          A18X+156791Y+060587X0400Y0630R270 S2      
327VR_P5V_EN_D      R4640 -2          A18X+157621Y+060587X0400Y0630R270 S2      
327VR_P5V_EN        Q37   -2          A01X+057339Y+042395X0170Y0200R270 S1      
327VR_P5V_EN        R333  -2          A01X+058305Y+042795X0198Y0197R180 S1      
327VR_P5V_EN        VIA   -    M      A01X+057825Y+042395X0300Y    R180 S1      
327VR_P5V_EN        R334  -1   M      A01X+058305Y+042395X0198Y0197     S1      
327m2403            Y8004 -3          A01X+003110Y+038778X0360Y0400     S1      
327m2403            U268  -11         A01X+004588Y+039030X0100Y0290R270 S1      
327m2403            C2030 -1   M      A01X+003660Y+038813X0198Y0197R270 S1      
317m2403            VIA   -    M      A01X+004094Y+038730X0200Y         S2      
017m2403            VIA   -    M      A18X+004094Y+038730X0260Y         S2      
017m2403                  -    MD0100PA00X+004094Y+038730                       
327m2404            Y8004 -1          A01X+002500Y+039507X0360Y0400     S1      
327m2404            U268  -10         A01X+004588Y+039227X0100Y0290R270 S1      
317m2404            VIA   -    M      A01X+003932Y+039227X0200Y         S2      
017m2404            VIA   -    M      A18X+003932Y+039227X0260Y         S2      
017m2404                  -    MD0100PA00X+003932Y+039227                       
327m2404            C2029 -1   M      A01X+003652Y+039220X0198Y0197R090 S1      
327USB_HUB_TEST     U268  -18         A01X+005537Y+038080X0100Y0290     S1      
327USB_HUB_TEST     VIA   -    M      A01X+005350Y+037136X0300Y         S1      
327USB_HUB_TEST     R3666 -1          A01X+005519Y+036649X0198Y0197R270 S1      
327USB_HUB_RREF     R3653 -1          A01X+003606Y+040100X0198Y0197R180 S1      
327USB_HUB_RREF     U268  -8          A01X+004588Y+039621X0100Y0290R270 S1      
327USB_HUB_RREF     VIA   -    M      A01X+004080Y+040096X0300Y         S1      
327USB_HUB_PSELF    R3664 -1          A01X+008182Y+037603X0198Y0197     S1      
327USB_HUB_PSELF    R3663 -2   M      A01X+008180Y+038222X0198Y0197R180 S1      
327USB_HUB_PSELF    VIA   -    M      A01X+007050Y+038156X0300Y         S1      
327USB_HUB_PSELF    U268  -22         A01X+006487Y+038440X0100Y0290R270 S1      
327USB_HUB_PGANG    R3665 -1          A01X+008180Y+038650X0198Y0197     S1      
327USB_HUB_PGANG    U268  -23         A01X+006487Y+038636X0100Y0290R270 S1      
327USB_HUB_PGANG    VIA   -    M      A01X+007660Y+038636X0300Y         S1      
327USB_HUB_OVCUR4   U268  -19         A01X+005734Y+038080X0100Y0290     S1      
327USB_HUB_OVCUR4   VIA   -    M      A01X+005734Y+037526X0300Y         S1      
327USB_HUB_OVCUR4   R3659 -2          A01X+005932Y+036649X0198Y0197R090 S1      
327USB_HUB_OVCUR3   R3658 -2          A01X+006343Y+036649X0198Y0197R090 S1      
327USB_HUB_OVCUR3   U268  -20         A01X+005931Y+038080X0100Y0290     S1      
327USB_HUB_OVCUR3   VIA   -    M      A01X+006335Y+037136X0300Y         S1      
327USB_HUB_OVCUR2   U268  -24         A01X+006487Y+038833X0100Y0290R270 S1      
327USB_HUB_OVCUR2   VIA   -    M      A01X+007114Y+039040X0300Y         S1      
327USB_HUB_OVCUR2   R3657 -2          A01X+008180Y+039139X0198Y0197R180 S1      
327USB_HUB_OVCUR1   R3656 -2          A01X+008180Y+039586X0198Y0197R180 S1      
327USB_HUB_OVCUR1   VIA   -    M      A01X+007620Y+039586X0300Y         S1      
327USB_HUB_OVCUR1   U268  -25         A01X+006487Y+039030X0100Y0290R270 S1      
327USB_HUB_DVDD     R3662 -2          A01X+006768Y+036649X0198Y0197R090 S1      
327USB_HUB_DVDD     U268  -21         A01X+006128Y+038080X0100Y0290     S1      
327USB_HUB_DVDD     VIA   -    M      A01X+006571Y+037604X0300Y         S1      
327USB2_P0_R_DP     R3651 -1          A01X+006019Y+041077X0180Y0200R270 S1      
327USB2_P0_R_DP     U268  -2          A01X+005931Y+039980X0100Y0290     S1      
327USB2_P0_R_DN     R3652 -1          A01X+006553Y+041089X0180Y0200R270 S1      
327USB2_P0_R_DN     U268  -1          A01X+006128Y+039980X0100Y0290     S1      
327m2405            R2786 -1          A01X+004497Y+041371X0180Y0200R270 S1      
327m2405            U268  -4          A01X+005537Y+039980X0100Y0290     S1      
327m2406            R2787 -1          A01X+005034Y+041380X0180Y0200R270 S1      
327m2406            U268  -3          A01X+005734Y+039980X0100Y0290     S1      
327m2407            R2786 -2          A01X+004497Y+041686X0180Y0200R270 S1      
327m2407            R2788 -2   M      A01X+004497Y+041686X0180Y0200R090 S1      
317m2407            VIA   -    MD0100PA18X+014258Y+164016X0200Y         S0      
317m2407            VIA   -    MD0100PA18X+004581Y+045160X0200Y         S0      
317m2407            VIA   -    MD0100PA00X+004762Y+041518X0200Y    R090 S0      
327m2407            U5201 -2   M      A18X+004676Y+043945X0070Y0320     S2      
327m2407            U5201 -7   M      A18X+004676Y+044496X0070Y0320     S2      
327m2407            R5234 -1          A18X+019811Y+164845X0198Y0197R180 S2      
327m2408            R2789 -2          A01X+005034Y+041694X0180Y0200R090 S1      
327m2408            R2787 -2   M      A01X+005034Y+041694X0180Y0200R270 S1      
317m2408            VIA   -    MD0100PA18X+014258Y+164356X0200Y         S0      
317m2408            VIA   -    MD0100PA18X+004921Y+045160X0200Y         S0      
317m2408            VIA   -    MD0100PA00X+004762Y+041908X0200Y    R090 S0      
327m2408            U5201 -1   M      A18X+004833Y+043945X0070Y0320     S2      
327m2408            U5201 -8   M      A18X+004833Y+044496X0070Y0320     S2      
327m2408            R5236 -1          A18X+019811Y+165245X0198Y0197R180 S2      
327m2409            R2790 -2          A01X+006019Y+041707X0180Y0200R270 S1      
327m2409            R2788 -1          A01X+004497Y+042001X0180Y0200R090 S1      
317m2409            VIA   -    MD0100PA00X+006092Y+043081X0200Y         S0      
317m2409            VIA   -    MD0100PA00X+004596Y+042881X0200Y         S0      
327m2409            R4482 -1   M      A01X+006018Y+042375X0198Y0197R180 S1      
327m2410            R2791 -2          A01X+006553Y+041719X0180Y0200R270 S1      
327m2410            R2789 -1          A01X+005034Y+042010X0180Y0200R090 S1      
317m2410            VIA   -    MD0100PA00X+006482Y+043081X0200Y         S0      
317m2410            VIA   -    MD0100PA00X+004936Y+042881X0200Y         S0      
327m2410            R4483 -1   M      A01X+006553Y+042375X0198Y0197     S1      
327U273_3_ADD2      VIA   -    M      A01X+046645Y+005502X0300Y         S1      
327U273_3_ADD2      R4184 -2          A01X+048597Y+005510X0198Y0197R180 S1      
327U273_3_ADD2      U273  -5          A01X+045613Y+005502X0240Y0520R270 S1      
327U273_3_ADD2      R4185 -1   M      A01X+047221Y+005514X0198Y0197     S1      
327U273_3_ADD1      VIA   -    M      A01X+046425Y+006002X0300Y         S1      
327U273_3_ADD1      R4192 -2          A01X+048581Y+006010X0198Y0197R180 S1      
327U273_3_ADD1      U273  -6          A01X+045613Y+006002X0240Y0520R270 S1      
327U273_3_ADD1      R4193 -1   M      A01X+047228Y+006003X0198Y0197     S1      
327U273_3_ADD0      VIA   -    M      A01X+046585Y+006502X0300Y         S1      
327U273_3_ADD0      R4200 -2          A01X+048570Y+006496X0198Y0197R180 S1      
327U273_3_ADD0      U273  -7          A01X+045613Y+006502X0240Y0520R270 S1      
327U273_3_ADD0      R4201 -1   M      A01X+047228Y+006498X0198Y0197     S1      
327U272_2_ADD2      U272  -5          A01X+039982Y+165502X0240Y0520     S1      
327U272_2_ADD2      VIA   -    M      A01X+039732Y+167012X0300Y         S1      
327U272_2_ADD2      R4187 -1   M      A01X+039982Y+166154X0198Y0197R090 S1      
327U272_2_ADD2      R4186 -2          A01X+039732Y+167492X0198Y0197R270 S1      
327U272_2_ADD1      U272  -6          A01X+039482Y+165502X0240Y0520     S1      
327U272_2_ADD1      VIA   -    M      A01X+039232Y+167012X0300Y         S1      
327U272_2_ADD1      R4195 -1   M      A01X+039482Y+166154X0198Y0197R090 S1      
327U272_2_ADD1      R4194 -2          A01X+039232Y+167492X0198Y0197R270 S1      
327U272_2_ADD0      U272  -7          A01X+038982Y+165502X0240Y0520     S1      
327U272_2_ADD0      VIA   -    M      A01X+038732Y+167012X0300Y         S1      
327U272_2_ADD0      R4203 -1   M      A01X+038982Y+166154X0198Y0197R090 S1      
327U272_2_ADD0      R4202 -2          A01X+038732Y+167492X0198Y0197R270 S1      
327U271_1_ADD2      R4189 -1          A01X+119273Y+005282X0198Y0197     S1      
327U271_1_ADD2      VIA   -    M      A01X+118721Y+005257X0300Y         S1      
327U271_1_ADD2      R4188 -2   M      A01X+117863Y+005282X0198Y0197R180 S1      
327U271_1_ADD2      U271  -5          A01X+116935Y+005319X0240Y0520R270 S1      
327U271_1_ADD1      VIA   -    M      A01X+118737Y+005912X0300Y         S1      
327U271_1_ADD1      R4197 -1          A01X+119281Y+005702X0198Y0197     S1      
327U271_1_ADD1      R4196 -2   M      A01X+117861Y+005702X0198Y0197R180 S1      
327U271_1_ADD1      U271  -6          A01X+116935Y+005819X0240Y0520R270 S1      
327U271_1_ADD0      VIA   -    M      A01X+118673Y+006512X0300Y         S1      
327U271_1_ADD0      R4205 -1          A01X+119271Y+006152X0198Y0197     S1      
327U271_1_ADD0      R4204 -2   M      A01X+117861Y+006152X0198Y0197R180 S1      
327U271_1_ADD0      U271  -7          A01X+116935Y+006319X0240Y0520R270 S1      
317U270_0_ADD2      VIA   -    M      A01X+145558Y+166570X0200Y         S2      
017U270_0_ADD2      VIA   -    M      A18X+145558Y+166570X0260Y         S2      
017U270_0_ADD2            -    MD0100PA00X+145558Y+166570                       
327U270_0_ADD2      R4190 -2          A01X+146170Y+166781X0198Y0197R270 S1      
327U270_0_ADD2      U270  -5          A01X+145558Y+166120X0240Y0520     S1      
327U270_0_ADD2      R4191 -1   M      A01X+145758Y+166773X0198Y0197R090 S1      
327U270_0_ADD1      VIA   -    M      A01X+145100Y+167700X0300Y         S1      
327U270_0_ADD1      R4198 -2          A01X+144907Y+168115X0198Y0197R270 S1      
327U270_0_ADD1      U270  -6          A01X+145058Y+166120X0240Y0520     S1      
327U270_0_ADD1      R4199 -1   M      A01X+145258Y+166773X0198Y0197R090 S1      
327U270_0_ADD0      VIA   -    M      A01X+144508Y+167709X0300Y         S1      
327U270_0_ADD0      U270  -7          A01X+144558Y+166120X0240Y0520     S1      
327U270_0_ADD0      R4206 -2          A01X+144508Y+168110X0198Y0197R270 S1      
327U270_0_ADD0      R4207 -1   M      A01X+144758Y+166773X0198Y0197R090 S1      
327TP_USB2_TEST     VIA   -           A18X+002752Y+043499X0260Y         S2      
327TP_USB2_TEST     U5201 -3          A18X+004440Y+043984X0070Y0240R270 S2      
327TP_USB2_ENA_HS   VIA   -           A18X+005792Y+044870X0260Y         S2      
327TP_USB2_ENA_HS   U5201 -9          A18X+005070Y+044456X0070Y0240R270 S2      
327TP_USB2_CD       VIA   -           A18X+003335Y+043499X0260Y         S2      
327TP_USB2_CD       U5201 -4          A18X+004440Y+044142X0070Y0240R270 S2      
317m2411            VIA   -    M      A01X+042730Y+007130X0200Y         S2      
017m2411            VIA   -    M      A18X+042730Y+007130X0260Y         S2      
017m2411                  -    MD0100PA00X+042730Y+007130                       
327m2411            U273  -1          A01X+043526Y+007002X0240Y0520R270 S1      
327m2411            R3554 -2          A01X+042241Y+007166X0198Y0197     S1      
327m2412            R3732 -2   M      A01X+106882Y+044550X0198Y0197     S1      
327m2412            R3722 -2          A01X+106884Y+044966X0198Y0197     S1      
317m2412            VIA   -    M      A01X+041655Y+007166X0200Y         S2      
017m2412            VIA   -    M      A18X+041655Y+007166X0260Y         S2      
017m2412                  -    MD0100PA00X+041655Y+007166                       
327m2412            R3554 -1          A01X+041926Y+007166X0198Y0197     S1      
317m2412            VIA   -    MD0100PA00X+100922Y+024364X0200Y         S0      
317m2413            VIA   -    M      A01X+042815Y+006502X0200Y         S2      
017m2413            VIA   -    M      A18X+042815Y+006502X0260Y         S2      
017m2413                  -    MD0100PA00X+042815Y+006502                       
327m2413            U273  -2          A01X+043526Y+006502X0240Y0520R270 S1      
327m2413            R3553 -2          A01X+042241Y+006686X0198Y0197     S1      
327m2414            R3731 -2   M      A01X+106887Y+045796X0198Y0197     S1      
327m2414            R3721 -2          A01X+106884Y+045366X0198Y0197     S1      
317m2414            VIA   -    M      A01X+041655Y+006636X0200Y         S2      
017m2414            VIA   -    M      A18X+041655Y+006636X0260Y         S2      
017m2414                  -    MD0100PA00X+041655Y+006636                       
327m2414            R3553 -1          A01X+041926Y+006686X0198Y0197     S1      
317m2414            VIA   -    MD0100PA00X+101522Y+024364X0200Y    R180 S0      
327m2415            U272  -1          A01X+038482Y+163415X0240Y0520     S1      
317m2415            VIA   -    M      A01X+038482Y+162971X0200Y    R090 S2      
017m2415            VIA   -    M      A18X+038482Y+162971X0260Y    R090 S2      
017m2415                  -    MD0100PA00X+038482Y+162971                       
327m2415            R4181 -2          A01X+038482Y+162729X0198Y0197R090 S1      
327m2416            R3720 -2          A01X+101119Y+045616X0198Y0197R180 S1      
327m2416            R3730 -2   M      A01X+100391Y+045168X0198Y0197     S1      
317m2416            VIA   -    MD0100PA00X+099166Y+044637X0200Y         S0      
317m2416            VIA   -    MD0100PA00X+087388Y+044799X0200Y         S0      
317m2416            VIA   -    MD0100PA00X+088378Y+078681X0200Y         S0      
317m2416            VIA   -    MD0100PA00X+067941Y+154884X0200Y         S0      
317m2416            VIA   -    MD0100PA00X+041085Y+155743X0200Y         S0      
327m2416            R4181 -1          A01X+038482Y+162414X0198Y0197R090 S1      
317m2416            VIA   -    M      A01X+038900Y+162150X0200Y    R270 S2      
017m2416            VIA   -    M      A18X+038900Y+162150X0260Y    R270 S2      
017m2416                  -    MD0100PA00X+038900Y+162150                       
327m2417            U272  -2          A01X+038982Y+163415X0240Y0520     S1      
317m2417            VIA   -    M      A01X+038982Y+162971X0200Y    R090 S2      
017m2417            VIA   -    M      A18X+038982Y+162971X0260Y    R090 S2      
017m2417                  -    MD0100PA00X+038982Y+162971                       
327m2417            R4178 -2          A01X+038982Y+162729X0198Y0197R090 S1      
327m2418            R3719 -2          A01X+101119Y+045216X0198Y0197R180 S1      
327m2418            R3729 -2   M      A01X+100391Y+044618X0198Y0197     S1      
317m2418            VIA   -    MD0100PA00X+099490Y+044619X0200Y         S0      
317m2418            VIA   -    MD0100PA00X+087388Y+045049X0200Y         S0      
317m2418            VIA   -    MD0100PA00X+088363Y+079034X0200Y         S0      
317m2418            VIA   -    MD0100PA00X+067985Y+155149X0200Y         S0      
317m2418            VIA   -    M      A01X+039400Y+162150X0200Y    R270 S2      
017m2418            VIA   -    M      A18X+039400Y+162150X0260Y    R270 S2      
017m2418                  -    MD0100PA00X+039400Y+162150                       
327m2418            R4178 -1          A01X+038982Y+162414X0198Y0197R090 S1      
317m2418            VIA   -    MD0100PA00X+042111Y+156024X0200Y         S0      
327m2419            R4182 -2          A01X+115039Y+007474X0198Y0197     S1      
327m2419            U271  -1          A01X+114849Y+006819X0240Y0520R270 S1      
317m2419            VIA   -    M      A01X+115168Y+007226X0200Y         S2      
017m2419            VIA   -    M      A18X+115168Y+007226X0260Y         S2      
017m2419                  -    MD0100PA00X+115168Y+007226                       
317m2420            VIA   -    MD0100PA00X+114264Y+007474X0200Y         S0      
317m2420            VIA   -    M      A01X+100391Y+046016X0200Y         S2      
017m2420            VIA   -    M      A18X+100391Y+046016X0260Y         S2      
017m2420                  -    MD0100PA00X+100391Y+046016                       
327m2420            R3718 -2          A01X+101119Y+046416X0198Y0197R180 S1      
327m2420            R3728 -2   M      A01X+100391Y+046268X0198Y0197     S1      
327m2420            R4182 -1          A01X+114724Y+007474X0198Y0197     S1      
327m2421            U271  -2          A01X+114849Y+006319X0240Y0520R270 S1      
317m2421            VIA   -    M      A01X+114214Y+006319X0200Y         S2      
017m2421            VIA   -    M      A18X+114214Y+006319X0260Y         S2      
017m2421                  -    MD0100PA00X+114214Y+006319                       
327m2421            R4179 -2          A01X+113621Y+005651X0198Y0197     S1      
317m2422            VIA   -    MD0100PA00X+112690Y+006080X0200Y         S0      
317m2422            VIA   -    M      A01X+100391Y+045466X0200Y         S2      
017m2422            VIA   -    M      A18X+100391Y+045466X0260Y         S2      
017m2422                  -    MD0100PA00X+100391Y+045466                       
327m2422            R3717 -2          A01X+101119Y+046016X0198Y0197R180 S1      
327m2422            R3727 -2   M      A01X+100391Y+045718X0198Y0197     S1      
327m2422            R4179 -1          A01X+113306Y+005651X0198Y0197     S1      
327m2423            VIA   -    M      A01X+143950Y+163350X0300Y         S1      
327m2423            U270  -1          A01X+144058Y+164034X0240Y0520     S1      
327m2423            R4183 -2          A01X+144050Y+163008X0198Y0197R090 S1      
317m2424            VIA   -    M      A01X+099632Y+047036X0200Y         S2      
017m2424            VIA   -    M      A18X+099632Y+047036X0260Y         S2      
017m2424                  -    MD0100PA00X+099632Y+047036                       
317m2424            VIA   -    MD0100PA00X+144600Y+160050X0200Y         S0      
327m2424            R4183 -1          A01X+144050Y+162692X0198Y0197R090 S1      
327m2424            R6253 -1   M      A01X+144050Y+162058X0198Y0197R270 S1      
327m2424            R3716 -2          A01X+101119Y+047216X0198Y0197R180 S1      
327m2424            R3726 -2   M      A01X+100391Y+047368X0198Y0197     S1      
317m2424            VIA   -    MD0100PA00X+138146Y+048555X0200Y         S0      
327m2425            U270  -2          A01X+144558Y+164034X0240Y0520     S1      
327m2425            VIA   -    M      A01X+144550Y+163350X0300Y         S1      
327m2425            R4180 -2          A01X+144550Y+163008X0198Y0197R090 S1      
317m2426            VIA   -    M      A01X+099365Y+046532X0200Y         S2      
017m2426            VIA   -    M      A18X+099365Y+046532X0260Y         S2      
017m2426                  -    MD0100PA00X+099365Y+046532                       
327m2426            R3715 -2          A01X+101119Y+046816X0198Y0197R180 S1      
327m2426            R3725 -2   M      A01X+100391Y+046818X0198Y0197     S1      
317m2426            VIA   -    MD0100PA00X+137386Y+048555X0200Y         S0      
317m2426            VIA   -    MD0100PA00X+145100Y+160100X0200Y         S0      
327m2426            R6252 -1   M      A01X+144550Y+162058X0198Y0197R270 S1      
327m2426            R4180 -1          A01X+144550Y+162692X0198Y0197R090 S1      
327m2427            U265  -4          A01X+082647Y+013139X0090Y0240     S1      
327m2427            R3577 -2          A01X+083914Y+012936X0198Y0197R180 S1      
327m2427            VIA   -    M      A01X+083362Y+012920X0300Y    R090 S1      
327m2428            R3577 -1          A01X+084230Y+012936X0198Y0197R180 S1      
327m2428            R3593 -2          A01X+084865Y+012936X0198Y0197R180 S1      
317m2428            VIA   -    M      A01X+084522Y+012936X0200Y    R090 S2      
017m2428            VIA   -    M      A18X+084522Y+012936X0260Y    R090 S2      
017m2428                  -    MD0100PA00X+084522Y+012936                       
327m2429            U265  -5          A01X+082903Y+013394X0090Y0240R090 S1      
327m2429            VIA   -    M      A01X+083412Y+013570X0300Y    R090 S1      
327m2429            R3576 -2          A01X+083914Y+013586X0198Y0197R180 S1      
327m2430            R3576 -1          A01X+084230Y+013586X0198Y0197R180 S1      
327m2430            R3592 -2          A01X+084865Y+013586X0198Y0197R180 S1      
317m2430            VIA   -    M      A01X+084522Y+013586X0200Y    R090 S2      
017m2430            VIA   -    M      A18X+084522Y+013586X0260Y    R090 S2      
017m2430                  -    MD0100PA00X+084522Y+013586                       
327m2431            R3573 -2          A01X+060229Y+020934X0198Y0197R090 S1      
327m2431            U264  -4          A01X+060472Y+022192X0090Y0240R270 S1      
327m2431            VIA   -    M      A01X+059997Y+021446X0300Y         S1      
327m2432            R3595 -2          A01X+060229Y+020134X0198Y0197R090 S1      
317m2432            VIA   -    M      A01X+060229Y+020379X0200Y         S2      
017m2432            VIA   -    M      A18X+060229Y+020379X0260Y         S2      
017m2432                  -    MD0100PA00X+060229Y+020379                       
327m2432            R3573 -1          A01X+060229Y+020619X0198Y0197R090 S1      
327m2433            R3572 -2          A01X+060879Y+020934X0198Y0197R090 S1      
327m2433            VIA   -    M      A01X+060565Y+021414X0300Y         S1      
327m2433            U264  -5          A01X+060728Y+021936X0090Y0240     S1      
327m2434            R3594 -2          A01X+060879Y+020134X0198Y0197R090 S1      
317m2434            VIA   -    M      A01X+060879Y+020379X0200Y         S2      
017m2434            VIA   -    M      A18X+060879Y+020379X0260Y         S2      
017m2434                  -    MD0100PA00X+060879Y+020379                       
327m2434            R3572 -1          A01X+060879Y+020619X0198Y0197R090 S1      
327m2435            U263  -4          A01X+028074Y+015185X0090Y0240R270 S1      
327m2435            R3569 -2          A01X+027998Y+013696X0198Y0197     S1      
327m2435            VIA   -    M      A01X+027700Y+014396X0300Y         S1      
317m2436            VIA   -    M      A01X+027682Y+014046X0200Y         S2      
017m2436            VIA   -    M      A18X+027682Y+014046X0260Y         S2      
017m2436                  -    MD0100PA00X+027682Y+014046                       
327m2436            R3569 -1          A01X+027682Y+013696X0198Y0197     S1      
317m2436            VIA   -    MD0100PA00X+059366Y+018878X0200Y         S0      
327m2436            R3591 -2          A01X+059829Y+020134X0198Y0197R090 S1      
327m2437            U263  -5          A01X+028330Y+014929X0090Y0240     S1      
317m2437            VIA   -    MD0100PA00X+028305Y+013973X0200Y         S0      
327m2437            R3568 -2          A01X+028372Y+013696X0198Y0197R180 S1      
327m2437            VIA   -    M      A01X+028200Y+014396X0300Y         S1      
317m2437            VIA   -    MD0100PA00X+026457Y+015121X0200Y         S0      
327m2437            R3620 -2          A01X+026698Y+015120X0198Y0197R180 S1      
317m2438            VIA   -    MD0100PA00X+060016Y+018878X0200Y         S0      
327m2438            R3590 -2          A01X+060879Y+019119X0198Y0197R270 S1      
327m2438            R3568 -1          A01X+028688Y+013696X0198Y0197R180 S1      
317m2438            VIA   -    M      A01X+028700Y+013986X0200Y         S2      
017m2438            VIA   -    M      A18X+028700Y+013986X0260Y         S2      
017m2438                  -    MD0100PA00X+028700Y+013986                       
327m2439            R3756 -2          A01X+084022Y+020094X0198Y0197R090 S1      
327m2439            R3751 -2          A18X+084172Y+021279X0198Y0197R090 S2      
327m2439            U276  -4          A01X+084197Y+021144X0090Y0240R270 S1      
317m2439            VIA   -    M      A01X+083882Y+020687X0200Y         S2      
017m2439            VIA   -    M      A18X+083882Y+020687X0260Y         S2      
017m2439                  -    MD0100PA00X+083882Y+020687                       
327m2440            R3756 -1          A01X+084022Y+019779X0198Y0197R090 S1      
327m2440            R3589 -2          A01X+084022Y+018794X0198Y0197R090 S1      
327m2440            VIA   -    M      A01X+083922Y+019286X0300Y         S1      
327m2441            R3754 -2          A01X+084422Y+020094X0198Y0197R090 S1      
317m2441            VIA   -    M      A01X+084453Y+020497X0200Y         S2      
017m2441            VIA   -    M      A18X+084453Y+020497X0260Y         S2      
017m2441                  -    MD0100PA00X+084453Y+020497                       
327m2441            U276  -5          A01X+084453Y+020888X0090Y0240     S1      
327m2442            R3754 -1          A01X+084422Y+019779X0198Y0197R090 S1      
327m2442            R3588 -2          A01X+084422Y+018794X0198Y0197R090 S1      
327m2442            VIA   -    M      A01X+084522Y+019286X0300Y         S1      
327m2443            R3601 -2          A01X+175114Y+037745X0198Y0197R180 S1      
327m2443            U266  -4          A01X+174050Y+037334X0090Y0240R090 S1      
317m2443            VIA   -    M      A01X+174451Y+037745X0200Y         S2      
017m2443            VIA   -    M      A18X+174451Y+037745X0260Y         S2      
017m2443                  -    MD0100PA00X+174451Y+037745                       
327m2444            R3587 -2          A01X+118085Y+046476X0198Y0197R090 S1      
317m2444            VIA   -    M      A01X+119304Y+048169X0200Y         S2      
017m2444            VIA   -    M      A18X+119304Y+048169X0260Y         S2      
017m2444                  -    MD0100PA00X+119304Y+048169                       
327m2444            R3601 -1          A01X+175430Y+037745X0198Y0197R180 S1      
317m2444            VIA   -    MD0100PA00X+177022Y+037745X0200Y         S0      
317m2444            VIA   -    MD0100PA00X+127048Y+043315X0200Y         S0      
327m2445            R3600 -2          A01X+175114Y+038295X0198Y0197R180 S1      
327m2445            U266  -5          A01X+173794Y+037590X0090Y0240R180 S1      
317m2445            VIA   -    M      A01X+174438Y+038289X0200Y         S2      
017m2445            VIA   -    M      A18X+174438Y+038289X0260Y         S2      
017m2445                  -    MD0100PA00X+174438Y+038289                       
327m2446            R3600 -1          A01X+175430Y+038295X0198Y0197R180 S1      
317m2446            VIA   -    MD0100PA00X+177022Y+038295X0200Y         S0      
317m2446            VIA   -    MD0100PA00X+127048Y+043565X0200Y         S0      
327m2446            R3586 -2          A01X+117834Y+047274X0198Y0197R090 S1      
317m2446            VIA   -    M      A01X+118604Y+048169X0200Y         S2      
017m2446            VIA   -    M      A18X+118604Y+048169X0260Y         S2      
017m2446                  -    MD0100PA00X+118604Y+048169                       
327m2447            R125  -1          A01X+124003Y+042726X0198Y0197R180 S1      
327m2447            R86   -1          A01X+125314Y+045318X0198Y0197R180 S1      
317m2447            VIA   -    MD0100PA00X+124243Y+042726X0200Y    R180 S0      
317m2447            VIA   -    MD0100PA00X+117825Y+045314X0200Y         S0      
327m2447            R2566 -2          A01X+116071Y+045769X0198Y0197     S1      
327m2447            R67   -2   M      A01X+116963Y+045334X0198Y0197R180 S1      
317m2447            VIA   -    M      A01X+125614Y+045387X0200Y         S2      
017m2447            VIA   -    M      A18X+125614Y+045387X0260Y         S2      
017m2447                  -    MD0100PA00X+125614Y+045387                       
327m2448            R121  -1          A01X+124003Y+043926X0198Y0197R180 S1      
327m2448            R85   -1          A01X+125314Y+045818X0198Y0197R180 S1      
317m2448            VIA   -    MD0100PA00X+124243Y+043926X0200Y    R180 S0      
327m2448            R2565 -2          A01X+116071Y+046169X0198Y0197     S1      
327m2448            R66   -2   M      A01X+116963Y+045884X0198Y0197R180 S1      
317m2448            VIA   -    MD0100PA00X+117834Y+045873X0200Y         S0      
317m2448            VIA   -    M      A01X+125614Y+045918X0200Y         S2      
017m2448            VIA   -    M      A18X+125614Y+045918X0260Y         S2      
017m2448                  -    MD0100PA00X+125614Y+045918                       
327m2449            R2801 -1          A18X+068340Y+164708X0198Y0197R270 S2      
327m2449            U192  -6          A18X+069319Y+164597X0140Y0560R090 S2      
317m2449            VIA   -    MD0100PA00X+061519Y+007453X0200Y         S0      
317m2449            VIA   -    MD0100PA00X+074513Y+034496X0200Y         S0      
317m2449            VIA   -    MD0100PA00X+086765Y+083339X0200Y         S0      
327m2449            R3114 -2          A18X+062201Y+007232X0198Y0197R270 S2      
317m2449            VIA   -    MD0100PA00X+067216Y+156090X0200Y         S0      
317m2449            VIA   -    M      A01X+068681Y+164350X0200Y         S2      
017m2449            VIA   -    M      A18X+068681Y+164350X0260Y         S2      
017m2449                  -    MD0100PA00X+068681Y+164350                       
317m2450            VIA   -    MD0100PA00X+062841Y+004538X0200Y         S0      
317m2450            VIA   -    M      A01X+086765Y+083682X0200Y         S2      
017m2450            VIA   -    M      A18X+086765Y+083682X0260Y         S2      
017m2450                  -    MD0100PA00X+086765Y+083682                       
327m2450            R2800 -1          A18X+071742Y+164576X0198Y0197R270 S2      
327m2450            U192  -3   M      A18X+071077Y+164597X0140Y0560R090 S2      
327m2450            R3113 -2          A18X+062717Y+005168X0198Y0197R180 S2      
317m2450            VIA   -    MD0100PA00X+074875Y+034358X0200Y         S0      
317m2450            VIA   -    MD0100PA00X+066952Y+156085X0200Y         S0      
317m2450            VIA   -    MD0100PA00X+070356Y+164412X0200Y         S0      
327m2451            R2812 -1          A18X+067997Y+164642X0198Y0197     S2      
327m2451            R2807 -2   M      A18X+067997Y+165042X0198Y0197R180 S2      
327m2451            R2801 -2   M      A18X+068340Y+165022X0198Y0197R270 S2      
327m2451            VIA   -    M      A18X+068687Y+165101X0260Y         S2      
327m2451            U192  -7          A18X+069319Y+164853X0140Y0560R090 S2      
327m2452            VIA   -    M      A18X+072166Y+164622X0260Y         S2      
327m2452            R2811 -1          A18X+072552Y+164400X0198Y0197R180 S2      
327m2452            R2805 -2   M      A18X+072552Y+164800X0198Y0197     S2      
327m2452            U192  -2          A18X+071077Y+164853X0140Y0560R090 S2      
327m2452            R2800 -2   M      A18X+071742Y+164891X0198Y0197R270 S2      
327m2453            R2812 -2          A18X+067682Y+164642X0198Y0197     S2      
327m2453            VIA   -    M      A18X+072768Y+163996X0260Y         S2      
317m2453            J45   -C2   D0402PA00X+092878Y+169489X0657Y    R270 S3      
317m2453            VIA   -    MD0100PA00X+073988Y+164805X0200Y         S0      
327m2454            VIA   -    M      A18X+073298Y+164288X0260Y         S2      
317m2454            VIA   -    MD0100PA00X+073564Y+164854X0200Y         S0      
327m2454            R2811 -2          A18X+072867Y+164400X0198Y0197R180 S2      
317m2454            J45   -C1   D0402PA00X+093878Y+169489X0657Y    R270 S3      
327m2455            R3654 -2          A01X+003901Y+036649X0198Y0197R090 S1      
327m2455            C2041 -1   M      A01X+004683Y+036649X0198Y0197R270 S1      
327m2455            R3661 -2   M      A01X+004281Y+036649X0198Y0197R090 S1      
327m2455            R3660 -2   M      A01X+005111Y+036649X0198Y0197R090 S1      
327m2455            U268  -17         A01X+005341Y+038080X0100Y0290     S1      
327m2455            VIA   -    M      A01X+005020Y+037526X0300Y         S1      
317RST_USB_HUB_N    VIA   -    M      A01X+003574Y+036334X0200Y         S2      
017RST_USB_HUB_N    VIA   -    M      A18X+003574Y+036334X0260Y         S2      
017RST_USB_HUB_N          -    MD0100PA00X+003574Y+036334                       
327RST_USB_HUB_N    R6322 -1          A01X+040330Y+021765X0198Y0197R270 S1      
317RST_USB_HUB_N    VIA   -    MD0100PA00X+039926Y+012114X0200Y         S0      
317RST_USB_HUB_N    VIA   -    MD0100PA00X+019259Y+035307X0200Y         S0      
327RST_USB_HUB_N    R3654 -1   M      A01X+003901Y+036334X0198Y0197R090 S1      
317RST_USB_HUB_N    VIA   -    MD0100PA00X+048668Y+018952X0200Y    R180 S0      
327RST_USB_HUB_N    R4451 -1          A01X+048911Y+018952X0198Y0197     S1      
317RST_USB_HUB_N    VIA   -    MD0100PA00X+040000Y+022030X0200Y    R090 S0      
327RST_USB_HUB_N    R6328 -1          A01X+039926Y+012357X0198Y0197R090 S1      
317RST_USB_HUB_N    VIA   -    MD0100PA00X+037037Y+166182X0200Y         S0      
327RST_USB_HUB_N    U181  -4          A01X+071934Y+164333X0160Y0540     S1      
317RST_USB_HUB_N    VIA   -    MD0100PA00X+071812Y+163913X0200Y         S0      
317RST_USB_HUB_N    VIA   -    MD0100PA00X+012170Y+161946X0200Y         S0      
317m2456            J45   -B1   D0402PA00X+093878Y+170489X0657Y    R270 S3      
327m2456            VIA   -    M      A18X+093980Y+167094X0260Y         S2      
327m2456            R2905 -2          A18X+094380Y+166634X0198Y0197R270 S2      
327m2456            C74   -1   M      A18X+093980Y+166634X0198Y0197R090 S2      
327m2457            R4268 -2          A01X+110829Y+171124X0198Y0197R180 S1      
327m2457            VIA   -    M      A01X+110349Y+171124X0300Y    R270 S1      
327m2457            U308  -1          A01X+109805Y+171124X0170Y0240R180 S1      
317m2458            VIA   -    M      A01X+109911Y+169123X0200Y         S2      
017m2458            VIA   -    M      A18X+109911Y+169123X0260Y         S2      
017m2458                  -    MD0100PA00X+109911Y+169123                       
327m2458            R4266 -1          A01X+109469Y+168723X0198Y0197R180 S1      
327m2458            R4265 -1   M      A01X+109469Y+169123X0198Y0197R180 S1      
327m2458            U308  -6          A01X+109805Y+170376X0170Y0240R180 S1      
327m2458            R4264 -2   M      A01X+109949Y+169603X0198Y0197R180 S1      
317m2459            J45   -B2   D0402PA00X+092878Y+170489X0657Y    R270 S3      
327m2459            R4266 -2          A01X+109154Y+168723X0198Y0197R180 S1      
317m2459            VIA   -    M      A01X+108714Y+168891X0200Y         S2      
017m2459            VIA   -    M      A18X+108714Y+168891X0260Y         S2      
017m2459                  -    MD0100PA00X+108714Y+168891                       
317m2460            VIA   -    MD0100PA00X+132843Y+034945X0200Y         S0      
317m2460            VIA   -    MD0100PA00X+125098Y+047494X0200Y         S0      
327m2460            R6078 -2          A01X+080946Y+043134X0198Y0197     S1      
317m2460            VIA   -    MD0100PA00X+084599Y+042941X0200Y         S0      
317m2460            VIA   -    M      A01X+111395Y+171124X0200Y    R090 S2      
017m2460            VIA   -    M      A18X+111395Y+171124X0260Y    R090 S2      
017m2460                  -    MD0100PA00X+111395Y+171124                       
327m2460            R4268 -1          A01X+111144Y+171124X0198Y0197R180 S1      
327PD_U5201_VREG    U5201 -11         A18X+005070Y+044142X0070Y0240R270 S2      
327PD_U5201_VREG    VIA   -    M      A18X+005792Y+044370X0260Y         S2      
327PD_U5201_VREG    C5236 -1          A18X+006235Y+044368X0198Y0197R180 S2      
327PD_U5201_RSTN    C5232 -1          A18X+003383Y+044113X0198Y0197     S2      
327PD_U5201_RSTN    VIA   -    M      A18X+003848Y+044148X0260Y         S2      
327PD_U5201_RSTN    U5201 -5          A18X+004440Y+044299X0070Y0240R270 S2      
327PD_U5201_EQ      R5238 -1          A18X+003383Y+044552X0198Y0197     S2      
327PD_U5201_EQ      VIA   -    M      A18X+003862Y+044720X0260Y         S2      
327PD_U5201_EQ      U5201 -6          A18X+004440Y+044456X0070Y0240R270 S2      
327PD_MB_FRU_WP     R710  -1          A01X+125487Y+046437X0198Y0197     S1      
327PD_MB_FRU_WP     U64   -7          A01X+123834Y+046538X0350Y0500R270 S1      
327PD_MB_FRU_WP     VIA   -    M      A01X+124672Y+046316X0300Y         S1      
327P5V              C6122 -1   M      A01X+067950Y+052092X0198Y0197R090 S1      
327P5V              R479  -1          A01X+066858Y+053350X0198Y0197R180 S1      
327P5V              U100  -3          A01X+067362Y+052000X0320Y0400R270 S1      
317P5V              VIA   -    MD0100PA00X+068300Y+052150X0200Y         S0      
317P5V              VIA   -    MD0100PA00X+082438Y+051760X0200Y         S0      
317P5V              VIA   -    MD0100PA00X+166434Y+021019X0200Y    R090 S0      
327P5V              D1    -3          A01X+166764Y+021019X0320Y0360R090 S1      
317P5V              VIA   -    MD0100PA00X+161214Y+041855X0200Y         S0      
317P5V              VIA   -    MD0100PA00X+130158Y+017155X0200Y         S0      
327P5V              R3005 -1          A01X+129918Y+017155X0198Y0197R180 S1      
317P5V              VIA   -    MD0100PA00X+123809Y+025863X0200Y         S0      
327P5V              R3102 -2          A18X+123809Y+026106X0198Y0197R090 S2      
317P5V              VIA   -    MD0100PA00X+113457Y+051387X0200Y         S0      
317P5V              VIA   -    MD0100PA00X+156125Y+058039X0200Y         S0      
317P5V              VIA   -    MD0100PA00X+156495Y+058273X0200Y         S0      
327P5V              C1227 -1   M      A01X+156134Y+057777X0198Y0197R270 S1      
327P5V              C1331 -1          A01X+156718Y+057889X0400Y0500R090 S1      
317P5V              VIA   -    M      A01X+157244Y+058243X0200Y         S2      
017P5V              VIA   -    M      A18X+157244Y+058243X0260Y         S2      
017P5V                    -    MD0100PA00X+157244Y+058243                       
317P5V              VIA   -    MD0100PA00X+156845Y+058273X0200Y         S0      
317P5V              VIA   -    MD0100PA00X+157244Y+058593X0200Y         S0      
317P5V              VIA   -    MD0100PA00X+157244Y+058943X0200Y         S0      
327P5V              Q57   -2          A01X+157668Y+058402X0280Y0460R270 S1      
327P5V              Q57   -1          A01X+157668Y+058902X0280Y0460R270 S1      
317P5V              VIA   -    MD0100PA00X+157244Y+057893X0200Y         S0      
327P5V              Q57   -3          A01X+157668Y+057902X0280Y0460R270 S1      
327P5V              R4640 -1          A18X+157621Y+059327X0400Y0630R270 S2      
327P5V              R4638 -1          A18X+156791Y+059327X0400Y0630R270 S2      
327P5V              R4639 -1          A18X+159281Y+059327X0400Y0630R270 S2      
327P5V              R4641 -1          A18X+158451Y+059327X0400Y0630R270 S2      
317P5V              VIA   -    MD0100PA00X+156202Y+058778X0200Y         S0      
317P5V              VIA   -    MD0100PA00X+156202Y+058428X0200Y         S0      
317P5V              VIA   -    MD0100PA00X+156544Y+058943X0200Y         S0      
317P5V              VIA   -    MD0100PA00X+156544Y+058593X0200Y         S0      
317P5V              VIA   -    MD0100PA00X+156894Y+058943X0200Y         S0      
317P5V              VIA   -    MD0100PA00X+156894Y+058593X0200Y         S0      
327m2461            C1529 -1          A01X+049372Y+146000X0120Y0150R270 S1      
327m2461            U6017 -BU35       A01X+049220Y+150946X0100Y0130     S1      
327m2462            C1531 -1          A01X+048702Y+146970X0120Y0150R270 S1      
327m2462            U6017 -CD35       A01X+048747Y+150946X0100Y0130     S1      
327m2463            C1533 -1          A01X+048032Y+147940X0120Y0150R270 S1      
327m2463            U6017 -CL35       A01X+048275Y+150946X0100Y0130     S1      
327m2464            C1535 -1          A01X+046692Y+146000X0120Y0150R270 S1      
327m2464            U6017 -CV35       A01X+047802Y+150946X0100Y0130     S1      
327m2465            C1537 -1          A01X+046022Y+146970X0120Y0150R270 S1      
327m2465            U6017 -DE35       A01X+047330Y+150946X0100Y0130     S1      
327m2466            C1539 -1          A01X+045352Y+147940X0120Y0150R270 S1      
327m2466            U6017 -DM35       A01X+046858Y+150946X0100Y0130     S1      
327m2467            C1541 -1          A01X+044012Y+146000X0120Y0150R270 S1      
327m2467            U6017 -DW35       A01X+046385Y+150946X0100Y0130     S1      
327m2468            C1543 -1          A01X+043342Y+146970X0120Y0150R270 S1      
327m2468            U6017 -EF35       A01X+045913Y+150946X0100Y0130     S1      
327m2469            C1545 -1          A01X+043439Y+148009X0120Y0150R180 S1      
327m2469            U6017 -EL34       A01X+045558Y+151150X0120Y         S1      
327m2470            C49   -1          A01X+053769Y+149398X0120Y0150     S1      
327m2470            U6017 -R35        A01X+052054Y+150946X0100Y0130     S1      
327m2471            C51   -1          A01X+053769Y+148418X0120Y0150     S1      
327m2471            U6017 -Y34        A01X+051700Y+151150X0120Y         S1      
327m2472            C53   -1          A01X+053392Y+146000X0120Y0150R270 S1      
327m2472            U6017 -AJ35       A01X+051109Y+150946X0100Y0130     S1      
327m2473            C55   -1          A01X+052052Y+146000X0120Y0150R270 S1      
327m2473            U6017 -AT35       A01X+050637Y+150946X0100Y0130     S1      
327m2474            C1525 -1          A01X+051382Y+146970X0120Y0150R270 S1      
327m2474            U6017 -BC35       A01X+050164Y+150946X0100Y0130     S1      
327m2475            C1527 -1          A01X+050712Y+147940X0120Y0150R270 S1      
327m2475            U6017 -BK35       A01X+049692Y+150946X0100Y0130     S1      
327m2476            C1547 -1          A01X+043439Y+150549X0120Y0150R180 S1      
327m2476            U6017 -EY35       A01X+044968Y+150946X0100Y0130     S1      
327m2477            C1528 -1          A01X+049732Y+146000X0120Y0150R270 S1      
327m2477            U6017 -BR34       A01X+049338Y+151150X0120Y         S1      
327m2478            C1530 -1          A01X+049062Y+146970X0120Y0150R270 S1      
327m2478            U6017 -CB34       A01X+048865Y+151150X0120Y         S1      
327m2479            C1532 -1          A01X+048392Y+147940X0120Y0150R270 S1      
327m2479            U6017 -CJ34       A01X+048393Y+151150X0120Y         S1      
327m2480            C1534 -1          A01X+047052Y+146000X0120Y0150R270 S1      
327m2480            U6017 -CT34       A01X+047920Y+151150X0120Y         S1      
327m2481            C1536 -1          A01X+046382Y+146970X0120Y0150R270 S1      
327m2481            U6017 -DC34       A01X+047448Y+151150X0120Y         S1      
327m2482            C1538 -1          A01X+045712Y+147940X0120Y0150R270 S1      
327m2482            U6017 -DK34       A01X+046976Y+151150X0120Y         S1      
327m2483            C1540 -1          A01X+044372Y+146000X0120Y0150R270 S1      
327m2483            U6017 -DU34       A01X+046503Y+151150X0120Y         S1      
327m2484            C1542 -1          A01X+043702Y+146970X0120Y0150R270 S1      
327m2484            U6017 -ED34       A01X+046031Y+151150X0120Y         S1      
327m2485            C1544 -1          A01X+043439Y+148369X0120Y0150R180 S1      
327m2485            U6017 -EN35       A01X+045440Y+150946X0100Y0130     S1      
327m2486            C48   -1          A01X+053769Y+149758X0120Y0150     S1      
327m2486            U6017 -N34        A01X+052172Y+151150X0120Y         S1      
327m2487            C50   -1          A01X+053769Y+148058X0120Y0150     S1      
327m2487            U6017 -AB35       A01X+051582Y+150946X0100Y0130     S1      
327m2488            C52   -1          A01X+053752Y+146000X0120Y0150R270 S1      
327m2488            U6017 -AG34       A01X+051228Y+151150X0120Y         S1      
327m2489            C54   -1          A01X+052412Y+146000X0120Y0150R270 S1      
327m2489            U6017 -AP34       A01X+050755Y+151150X0120Y         S1      
327m2490            C1524 -1          A01X+051742Y+146970X0120Y0150R270 S1      
327m2490            U6017 -BA34       A01X+050283Y+151150X0120Y         S1      
327m2491            C1526 -1          A01X+051072Y+147940X0120Y0150R270 S1      
327m2491            U6017 -BH34       A01X+049810Y+151150X0120Y         S1      
327m2492            C1546 -1          A01X+043439Y+150189X0120Y0150R180 S1      
327m2492            U6017 -EV34       A01X+045086Y+151150X0120Y         S1      
327m2493            C755  -1          A01X+062179Y+146000X0120Y0150R270 S1      
327m2493            U6016 -BU35       A01X+062026Y+150946X0100Y0130     S1      
327m2494            C757  -1          A01X+061509Y+146970X0120Y0150R270 S1      
327m2494            U6016 -CD35       A01X+061553Y+150946X0100Y0130     S1      
327m2495            C759  -1          A01X+060839Y+147940X0120Y0150R270 S1      
327m2495            U6016 -CL35       A01X+061081Y+150946X0100Y0130     S1      
327m2496            C761  -1          A01X+059499Y+146000X0120Y0150R270 S1      
327m2496            U6016 -CV35       A01X+060608Y+150946X0100Y0130     S1      
327m2497            C763  -1          A01X+058829Y+146970X0120Y0150R270 S1      
327m2497            U6016 -DE35       A01X+060136Y+150946X0100Y0130     S1      
327m2498            C765  -1          A01X+058159Y+147940X0120Y0150R270 S1      
327m2498            U6016 -DM35       A01X+059664Y+150946X0100Y0130     S1      
327m2499            C767  -1          A01X+056819Y+146000X0120Y0150R270 S1      
327m2499            U6016 -DW35       A01X+059191Y+150946X0100Y0130     S1      
327m2500            C769  -1          A01X+056149Y+146970X0120Y0150R270 S1      
327m2500            U6016 -EF35       A01X+058719Y+150946X0100Y0130     S1      
327m2501            C771  -1          A01X+056245Y+148009X0120Y0150R180 S1      
327m2501            U6016 -EL34       A01X+058364Y+151150X0120Y         S1      
327m2502            C743  -1          A01X+066576Y+149398X0120Y0150     S1      
327m2502            U6016 -R35        A01X+064860Y+150946X0100Y0130     S1      
327m2503            C745  -1          A01X+066576Y+148058X0120Y0150     S1      
327m2503            U6016 -AB35       A01X+064388Y+150946X0100Y0130     S1      
327m2504            C747  -1          A01X+066199Y+146000X0120Y0150R270 S1      
327m2504            U6016 -AJ35       A01X+063916Y+150946X0100Y0130     S1      
327m2505            C749  -1          A01X+064859Y+146000X0120Y0150R270 S1      
327m2505            U6016 -AT35       A01X+063443Y+150946X0100Y0130     S1      
327m2506            C751  -1          A01X+064189Y+146970X0120Y0150R270 S1      
327m2506            U6016 -BC35       A01X+062971Y+150946X0100Y0130     S1      
327m2507            C753  -1          A01X+063519Y+147940X0120Y0150R270 S1      
327m2507            U6016 -BK35       A01X+062498Y+150946X0100Y0130     S1      
327m2508            C773  -1          A01X+056245Y+150549X0120Y0150R180 S1      
327m2508            U6016 -EY35       A01X+057774Y+150946X0100Y0130     S1      
327m2509            C754  -1          A01X+062539Y+146000X0120Y0150R270 S1      
327m2509            U6016 -BR34       A01X+062144Y+151150X0120Y         S1      
327m2510            C756  -1          A01X+061869Y+146970X0120Y0150R270 S1      
327m2510            U6016 -CB34       A01X+061672Y+151150X0120Y         S1      
327m2511            C758  -1          A01X+061199Y+147940X0120Y0150R270 S1      
327m2511            U6016 -CJ34       A01X+061199Y+151150X0120Y         S1      
327m2512            C760  -1          A01X+059859Y+146000X0120Y0150R270 S1      
327m2512            U6016 -CT34       A01X+060727Y+151150X0120Y         S1      
327m2513            C762  -1          A01X+059189Y+146970X0120Y0150R270 S1      
327m2513            U6016 -DC34       A01X+060254Y+151150X0120Y         S1      
327m2514            C764  -1          A01X+058519Y+147940X0120Y0150R270 S1      
327m2514            U6016 -DK34       A01X+059782Y+151150X0120Y         S1      
327m2515            C766  -1          A01X+057179Y+146000X0120Y0150R270 S1      
327m2515            U6016 -DU34       A01X+059309Y+151150X0120Y         S1      
327m2516            C768  -1          A01X+056509Y+146970X0120Y0150R270 S1      
327m2516            U6016 -ED34       A01X+058837Y+151150X0120Y         S1      
327m2517            C770  -1          A01X+056245Y+148369X0120Y0150R180 S1      
327m2517            U6016 -EN35       A01X+058246Y+150946X0100Y0130     S1      
327m2518            C742  -1          A01X+066576Y+149758X0120Y0150     S1      
327m2518            U6016 -N34        A01X+064979Y+151150X0120Y         S1      
327m2519            C744  -1          A01X+066576Y+148418X0120Y0150     S1      
327m2519            U6016 -Y34        A01X+064506Y+151150X0120Y         S1      
327m2520            C746  -1          A01X+066559Y+146000X0120Y0150R270 S1      
327m2520            U6016 -AG34       A01X+064034Y+151150X0120Y         S1      
327m2521            C748  -1          A01X+065219Y+146000X0120Y0150R270 S1      
327m2521            U6016 -AP34       A01X+063561Y+151150X0120Y         S1      
327m2522            C750  -1          A01X+064549Y+146970X0120Y0150R270 S1      
327m2522            U6016 -BA34       A01X+063089Y+151150X0120Y         S1      
327m2523            C752  -1          A01X+063879Y+147940X0120Y0150R270 S1      
327m2523            U6016 -BH34       A01X+062616Y+151150X0120Y         S1      
327m2524            C772  -1          A01X+056245Y+150189X0120Y0150R180 S1      
327m2524            U6016 -EV34       A01X+057892Y+151150X0120Y         S1      
327m2525            C723  -1          A01X+035761Y+146000X0120Y0150R270 S1      
327m2525            U6015 -BU35       A01X+035609Y+150946X0100Y0130     S1      
327m2526            C725  -1          A01X+035091Y+146970X0120Y0150R270 S1      
327m2526            U6015 -CD35       A01X+035136Y+150946X0100Y0130     S1      
327m2527            C727  -1          A01X+034421Y+147940X0120Y0150R270 S1      
327m2527            U6015 -CL35       A01X+034664Y+150946X0100Y0130     S1      
327m2528            C729  -1          A01X+033081Y+146000X0120Y0150R270 S1      
327m2528            U6015 -CV35       A01X+034191Y+150946X0100Y0130     S1      
327m2529            C731  -1          A01X+032411Y+146970X0120Y0150R270 S1      
327m2529            U6015 -DE35       A01X+033719Y+150946X0100Y0130     S1      
327m2530            C733  -1          A01X+031741Y+147940X0120Y0150R270 S1      
327m2530            U6015 -DM35       A01X+033246Y+150946X0100Y0130     S1      
327m2531            C735  -1          A01X+030401Y+146000X0120Y0150R270 S1      
327m2531            U6015 -DW35       A01X+032774Y+150946X0100Y0130     S1      
327m2532            C737  -1          A01X+029731Y+146970X0120Y0150R270 S1      
327m2532            U6015 -EF35       A01X+032302Y+150946X0100Y0130     S1      
327m2533            C739  -1          A01X+029828Y+148009X0120Y0150R180 S1      
327m2533            U6015 -EL34       A01X+031947Y+151150X0120Y         S1      
327m2534            C711  -1          A01X+040158Y+149398X0120Y0150     S1      
327m2534            U6015 -R35        A01X+038443Y+150946X0100Y0130     S1      
327m2535            C713  -1          A01X+040158Y+148418X0120Y0150     S1      
327m2535            U6015 -Y34        A01X+038089Y+151150X0120Y         S1      
327m2536            C715  -1          A01X+039781Y+146000X0120Y0150R270 S1      
327m2536            U6015 -AJ35       A01X+037498Y+150946X0100Y0130     S1      
327m2537            C717  -1          A01X+038441Y+146000X0120Y0150R270 S1      
327m2537            U6015 -AT35       A01X+037026Y+150946X0100Y0130     S1      
327m2538            C719  -1          A01X+037771Y+146970X0120Y0150R270 S1      
327m2538            U6015 -BC35       A01X+036553Y+150946X0100Y0130     S1      
327m2539            C721  -1          A01X+037101Y+147940X0120Y0150R270 S1      
327m2539            U6015 -BK35       A01X+036081Y+150946X0100Y0130     S1      
327m2540            C741  -1          A01X+029828Y+150549X0120Y0150R180 S1      
327m2540            U6015 -EY35       A01X+031357Y+150946X0100Y0130     S1      
327m2541            C722  -1          A01X+036121Y+146000X0120Y0150R270 S1      
327m2541            U6015 -BR34       A01X+035727Y+151150X0120Y         S1      
327m2542            C724  -1          A01X+035451Y+146970X0120Y0150R270 S1      
327m2542            U6015 -CB34       A01X+035254Y+151150X0120Y         S1      
327m2543            C726  -1          A01X+034781Y+147940X0120Y0150R270 S1      
327m2543            U6015 -CJ34       A01X+034782Y+151150X0120Y         S1      
327m2544            C728  -1          A01X+033441Y+146000X0120Y0150R270 S1      
327m2544            U6015 -CT34       A01X+034309Y+151150X0120Y         S1      
327m2545            C730  -1          A01X+032771Y+146970X0120Y0150R270 S1      
327m2545            U6015 -DC34       A01X+033837Y+151150X0120Y         S1      
327m2546            C732  -1          A01X+032101Y+147940X0120Y0150R270 S1      
327m2546            U6015 -DK34       A01X+033364Y+151150X0120Y         S1      
327m2547            C734  -1          A01X+030761Y+146000X0120Y0150R270 S1      
327m2547            U6015 -DU34       A01X+032892Y+151150X0120Y         S1      
327m2548            C736  -1          A01X+030091Y+146970X0120Y0150R270 S1      
327m2548            U6015 -ED34       A01X+032420Y+151150X0120Y         S1      
327m2549            C738  -1          A01X+029828Y+148369X0120Y0150R180 S1      
327m2549            U6015 -EN35       A01X+031829Y+150946X0100Y0130     S1      
327m2550            C710  -1          A01X+040158Y+149758X0120Y0150     S1      
327m2550            U6015 -N34        A01X+038561Y+151150X0120Y         S1      
327m2551            C712  -1          A01X+040158Y+148058X0120Y0150     S1      
327m2551            U6015 -AB35       A01X+037971Y+150946X0100Y0130     S1      
327m2552            C714  -1          A01X+040141Y+146000X0120Y0150R270 S1      
327m2552            U6015 -AG34       A01X+037616Y+151150X0120Y         S1      
327m2553            C716  -1          A01X+038801Y+146000X0120Y0150R270 S1      
327m2553            U6015 -AP34       A01X+037144Y+151150X0120Y         S1      
327m2554            C718  -1          A01X+038131Y+146970X0120Y0150R270 S1      
327m2554            U6015 -BA34       A01X+036672Y+151150X0120Y         S1      
327m2555            C720  -1          A01X+037461Y+147940X0120Y0150R270 S1      
327m2555            U6015 -BH34       A01X+036199Y+151150X0120Y         S1      
327m2556            C740  -1          A01X+029828Y+150189X0120Y0150R180 S1      
327m2556            U6015 -EV34       A01X+031475Y+151150X0120Y         S1      
327m2557            C819  -1          A01X+022955Y+146000X0120Y0150R270 S1      
327m2557            U6014 -BU35       A01X+022802Y+150946X0100Y0130     S1      
327m2558            C821  -1          A01X+022285Y+146970X0120Y0150R270 S1      
327m2558            U6014 -CD35       A01X+022330Y+150946X0100Y0130     S1      
327m2559            C823  -1          A01X+021615Y+147940X0120Y0150R270 S1      
327m2559            U6014 -CL35       A01X+021858Y+150946X0100Y0130     S1      
327m2560            C825  -1          A01X+020275Y+146000X0120Y0150R270 S1      
327m2560            U6014 -CV35       A01X+021385Y+150946X0100Y0130     S1      
327m2561            C827  -1          A01X+019605Y+146970X0120Y0150R270 S1      
327m2561            U6014 -DE35       A01X+020913Y+150946X0100Y0130     S1      
327m2562            C829  -1          A01X+018935Y+147940X0120Y0150R270 S1      
327m2562            U6014 -DM35       A01X+020440Y+150946X0100Y0130     S1      
327m2563            C831  -1          A01X+017595Y+146000X0120Y0150R270 S1      
327m2563            U6014 -DW35       A01X+019968Y+150946X0100Y0130     S1      
327m2564            C833  -1          A01X+016925Y+146970X0120Y0150R270 S1      
327m2564            U6014 -EF35       A01X+019495Y+150946X0100Y0130     S1      
327m2565            C835  -1          A01X+017021Y+148009X0120Y0150R180 S1      
327m2565            U6014 -EL34       A01X+019141Y+151150X0120Y         S1      
327m2566            C807  -1          A01X+027352Y+149398X0120Y0150     S1      
327m2566            U6014 -R35        A01X+025637Y+150946X0100Y0130     S1      
327m2567            C809  -1          A01X+027352Y+148058X0120Y0150     S1      
327m2567            U6014 -AB35       A01X+025165Y+150946X0100Y0130     S1      
327m2568            C811  -1          A01X+027335Y+146000X0120Y0150R270 S1      
327m2568            U6014 -AG34       A01X+024810Y+151150X0120Y         S1      
327m2569            C813  -1          A01X+025635Y+146000X0120Y0150R270 S1      
327m2569            U6014 -AT35       A01X+024220Y+150946X0100Y0130     S1      
327m2570            C815  -1          A01X+024965Y+146970X0120Y0150R270 S1      
327m2570            U6014 -BC35       A01X+023747Y+150946X0100Y0130     S1      
327m2571            C817  -1          A01X+024295Y+147940X0120Y0150R270 S1      
327m2571            U6014 -BK35       A01X+023275Y+150946X0100Y0130     S1      
327m2572            C837  -1          A01X+017021Y+150549X0120Y0150R180 S1      
327m2572            U6014 -EY35       A01X+018550Y+150946X0100Y0130     S1      
327m2573            C818  -1          A01X+023315Y+146000X0120Y0150R270 S1      
327m2573            U6014 -BR34       A01X+022920Y+151150X0120Y         S1      
327m2574            C820  -1          A01X+022645Y+146970X0120Y0150R270 S1      
327m2574            U6014 -CB34       A01X+022448Y+151150X0120Y         S1      
327m2575            C822  -1          A01X+021975Y+147940X0120Y0150R270 S1      
327m2575            U6014 -CJ34       A01X+021976Y+151150X0120Y         S1      
327m2576            C824  -1          A01X+020635Y+146000X0120Y0150R270 S1      
327m2576            U6014 -CT34       A01X+021503Y+151150X0120Y         S1      
327m2577            C826  -1          A01X+019965Y+146970X0120Y0150R270 S1      
327m2577            U6014 -DC34       A01X+021031Y+151150X0120Y         S1      
327m2578            C828  -1          A01X+019295Y+147940X0120Y0150R270 S1      
327m2578            U6014 -DK34       A01X+020558Y+151150X0120Y         S1      
327m2579            C830  -1          A01X+017955Y+146000X0120Y0150R270 S1      
327m2579            U6014 -DU34       A01X+020086Y+151150X0120Y         S1      
327m2580            C832  -1          A01X+017285Y+146970X0120Y0150R270 S1      
327m2580            U6014 -ED34       A01X+019613Y+151150X0120Y         S1      
327m2581            C834  -1          A01X+017021Y+148369X0120Y0150R180 S1      
327m2581            U6014 -EN35       A01X+019023Y+150946X0100Y0130     S1      
327m2582            C806  -1          A01X+027352Y+149758X0120Y0150     S1      
327m2582            U6014 -N34        A01X+025755Y+151150X0120Y         S1      
327m2583            C808  -1          A01X+027352Y+148418X0120Y0150     S1      
327m2583            U6014 -Y34        A01X+025283Y+151150X0120Y         S1      
327m2584            C810  -1          A01X+026975Y+146000X0120Y0150R270 S1      
327m2584            U6014 -AJ35       A01X+024692Y+150946X0100Y0130     S1      
327m2585            C812  -1          A01X+025995Y+146000X0120Y0150R270 S1      
327m2585            U6014 -AP34       A01X+024338Y+151150X0120Y         S1      
327m2586            C814  -1          A01X+025325Y+146970X0120Y0150R270 S1      
327m2586            U6014 -BA34       A01X+023865Y+151150X0120Y         S1      
327m2587            C816  -1          A01X+024655Y+147940X0120Y0150R270 S1      
327m2587            U6014 -BH34       A01X+023393Y+151150X0120Y         S1      
327m2588            C836  -1          A01X+017021Y+150189X0120Y0150R180 S1      
327m2588            U6014 -EV34       A01X+018668Y+151150X0120Y         S1      
317m2589            VIA   -    MD0080PA01X+041048Y+096892X0160Y    R180 S0      
327m2589            C691  -2          A01X+013066Y+006443X0120Y0150R090 S1      
327m2589            U26   -AL46       A01X+041232Y+096996X0177Y    R180 S1      
317m2589            VIA   -    MD0100PA01X+013055Y+006934X0200Y    R180 S0      
317m2590            VIA   -    MD0080PA01X+041048Y+096254X0160Y    R180 S0      
327m2590            C56   -2          A01X+014166Y+007043X0120Y0150R090 S1      
327m2590            U26   -AJ46       A01X+041232Y+096358X0177Y    R180 S1      
317m2590            VIA   -    MD0100PA01X+014156Y+007534X0200Y    R180 S0      
317m2591            VIA   -    MD0080PA01X+041048Y+097529X0160Y    R180 S0      
327m2591            C695  -2          A01X+015266Y+006443X0120Y0150R090 S1      
327m2591            U26   -AN46       A01X+041232Y+097634X0177Y    R180 S1      
317m2591            VIA   -    MD0100PA01X+015255Y+006934X0200Y    R180 S0      
317m2592            VIA   -    MD0080PA01X+042158Y+096892X0160Y    R180 S0      
327m2592            C697  -2          A01X+016486Y+007043X0120Y0150R090 S1      
327m2592            U26   -AL43       A01X+042342Y+096996X0177Y    R180 S1      
317m2592            VIA   -    MD0100PA01X+016476Y+007534X0200Y    R180 S0      
317m2593            VIA   -    MD0080PA01X+042158Y+096254X0160Y    R180 S0      
327m2593            C699  -2          A01X+017586Y+006443X0120Y0150R090 S1      
327m2593            U26   -AJ43       A01X+042342Y+096358X0177Y    R180 S1      
317m2593            VIA   -    MD0100PA01X+017576Y+006934X0200Y    R180 S0      
317m2594            VIA   -    MD0080PA01X+042158Y+097529X0160Y    R180 S0      
327m2594            C701  -2          A01X+018686Y+007043X0120Y0150R090 S1      
327m2594            U26   -AN43       A01X+042342Y+097634X0177Y    R180 S1      
317m2594            VIA   -    MD0100PA01X+018676Y+007534X0200Y         S0      
317m2595            VIA   -    MD0080PA01X+043083Y+096573X0160Y    R180 S0      
327m2595            C703  -2          A01X+019786Y+006443X0120Y0150R090 S1      
327m2595            U26   -AK40       A01X+043267Y+096677X0177Y    R180 S1      
317m2595            VIA   -    MD0100PA01X+019776Y+006934X0200Y    R180 S0      
317m2596            VIA   -    MD0080PA01X+043083Y+095935X0160Y    R180 S0      
327m2596            C705  -2          A01X+020900Y+007043X0120Y0150R090 S1      
327m2596            U26   -AH40       A01X+043267Y+096040X0177Y    R180 S1      
317m2596            VIA   -    MD0100PA01X+020890Y+007534X0200Y    R180 S0      
317m2597            VIA   -    MD0080PA01X+043083Y+097210X0160Y    R180 S0      
327m2597            C707  -2          A01X+022000Y+006443X0120Y0150R090 S1      
327m2597            U26   -AM40       A01X+043267Y+097315X0177Y    R180 S1      
317m2597            VIA   -    MD0100PA01X+021989Y+006934X0200Y         S0      
317m2598            VIA   -    MD0080PA01X+038827Y+096892X0160Y    R180 S0      
327m2598            C679  -2          A01X+006466Y+006443X0120Y0150R090 S1      
327m2598            U26   -AL52       A01X+039011Y+096996X0177Y    R180 S1      
317m2598            VIA   -    MD0100PA01X+006456Y+006934X0200Y    R180 S0      
317m2599            VIA   -    MD0080PA01X+038827Y+096254X0160Y    R180 S0      
327m2599            C681  -2          A01X+007566Y+007043X0120Y0150R090 S1      
327m2599            U26   -AJ52       A01X+039011Y+096358X0177Y    R180 S1      
317m2599            VIA   -    MD0100PA01X+007555Y+007534X0200Y    R180 S0      
317m2600            VIA   -    MD0080PA01X+038827Y+097529X0160Y    R180 S0      
327m2600            C683  -2          A01X+008666Y+006443X0120Y0150R090 S1      
327m2600            U26   -AN52       A01X+039011Y+097634X0177Y    R180 S1      
317m2600            VIA   -    MD0100PA01X+008656Y+006934X0200Y    R180 S0      
317m2601            VIA   -    MD0080PA01X+039937Y+096892X0160Y    R180 S0      
327m2601            C685  -2          A01X+009766Y+007043X0120Y0150R090 S1      
327m2601            U26   -AL49       A01X+040121Y+096996X0177Y    R180 S1      
317m2601            VIA   -    MD0100PA01X+009756Y+007534X0200Y    R180 S0      
317m2602            VIA   -    MD0080PA01X+039937Y+096254X0160Y    R180 S0      
327m2602            C687  -2          A01X+010866Y+006443X0120Y0150R090 S1      
327m2602            U26   -AJ49       A01X+040121Y+096358X0177Y    R180 S1      
317m2602            VIA   -    MD0100PA01X+010856Y+006934X0200Y    R180 S0      
317m2603            VIA   -    MD0080PA01X+039937Y+097529X0160Y    R180 S0      
327m2603            C689  -2          A01X+011966Y+007043X0120Y0150R090 S1      
327m2603            U26   -AN49       A01X+040121Y+097634X0177Y    R180 S1      
317m2603            VIA   -    MD0100PA01X+011956Y+007534X0200Y    R180 S0      
317m2604            VIA   -    MD0080PA01X+043083Y+097848X0160Y    R180 S0      
327m2604            C709  -2          A01X+023100Y+007043X0120Y0150R090 S1      
327m2604            U26   -AP40       A01X+043267Y+097953X0177Y    R180 S1      
317m2604            VIA   -    MD0100PA01X+023090Y+007534X0200Y    R180 S0      
317m2605            VIA   -    MD0080PA01X+040678Y+096892X0160Y    R180 S0      
327m2605            C690  -2          A01X+012706Y+006443X0120Y0150R090 S1      
327m2605            U26   -AL47       A01X+040861Y+096996X0177Y    R180 S1      
317m2605            VIA   -    MD0100PA01X+012715Y+006934X0200Y    R180 S0      
317m2606            VIA   -    MD0080PA01X+040678Y+096254X0160Y    R180 S0      
327m2606            C692  -2          A01X+013806Y+007043X0120Y0150R090 S1      
327m2606            U26   -AJ47       A01X+040861Y+096358X0177Y    R180 S1      
317m2606            VIA   -    MD0100PA01X+013816Y+007534X0200Y    R180 S0      
317m2607            VIA   -    MD0080PA01X+040678Y+097529X0160Y    R180 S0      
327m2607            C694  -2          A01X+014906Y+006443X0120Y0150R090 S1      
327m2607            U26   -AN47       A01X+040861Y+097634X0177Y    R180 S1      
317m2607            VIA   -    MD0100PA01X+014915Y+006934X0200Y    R180 S0      
317m2608            VIA   -    MD0080PA01X+041788Y+096892X0160Y    R180 S0      
327m2608            C696  -2          A01X+016126Y+007043X0120Y0150R090 S1      
327m2608            U26   -AL44       A01X+041972Y+096996X0177Y    R180 S1      
317m2608            VIA   -    MD0100PA01X+016136Y+007534X0200Y    R180 S0      
317m2609            VIA   -    MD0080PA01X+041788Y+096254X0160Y    R180 S0      
327m2609            C698  -2          A01X+017226Y+006443X0120Y0150R090 S1      
327m2609            U26   -AJ44       A01X+041972Y+096358X0177Y    R180 S1      
317m2609            VIA   -    MD0100PA01X+017236Y+006934X0200Y    R180 S0      
317m2610            VIA   -    MD0080PA01X+041788Y+097529X0160Y    R180 S0      
327m2610            C700  -2          A01X+018326Y+007043X0120Y0150R090 S1      
327m2610            U26   -AN44       A01X+041972Y+097634X0177Y    R180 S1      
317m2610            VIA   -    MD0100PA01X+018336Y+007534X0200Y         S0      
317m2611            VIA   -    MD0080PA01X+042713Y+096573X0160Y    R180 S0      
327m2611            C702  -2          A01X+019426Y+006443X0120Y0150R090 S1      
327m2611            U26   -AK41       A01X+042897Y+096677X0177Y    R180 S1      
317m2611            VIA   -    MD0100PA01X+019436Y+006934X0200Y    R180 S0      
317m2612            VIA   -    MD0080PA01X+042713Y+095935X0160Y    R180 S0      
327m2612            C704  -2          A01X+020540Y+007043X0120Y0150R090 S1      
327m2612            U26   -AH41       A01X+042897Y+096040X0177Y    R180 S1      
317m2612            VIA   -    MD0100PA01X+020550Y+007534X0200Y    R180 S0      
317m2613            VIA   -    MD0080PA01X+042713Y+097210X0160Y    R180 S0      
327m2613            C706  -2          A01X+021640Y+006443X0120Y0150R090 S1      
327m2613            U26   -AM41       A01X+042897Y+097315X0177Y    R180 S1      
317m2613            VIA   -    MD0100PA01X+021649Y+006934X0200Y         S0      
317m2614            VIA   -    MD0080PA01X+038457Y+096892X0160Y    R180 S0      
327m2614            C678  -2          A01X+006106Y+006443X0120Y0150R090 S1      
327m2614            U26   -AL53       A01X+038641Y+096996X0177Y    R180 S1      
317m2614            VIA   -    MD0100PA01X+006116Y+006934X0200Y    R180 S0      
317m2615            VIA   -    MD0080PA01X+038457Y+096254X0160Y    R180 S0      
327m2615            C680  -2          A01X+007206Y+007043X0120Y0150R090 S1      
327m2615            U26   -AJ53       A01X+038641Y+096358X0177Y    R180 S1      
317m2615            VIA   -    MD0100PA01X+007215Y+007534X0200Y    R180 S0      
317m2616            VIA   -    MD0080PA01X+038457Y+097529X0160Y    R180 S0      
327m2616            C682  -2          A01X+008306Y+006443X0120Y0150R090 S1      
327m2616            U26   -AN53       A01X+038641Y+097634X0177Y    R180 S1      
317m2616            VIA   -    MD0100PA01X+008316Y+006934X0200Y    R180 S0      
317m2617            VIA   -    MD0080PA01X+039567Y+096892X0160Y    R180 S0      
327m2617            C684  -2          A01X+009406Y+007043X0120Y0150R090 S1      
327m2617            U26   -AL50       A01X+039751Y+096996X0177Y    R180 S1      
317m2617            VIA   -    MD0100PA01X+009416Y+007534X0200Y    R180 S0      
317m2618            VIA   -    MD0080PA01X+039567Y+096254X0160Y    R180 S0      
327m2618            C686  -2          A01X+010506Y+006443X0120Y0150R090 S1      
327m2618            U26   -AJ50       A01X+039751Y+096358X0177Y    R180 S1      
317m2618            VIA   -    MD0100PA01X+010516Y+006934X0200Y    R180 S0      
317m2619            VIA   -    MD0080PA01X+039567Y+097529X0160Y    R180 S0      
327m2619            C688  -2          A01X+011606Y+007043X0120Y0150R090 S1      
327m2619            U26   -AN50       A01X+039751Y+097634X0177Y    R180 S1      
317m2619            VIA   -    MD0100PA01X+011616Y+007534X0200Y    R180 S0      
317m2620            VIA   -    MD0080PA01X+042713Y+097848X0160Y    R180 S0      
327m2620            C708  -2          A01X+022740Y+007043X0120Y0150R090 S1      
327m2620            U26   -AP41       A01X+042897Y+097953X0177Y    R180 S1      
317m2620            VIA   -    MD0100PA01X+022750Y+007534X0200Y    R180 S0      
327m2621            C691  -1          A01X+013066Y+006233X0120Y0150R090 S1      
327m2621            J35   -B47        A01X+012026Y+004437X0150Y0570R180 S1      
327m2622            C56   -1          A01X+014166Y+006833X0120Y0150R090 S1      
327m2622            J35   -B44        A01X+012735Y+004437X0150Y0570R180 S1      
327m2623            C695  -1          A01X+015266Y+006233X0120Y0150R090 S1      
327m2623            J35   -B39        A01X+015613Y+004437X0150Y0570R180 S1      
327m2624            C697  -1          A01X+016486Y+006833X0120Y0150R090 S1      
327m2624            J35   -B36        A01X+016322Y+004437X0150Y0570R180 S1      
327m2625            C699  -1          A01X+017586Y+006233X0120Y0150R090 S1      
327m2625            J35   -B33        A01X+017030Y+004437X0150Y0570R180 S1      
327m2626            C701  -1          A01X+018686Y+006833X0120Y0150R090 S1      
327m2626            J35   -B30        A01X+017739Y+004437X0150Y0570R180 S1      
327m2627            C703  -1          A01X+019786Y+006233X0120Y0150R090 S1      
327m2627            J35   -B26        A01X+020026Y+004437X0150Y0570R180 S1      
327m2628            C705  -1          A01X+020900Y+006833X0120Y0150R090 S1      
327m2628            J35   -B23        A01X+020735Y+004437X0150Y0570R180 S1      
327m2629            C707  -1          A01X+022000Y+006233X0120Y0150R090 S1      
327m2629            J35   -B20        A01X+021444Y+004437X0150Y0570R180 S1      
327m2630            C679  -1          A01X+006466Y+006233X0120Y0150R090 S1      
327m2630            J35   -B65        A01X+007774Y+004437X0150Y0570R180 S1      
327m2631            C681  -1          A01X+007566Y+006833X0120Y0150R090 S1      
327m2631            J35   -B62        A01X+008483Y+004437X0150Y0570R180 S1      
327m2632            C683  -1          A01X+008666Y+006233X0120Y0150R090 S1      
327m2632            J35   -B59        A01X+009192Y+004437X0150Y0570R180 S1      
327m2633            C685  -1          A01X+009766Y+006833X0120Y0150R090 S1      
327m2633            J35   -B56        A01X+009900Y+004437X0150Y0570R180 S1      
327m2634            C687  -1          A01X+010866Y+006233X0120Y0150R090 S1      
327m2634            J35   -B53        A01X+010609Y+004437X0150Y0570R180 S1      
327m2635            C689  -1          A01X+011966Y+006833X0120Y0150R090 S1      
327m2635            J35   -B50        A01X+011318Y+004437X0150Y0570R180 S1      
327m2636            C709  -1          A01X+023100Y+006833X0120Y0150R090 S1      
327m2636            J35   -B17        A01X+022152Y+004437X0150Y0570R180 S1      
327m2637            C690  -1          A01X+012706Y+006233X0120Y0150R090 S1      
327m2637            J35   -B48        A01X+011790Y+004437X0150Y0570R180 S1      
327m2638            C692  -1          A01X+013806Y+006833X0120Y0150R090 S1      
327m2638            J35   -B45        A01X+012499Y+004437X0150Y0570R180 S1      
327m2639            C694  -1          A01X+014906Y+006233X0120Y0150R090 S1      
327m2639            J35   -B40        A01X+015377Y+004437X0150Y0570R180 S1      
327m2640            C696  -1          A01X+016126Y+006833X0120Y0150R090 S1      
327m2640            J35   -B37        A01X+016085Y+004437X0150Y0570R180 S1      
327m2641            C698  -1          A01X+017226Y+006233X0120Y0150R090 S1      
327m2641            J35   -B34        A01X+016794Y+004437X0150Y0570R180 S1      
327m2642            C700  -1          A01X+018326Y+006833X0120Y0150R090 S1      
327m2642            J35   -B31        A01X+017503Y+004437X0150Y0570R180 S1      
327m2643            C702  -1          A01X+019426Y+006233X0120Y0150R090 S1      
327m2643            J35   -B27        A01X+019790Y+004437X0150Y0570R180 S1      
327m2644            C704  -1          A01X+020540Y+006833X0120Y0150R090 S1      
327m2644            J35   -B24        A01X+020499Y+004437X0150Y0570R180 S1      
327m2645            C706  -1          A01X+021640Y+006233X0120Y0150R090 S1      
327m2645            J35   -B21        A01X+021208Y+004437X0150Y0570R180 S1      
327m2646            C678  -1          A01X+006106Y+006233X0120Y0150R090 S1      
327m2646            J35   -B66        A01X+007538Y+004437X0150Y0570R180 S1      
327m2647            C680  -1          A01X+007206Y+006833X0120Y0150R090 S1      
327m2647            J35   -B63        A01X+008247Y+004437X0150Y0570R180 S1      
327m2648            C682  -1          A01X+008306Y+006233X0120Y0150R090 S1      
327m2648            J35   -B60        A01X+008956Y+004437X0150Y0570R180 S1      
327m2649            C684  -1          A01X+009406Y+006833X0120Y0150R090 S1      
327m2649            J35   -B57        A01X+009664Y+004437X0150Y0570R180 S1      
327m2650            C686  -1          A01X+010506Y+006233X0120Y0150R090 S1      
327m2650            J35   -B54        A01X+010373Y+004437X0150Y0570R180 S1      
327m2651            C688  -1          A01X+011606Y+006833X0120Y0150R090 S1      
327m2651            J35   -B51        A01X+011082Y+004437X0150Y0570R180 S1      
327m2652            C708  -1          A01X+022740Y+006833X0120Y0150R090 S1      
327m2652            J35   -B18        A01X+021916Y+004437X0150Y0570R180 S1      
317m2653            VIA   -    MD0080PA01X+144699Y+108865X0160Y         S0      
317m2653            VIA   -    MD0100PA01X+150170Y+148590X0200Y    R180 S0      
327m2653            C883  -2          A01X+150160Y+149090X0120Y0150R270 S1      
327m2653            U25   -CE30       A01X+144515Y+108760X0177Y    R180 S1      
317m2654            VIA   -    MD0080PA01X+144699Y+109502X0160Y         S0      
317m2654            VIA   -    MD0100PA01X+149500Y+149560X0200Y    R180 S0      
327m2654            C885  -2          A01X+149490Y+150060X0120Y0150R270 S1      
327m2654            U25   -CG30       A01X+144515Y+109398X0177Y    R180 S1      
317m2655            VIA   -    MD0080PA01X+143588Y+108227X0160Y         S0      
317m2655            VIA   -    MD0100PA01X+144810Y+148590X0200Y    R180 S0      
327m2655            C895  -2          A01X+144800Y+149090X0120Y0150R270 S1      
327m2655            U25   -CC33       A01X+143405Y+108122X0177Y    R180 S1      
317m2656            VIA   -    MD0080PA01X+142663Y+109821X0160Y         S0      
317m2656            VIA   -    MD0100PA01X+144140Y+149560X0200Y    R180 S0      
327m2656            C897  -2          A01X+144130Y+150060X0120Y0150R270 S1      
327m2656            U25   -CH36       A01X+142480Y+109717X0177Y    R180 S1      
317m2657            VIA   -    MD0080PA01X+142663Y+109184X0160Y         S0      
317m2657            VIA   -    MD0100PA01X+143516Y+151319X0200Y    R270 S0      
327m2657            C899  -2          A01X+144016Y+151309X0120Y0150R180 S1      
327m2657            U25   -CF36       A01X+142480Y+109079X0177Y    R180 S1      
317m2658            VIA   -    MD0080PA01X+146919Y+108865X0160Y         S0      
317m2658            VIA   -    MD0100PA01X+155267Y+152708X0200Y    R270 S0      
327m2658            U25   -CE24       A01X+146735Y+108760X0177Y    R180 S1      
327m2658            C871  -2          A01X+154767Y+152698X0120Y0150     S1      
317m2659            VIA   -    MD0080PA01X+146919Y+109502X0160Y         S0      
317m2659            VIA   -    MD0100PA01X+155267Y+151708X0200Y    R270 S0      
327m2659            C873  -2          A01X+154767Y+151718X0120Y0150     S1      
327m2659            U25   -CG24       A01X+146735Y+109398X0177Y    R180 S1      
317m2660            VIA   -    MD0080PA01X+146919Y+108227X0160Y         S0      
317m2660            VIA   -    MD0100PA01X+154190Y+148590X0200Y    R180 S0      
327m2660            C875  -2          A01X+154180Y+149090X0120Y0150R270 S1      
327m2660            U25   -CC24       A01X+146735Y+108122X0177Y    R180 S1      
317m2661            VIA   -    MD0080PA01X+145809Y+108865X0160Y         S0      
317m2661            VIA   -    MD0100PA01X+152850Y+148590X0200Y    R180 S0      
327m2661            C877  -2          A01X+152840Y+149090X0120Y0150R270 S1      
327m2661            U25   -CE27       A01X+145625Y+108760X0177Y    R180 S1      
317m2662            VIA   -    MD0080PA01X+145809Y+109502X0160Y         S0      
317m2662            VIA   -    MD0100PA01X+152180Y+149560X0200Y    R180 S0      
327m2662            C879  -2          A01X+152170Y+150060X0120Y0150R270 S1      
327m2662            U25   -CG27       A01X+145625Y+109398X0177Y    R180 S1      
317m2663            VIA   -    MD0080PA01X+145809Y+108227X0160Y         S0      
317m2663            VIA   -    MD0100PA01X+151510Y+150530X0200Y    R180 S0      
327m2663            C881  -2          A01X+151500Y+151030X0120Y0150R270 S1      
327m2663            U25   -CC27       A01X+145625Y+108122X0177Y    R180 S1      
317m2664            VIA   -    MD0080PA01X+142663Y+108546X0160Y         S0      
317m2664            VIA   -    MD0100PA01X+143516Y+153839X0200Y    R270 S0      
327m2664            C901  -2          A01X+144016Y+153849X0120Y0150R180 S1      
327m2664            U25   -CD36       A01X+142480Y+108441X0177Y    R180 S1      
317m2665            VIA   -    MD0080PA01X+145069Y+108865X0160Y         S0      
317m2665            VIA   -    MD0100PA01X+150510Y+148590X0200Y    R180 S0      
327m2665            C882  -2          A01X+150520Y+149090X0120Y0150R270 S1      
327m2665            U25   -CE29       A01X+144885Y+108760X0177Y    R180 S1      
317m2666            VIA   -    MD0080PA01X+145069Y+109502X0160Y         S0      
317m2666            VIA   -    MD0100PA01X+149840Y+149560X0200Y    R180 S0      
327m2666            C884  -2          A01X+149850Y+150060X0120Y0150R270 S1      
327m2666            U25   -CG29       A01X+144885Y+109398X0177Y    R180 S1      
317m2667            VIA   -    MD0080PA01X+143959Y+108227X0160Y         S0      
317m2667            VIA   -    MD0100PA01X+145150Y+148590X0200Y    R180 S0      
327m2667            C894  -2          A01X+145160Y+149090X0120Y0150R270 S1      
327m2667            U25   -CC32       A01X+143775Y+108122X0177Y    R180 S1      
317m2668            VIA   -    MD0080PA01X+143033Y+109821X0160Y         S0      
317m2668            VIA   -    MD0100PA01X+144480Y+149560X0200Y    R180 S0      
327m2668            C896  -2          A01X+144490Y+150060X0120Y0150R270 S1      
327m2668            U25   -CH35       A01X+142850Y+109717X0177Y    R180 S1      
317m2669            VIA   -    MD0080PA01X+143033Y+109184X0160Y         S0      
317m2669            VIA   -    MD0100PA01X+143516Y+151659X0200Y    R270 S0      
327m2669            C898  -2          A01X+144016Y+151669X0120Y0150R180 S1      
327m2669            U25   -CF35       A01X+142850Y+109079X0177Y    R180 S1      
317m2670            VIA   -    MD0080PA01X+147289Y+108865X0160Y         S0      
317m2670            VIA   -    MD0100PA01X+155267Y+153048X0200Y    R270 S0      
327m2670            U25   -CE23       A01X+147106Y+108760X0177Y    R180 S1      
327m2670            C870  -2          A01X+154767Y+153058X0120Y0150     S1      
317m2671            VIA   -    MD0080PA01X+147289Y+109502X0160Y         S0      
317m2671            VIA   -    MD0100PA01X+155267Y+151368X0200Y    R270 S0      
327m2671            C872  -2          A01X+154767Y+151358X0120Y0150     S1      
327m2671            U25   -CG23       A01X+147106Y+109398X0177Y    R180 S1      
317m2672            VIA   -    MD0080PA01X+147289Y+108227X0160Y         S0      
317m2672            VIA   -    MD0100PA01X+154530Y+148590X0200Y    R180 S0      
327m2672            C874  -2          A01X+154540Y+149090X0120Y0150R270 S1      
327m2672            U25   -CC23       A01X+147106Y+108122X0177Y    R180 S1      
317m2673            VIA   -    MD0080PA01X+146179Y+108865X0160Y         S0      
317m2673            VIA   -    MD0100PA01X+153190Y+148590X0200Y    R180 S0      
327m2673            C876  -2          A01X+153200Y+149090X0120Y0150R270 S1      
327m2673            U25   -CE26       A01X+145995Y+108760X0177Y    R180 S1      
317m2674            VIA   -    MD0080PA01X+146179Y+109502X0160Y         S0      
317m2674            VIA   -    MD0100PA01X+152520Y+149560X0200Y    R180 S0      
327m2674            C878  -2          A01X+152530Y+150060X0120Y0150R270 S1      
327m2674            U25   -CG26       A01X+145995Y+109398X0177Y    R180 S1      
317m2675            VIA   -    MD0080PA01X+146179Y+108227X0160Y         S0      
317m2675            VIA   -    MD0100PA01X+151850Y+150530X0200Y    R180 S0      
327m2675            C880  -2          A01X+151860Y+151030X0120Y0150R270 S1      
327m2675            U25   -CC26       A01X+145995Y+108122X0177Y    R180 S1      
317m2676            VIA   -    MD0080PA01X+143033Y+108546X0160Y         S0      
317m2676            VIA   -    MD0100PA01X+143516Y+153499X0200Y    R270 S0      
327m2676            C900  -2          A01X+144016Y+153489X0120Y0150R180 S1      
327m2676            U25   -CD35       A01X+142850Y+108441X0177Y    R180 S1      
327m2677            C883  -1          A01X+150160Y+149300X0120Y0150R270 S1      
327m2677            U6013 -BU35       A01X+150007Y+154246X0100Y0130     S1      
327m2678            C885  -1          A01X+149490Y+150270X0120Y0150R270 S1      
327m2678            U6013 -CD35       A01X+149535Y+154246X0100Y0130     S1      
327m2679            C887  -1          A01X+148820Y+151240X0120Y0150R270 S1      
327m2679            U6013 -CL35       A01X+149062Y+154246X0100Y0130     S1      
327m2680            C889  -1          A01X+147480Y+149300X0120Y0150R270 S1      
327m2680            U6013 -CV35       A01X+148590Y+154246X0100Y0130     S1      
327m2681            C891  -1          A01X+146810Y+150270X0120Y0150R270 S1      
327m2681            U6013 -DE35       A01X+148117Y+154246X0100Y0130     S1      
327m2682            C893  -1          A01X+146140Y+151240X0120Y0150R270 S1      
327m2682            U6013 -DM35       A01X+147645Y+154246X0100Y0130     S1      
327m2683            C895  -1          A01X+144800Y+149300X0120Y0150R270 S1      
327m2683            U6013 -DW35       A01X+147172Y+154246X0100Y0130     S1      
327m2684            C897  -1          A01X+144130Y+150270X0120Y0150R270 S1      
327m2684            U6013 -EF35       A01X+146700Y+154246X0100Y0130     S1      
327m2685            C899  -1          A01X+144226Y+151309X0120Y0150R180 S1      
327m2685            U6013 -EL34       A01X+146346Y+154450X0120Y         S1      
327m2686            C871  -1          A01X+154557Y+152698X0120Y0150     S1      
327m2686            U6013 -R35        A01X+152842Y+154246X0100Y0130     S1      
327m2687            C873  -1          A01X+154557Y+151718X0120Y0150     S1      
327m2687            U6013 -Y34        A01X+152487Y+154450X0120Y         S1      
327m2688            C875  -1          A01X+154180Y+149300X0120Y0150R270 S1      
327m2688            U6013 -AJ35       A01X+151897Y+154246X0100Y0130     S1      
327m2689            C877  -1          A01X+152840Y+149300X0120Y0150R270 S1      
327m2689            U6013 -AT35       A01X+151424Y+154246X0100Y0130     S1      
327m2690            C879  -1          A01X+152170Y+150270X0120Y0150R270 S1      
327m2690            U6013 -BC35       A01X+150952Y+154246X0100Y0130     S1      
327m2691            C881  -1          A01X+151500Y+151240X0120Y0150R270 S1      
327m2691            U6013 -BK35       A01X+150480Y+154246X0100Y0130     S1      
327m2692            C901  -1          A01X+144226Y+153849X0120Y0150R180 S1      
327m2692            U6013 -EY35       A01X+145755Y+154246X0100Y0130     S1      
327m2693            C882  -1          A01X+150520Y+149300X0120Y0150R270 S1      
327m2693            U6013 -BR34       A01X+150125Y+154450X0120Y         S1      
327m2694            C884  -1          A01X+149850Y+150270X0120Y0150R270 S1      
327m2694            U6013 -CB34       A01X+149653Y+154450X0120Y         S1      
327m2695            C886  -1          A01X+149180Y+151240X0120Y0150R270 S1      
327m2695            U6013 -CJ34       A01X+149180Y+154450X0120Y         S1      
327m2696            C888  -1          A01X+147840Y+149300X0120Y0150R270 S1      
327m2696            U6013 -CT34       A01X+148708Y+154450X0120Y         S1      
327m2697            C890  -1          A01X+147170Y+150270X0120Y0150R270 S1      
327m2697            U6013 -DC34       A01X+148235Y+154450X0120Y         S1      
327m2698            C892  -1          A01X+146500Y+151240X0120Y0150R270 S1      
327m2698            U6013 -DK34       A01X+147763Y+154450X0120Y         S1      
327m2699            C894  -1          A01X+145160Y+149300X0120Y0150R270 S1      
327m2699            U6013 -DU34       A01X+147290Y+154450X0120Y         S1      
327m2700            C896  -1          A01X+144490Y+150270X0120Y0150R270 S1      
327m2700            U6013 -ED34       A01X+146818Y+154450X0120Y         S1      
327m2701            C898  -1          A01X+144226Y+151669X0120Y0150R180 S1      
327m2701            U6013 -EN35       A01X+146228Y+154246X0100Y0130     S1      
327m2702            C870  -1          A01X+154557Y+153058X0120Y0150     S1      
327m2702            U6013 -N34        A01X+152960Y+154450X0120Y         S1      
327m2703            C872  -1          A01X+154557Y+151358X0120Y0150     S1      
327m2703            U6013 -AB35       A01X+152369Y+154246X0100Y0130     S1      
327m2704            C874  -1          A01X+154540Y+149300X0120Y0150R270 S1      
327m2704            U6013 -AG34       A01X+152015Y+154450X0120Y         S1      
327m2705            C876  -1          A01X+153200Y+149300X0120Y0150R270 S1      
327m2705            U6013 -AP34       A01X+151542Y+154450X0120Y         S1      
327m2706            C878  -1          A01X+152530Y+150270X0120Y0150R270 S1      
327m2706            U6013 -BA34       A01X+151070Y+154450X0120Y         S1      
327m2707            C880  -1          A01X+151860Y+151240X0120Y0150R270 S1      
327m2707            U6013 -BH34       A01X+150598Y+154450X0120Y         S1      
327m2708            C900  -1          A01X+144226Y+153489X0120Y0150R180 S1      
327m2708            U6013 -EV34       A01X+145873Y+154450X0120Y         S1      
317m2709            VIA   -    MD0080PA01X+147595Y+155270X0160Y         S0      
317m2709            VIA   -    MD0080PA01X+143959Y+113329X0160Y         S0      
327m2709            U25   -CW32       A01X+143775Y+113224X0177Y    R180 S1      
327m2709            U6013 -DT26       A01X+147390Y+155270X0150Y         S1      
317m2710            VIA   -    MD0080PA01X+147122Y+155270X0160Y         S0      
317m2710            VIA   -    MD0080PA01X+143033Y+114286X0160Y         S0      
327m2710            U25   -DB35       A01X+142850Y+114181X0177Y    R180 S1      
327m2710            U6013 -EC26       A01X+146918Y+155270X0150Y         S1      
317m2711            VIA   -    MD0080PA01X+146650Y+155270X0160Y         S0      
317m2711            VIA   -    MD0080PA01X+143033Y+113648X0160Y         S0      
327m2711            U25   -CY35       A01X+142850Y+113543X0177Y    R180 S1      
327m2711            U6013 -EK26       A01X+146445Y+155270X0150Y         S1      
317m2712            VIA   -    MD0080PA01X+147289Y+112691X0160Y         S0      
327m2712            U25   -CU23       A01X+147106Y+112587X0177Y    R180 S1      
327m2712            U6013 -M26        A01X+153059Y+155270X0150Y         S1      
317m2712            VIA   -    MD0080PA01X+153264Y+155270X0160Y         S0      
317m2713            VIA   -    MD0080PA01X+152792Y+155270X0160Y         S0      
327m2713            U6013 -W26        A01X+152587Y+155270X0150Y         S1      
317m2713            VIA   -    MD0080PA01X+147289Y+113967X0160Y         S0      
327m2713            U25   -DA23       A01X+147106Y+113862X0177Y    R180 S1      
317m2714            VIA   -    MD0080PA01X+152319Y+155270X0160Y         S0      
327m2714            U6013 -AF26       A01X+152114Y+155270X0150Y         S1      
317m2714            VIA   -    MD0080PA01X+147289Y+114605X0160Y         S0      
327m2714            U25   -DC23       A01X+147106Y+114500X0177Y    R180 S1      
317m2715            VIA   -    MD0080PA01X+151847Y+155270X0160Y         S0      
317m2715            VIA   -    MD0080PA01X+147289Y+113329X0160Y         S0      
327m2715            U25   -CW23       A01X+147106Y+113224X0177Y    R180 S1      
327m2715            U6013 -AN26       A01X+151642Y+155270X0150Y         S1      
317m2716            VIA   -    MD0080PA01X+147438Y+154997X0160Y         S0      
317m2716            VIA   -    MD0080PA01X+143588Y+113329X0160Y         S0      
327m2716            U25   -CW33       A01X+143405Y+113224X0177Y    R180 S1      
327m2716            U6013 -DV29       A01X+147232Y+154997X0150Y         S1      
317m2717            VIA   -    MD0080PA01X+146965Y+154997X0160Y         S0      
317m2717            VIA   -    MD0080PA01X+142663Y+114286X0160Y         S0      
327m2717            U25   -DB36       A01X+142480Y+114181X0177Y    R180 S1      
327m2717            U6013 -EE29       A01X+146760Y+154997X0150Y         S1      
317m2718            VIA   -    MD0080PA01X+146493Y+154997X0160Y         S0      
317m2718            VIA   -    MD0080PA01X+142663Y+113648X0160Y         S0      
327m2718            U25   -CY36       A01X+142480Y+113543X0177Y    R180 S1      
327m2718            U6013 -EM29       A01X+146288Y+154997X0150Y         S1      
317m2719            VIA   -    MD0080PA01X+146919Y+112691X0160Y         S0      
327m2719            U25   -CU24       A01X+146735Y+112587X0177Y    R180 S1      
327m2719            U6013 -P29        A01X+152902Y+154997X0150Y         S1      
317m2719            VIA   -    MD0080PA01X+153107Y+154997X0160Y         S0      
317m2720            VIA   -    MD0080PA01X+152634Y+154997X0160Y         S0      
327m2720            U6013 -AA29       A01X+152429Y+154997X0150Y         S1      
317m2720            VIA   -    MD0080PA01X+146919Y+113967X0160Y         S0      
327m2720            U25   -DA24       A01X+146735Y+113862X0177Y    R180 S1      
317m2721            VIA   -    MD0080PA01X+152162Y+154997X0160Y         S0      
327m2721            U6013 -AH29       A01X+151957Y+154997X0150Y         S1      
327m2721            U25   -DC24       A01X+146735Y+114500X0177Y    R180 S1      
317m2721            VIA   -    MD0080PA01X+146919Y+114605X0160Y         S0      
317m2722            VIA   -    MD0080PA01X+151690Y+154997X0160Y         S0      
317m2722            VIA   -    MD0080PA01X+146919Y+113329X0160Y         S0      
327m2722            U25   -CW24       A01X+146735Y+113224X0177Y    R180 S1      
327m2722            U6013 -AR29       A01X+151484Y+154997X0150Y         S1      
327m2723            C851  -1          A01X+162966Y+149300X0120Y0150R270 S1      
327m2723            U6012 -BU35       A01X+162813Y+154246X0100Y0130     S1      
327m2724            C853  -1          A01X+162296Y+150270X0120Y0150R270 S1      
327m2724            U6012 -CD35       A01X+162341Y+154246X0100Y0130     S1      
327m2725            C855  -1          A01X+161626Y+151240X0120Y0150R270 S1      
327m2725            U6012 -CL35       A01X+161868Y+154246X0100Y0130     S1      
327m2726            C857  -1          A01X+160286Y+149300X0120Y0150R270 S1      
327m2726            U6012 -CV35       A01X+161396Y+154246X0100Y0130     S1      
327m2727            C859  -1          A01X+159616Y+150270X0120Y0150R270 S1      
327m2727            U6012 -DE35       A01X+160924Y+154246X0100Y0130     S1      
327m2728            C861  -1          A01X+158946Y+151240X0120Y0150R270 S1      
327m2728            U6012 -DM35       A01X+160451Y+154246X0100Y0130     S1      
327m2729            C863  -1          A01X+157606Y+149300X0120Y0150R270 S1      
327m2729            U6012 -DW35       A01X+159979Y+154246X0100Y0130     S1      
327m2730            C865  -1          A01X+156936Y+150270X0120Y0150R270 S1      
327m2730            U6012 -EF35       A01X+159506Y+154246X0100Y0130     S1      
327m2731            C867  -1          A01X+157032Y+151309X0120Y0150R180 S1      
327m2731            U6012 -EL34       A01X+159152Y+154450X0120Y         S1      
327m2732            C839  -1          A01X+167363Y+152698X0120Y0150     S1      
327m2732            U6012 -R35        A01X+165648Y+154246X0100Y0130     S1      
327m2733            C841  -1          A01X+167363Y+151358X0120Y0150     S1      
327m2733            U6012 -AB35       A01X+165176Y+154246X0100Y0130     S1      
327m2734            C843  -1          A01X+166986Y+149300X0120Y0150R270 S1      
327m2734            U6012 -AJ35       A01X+164703Y+154246X0100Y0130     S1      
327m2735            C845  -1          A01X+165646Y+149300X0120Y0150R270 S1      
327m2735            U6012 -AT35       A01X+164231Y+154246X0100Y0130     S1      
327m2736            C847  -1          A01X+164976Y+150270X0120Y0150R270 S1      
327m2736            U6012 -BC35       A01X+163758Y+154246X0100Y0130     S1      
327m2737            C849  -1          A01X+164306Y+151240X0120Y0150R270 S1      
327m2737            U6012 -BK35       A01X+163286Y+154246X0100Y0130     S1      
327m2738            C869  -1          A01X+157032Y+153849X0120Y0150R180 S1      
327m2738            U6012 -EY35       A01X+158561Y+154246X0100Y0130     S1      
327m2739            C850  -1          A01X+163326Y+149300X0120Y0150R270 S1      
327m2739            U6012 -BR34       A01X+162931Y+154450X0120Y         S1      
327m2740            C852  -1          A01X+162656Y+150270X0120Y0150R270 S1      
327m2740            U6012 -CB34       A01X+162459Y+154450X0120Y         S1      
327m2741            C854  -1          A01X+161986Y+151240X0120Y0150R270 S1      
327m2741            U6012 -CJ34       A01X+161986Y+154450X0120Y         S1      
327m2742            C856  -1          A01X+160646Y+149300X0120Y0150R270 S1      
327m2742            U6012 -CT34       A01X+161514Y+154450X0120Y         S1      
327m2743            C858  -1          A01X+159976Y+150270X0120Y0150R270 S1      
327m2743            U6012 -DC34       A01X+161042Y+154450X0120Y         S1      
327m2744            C860  -1          A01X+159306Y+151240X0120Y0150R270 S1      
327m2744            U6012 -DK34       A01X+160569Y+154450X0120Y         S1      
327m2745            C862  -1          A01X+157966Y+149300X0120Y0150R270 S1      
327m2745            U6012 -DU34       A01X+160097Y+154450X0120Y         S1      
327m2746            C864  -1          A01X+157296Y+150270X0120Y0150R270 S1      
327m2746            U6012 -ED34       A01X+159624Y+154450X0120Y         S1      
327m2747            C866  -1          A01X+157032Y+151669X0120Y0150R180 S1      
327m2747            U6012 -EN35       A01X+159034Y+154246X0100Y0130     S1      
327m2748            C838  -1          A01X+167363Y+153058X0120Y0150     S1      
327m2748            U6012 -N34        A01X+165766Y+154450X0120Y         S1      
327m2749            C840  -1          A01X+167363Y+151718X0120Y0150     S1      
327m2749            U6012 -Y34        A01X+165294Y+154450X0120Y         S1      
327m2750            C842  -1          A01X+167346Y+149300X0120Y0150R270 S1      
327m2750            U6012 -AG34       A01X+164821Y+154450X0120Y         S1      
327m2751            C844  -1          A01X+166006Y+149300X0120Y0150R270 S1      
327m2751            U6012 -AP34       A01X+164349Y+154450X0120Y         S1      
327m2752            C846  -1          A01X+165336Y+150270X0120Y0150R270 S1      
327m2752            U6012 -BA34       A01X+163876Y+154450X0120Y         S1      
327m2753            C848  -1          A01X+164666Y+151240X0120Y0150R270 S1      
327m2753            U6012 -BH34       A01X+163404Y+154450X0120Y         S1      
327m2754            C868  -1          A01X+157032Y+153489X0120Y0150R180 S1      
327m2754            U6012 -EV34       A01X+158679Y+154450X0120Y         S1      
327m2755            C947  -1          A01X+136549Y+149300X0120Y0150R270 S1      
327m2755            U6011 -BU35       A01X+136396Y+154246X0100Y0130     S1      
327m2756            C949  -1          A01X+135879Y+150270X0120Y0150R270 S1      
327m2756            U6011 -CD35       A01X+135923Y+154246X0100Y0130     S1      
327m2757            C951  -1          A01X+135209Y+151240X0120Y0150R270 S1      
327m2757            U6011 -CL35       A01X+135451Y+154246X0100Y0130     S1      
327m2758            C953  -1          A01X+133869Y+149300X0120Y0150R270 S1      
327m2758            U6011 -CV35       A01X+134978Y+154246X0100Y0130     S1      
327m2759            C955  -1          A01X+133199Y+150270X0120Y0150R270 S1      
327m2759            U6011 -DE35       A01X+134506Y+154246X0100Y0130     S1      
327m2760            C957  -1          A01X+132529Y+151240X0120Y0150R270 S1      
327m2760            U6011 -DM35       A01X+134034Y+154246X0100Y0130     S1      
327m2761            C959  -1          A01X+131189Y+149300X0120Y0150R270 S1      
327m2761            U6011 -DW35       A01X+133561Y+154246X0100Y0130     S1      
327m2762            C961  -1          A01X+130519Y+150270X0120Y0150R270 S1      
327m2762            U6011 -EF35       A01X+133089Y+154246X0100Y0130     S1      
327m2763            C963  -1          A01X+130615Y+151309X0120Y0150R180 S1      
327m2763            U6011 -EL34       A01X+132734Y+154450X0120Y         S1      
327m2764            C935  -1          A01X+140946Y+152698X0120Y0150     S1      
327m2764            U6011 -R35        A01X+139230Y+154246X0100Y0130     S1      
327m2765            C937  -1          A01X+140946Y+151718X0120Y0150     S1      
327m2765            U6011 -Y34        A01X+138876Y+154450X0120Y         S1      
327m2766            C939  -1          A01X+140569Y+149300X0120Y0150R270 S1      
327m2766            U6011 -AJ35       A01X+138286Y+154246X0100Y0130     S1      
327m2767            C941  -1          A01X+139229Y+149300X0120Y0150R270 S1      
327m2767            U6011 -AT35       A01X+137813Y+154246X0100Y0130     S1      
327m2768            C943  -1          A01X+138559Y+150270X0120Y0150R270 S1      
327m2768            U6011 -BC35       A01X+137341Y+154246X0100Y0130     S1      
327m2769            C945  -1          A01X+137889Y+151240X0120Y0150R270 S1      
327m2769            U6011 -BK35       A01X+136868Y+154246X0100Y0130     S1      
327m2770            C965  -1          A01X+130615Y+153849X0120Y0150R180 S1      
327m2770            U6011 -EY35       A01X+132144Y+154246X0100Y0130     S1      
327m2771            C946  -1          A01X+136909Y+149300X0120Y0150R270 S1      
327m2771            U6011 -BR34       A01X+136514Y+154450X0120Y         S1      
327m2772            C948  -1          A01X+136239Y+150270X0120Y0150R270 S1      
327m2772            U6011 -CB34       A01X+136042Y+154450X0120Y         S1      
327m2773            C950  -1          A01X+135569Y+151240X0120Y0150R270 S1      
327m2773            U6011 -CJ34       A01X+135569Y+154450X0120Y         S1      
327m2774            C952  -1          A01X+134229Y+149300X0120Y0150R270 S1      
327m2774            U6011 -CT34       A01X+135097Y+154450X0120Y         S1      
327m2775            C954  -1          A01X+133559Y+150270X0120Y0150R270 S1      
327m2775            U6011 -DC34       A01X+134624Y+154450X0120Y         S1      
327m2776            C956  -1          A01X+132889Y+151240X0120Y0150R270 S1      
327m2776            U6011 -DK34       A01X+134152Y+154450X0120Y         S1      
327m2777            C958  -1          A01X+131549Y+149300X0120Y0150R270 S1      
327m2777            U6011 -DU34       A01X+133679Y+154450X0120Y         S1      
327m2778            C960  -1          A01X+130879Y+150270X0120Y0150R270 S1      
327m2778            U6011 -ED34       A01X+133207Y+154450X0120Y         S1      
327m2779            C962  -1          A01X+130615Y+151669X0120Y0150R180 S1      
327m2779            U6011 -EN35       A01X+132616Y+154246X0100Y0130     S1      
327m2780            C934  -1          A01X+140946Y+153058X0120Y0150     S1      
327m2780            U6011 -N34        A01X+139349Y+154450X0120Y         S1      
327m2781            C936  -1          A01X+140946Y+151358X0120Y0150     S1      
327m2781            U6011 -AB35       A01X+138758Y+154246X0100Y0130     S1      
327m2782            C938  -1          A01X+140929Y+149300X0120Y0150R270 S1      
327m2782            U6011 -AG34       A01X+138404Y+154450X0120Y         S1      
327m2783            C940  -1          A01X+139589Y+149300X0120Y0150R270 S1      
327m2783            U6011 -AP34       A01X+137931Y+154450X0120Y         S1      
327m2784            C942  -1          A01X+138919Y+150270X0120Y0150R270 S1      
327m2784            U6011 -BA34       A01X+137459Y+154450X0120Y         S1      
327m2785            C944  -1          A01X+138249Y+151240X0120Y0150R270 S1      
327m2785            U6011 -BH34       A01X+136986Y+154450X0120Y         S1      
327m2786            C964  -1          A01X+130615Y+153489X0120Y0150R180 S1      
327m2786            U6011 -EV34       A01X+132262Y+154450X0120Y         S1      
327m2787            C915  -1          A01X+123742Y+149300X0120Y0150R270 S1      
327m2787            U6010 -BU35       A01X+123590Y+154246X0100Y0130     S1      
327m2788            C917  -1          A01X+123072Y+150270X0120Y0150R270 S1      
327m2788            U6010 -CD35       A01X+123117Y+154246X0100Y0130     S1      
327m2789            C919  -1          A01X+122402Y+151240X0120Y0150R270 S1      
327m2789            U6010 -CL35       A01X+122645Y+154246X0100Y0130     S1      
327m2790            C921  -1          A01X+121062Y+149300X0120Y0150R270 S1      
327m2790            U6010 -CV35       A01X+122172Y+154246X0100Y0130     S1      
327m2791            C923  -1          A01X+120392Y+150270X0120Y0150R270 S1      
327m2791            U6010 -DE35       A01X+121700Y+154246X0100Y0130     S1      
327m2792            C925  -1          A01X+119722Y+151240X0120Y0150R270 S1      
327m2792            U6010 -DM35       A01X+121228Y+154246X0100Y0130     S1      
327m2793            C927  -1          A01X+118382Y+149300X0120Y0150R270 S1      
327m2793            U6010 -DW35       A01X+120755Y+154246X0100Y0130     S1      
327m2794            C929  -1          A01X+117712Y+150270X0120Y0150R270 S1      
327m2794            U6010 -EF35       A01X+120283Y+154246X0100Y0130     S1      
327m2795            C931  -1          A01X+117809Y+151309X0120Y0150R180 S1      
327m2795            U6010 -EL34       A01X+119928Y+154450X0120Y         S1      
327m2796            C903  -1          A01X+128139Y+152698X0120Y0150     S1      
327m2796            U6010 -R35        A01X+126424Y+154246X0100Y0130     S1      
327m2797            C905  -1          A01X+128139Y+151358X0120Y0150     S1      
327m2797            U6010 -AB35       A01X+125952Y+154246X0100Y0130     S1      
327m2798            C907  -1          A01X+128122Y+149300X0120Y0150R270 S1      
327m2798            U6010 -AG34       A01X+125598Y+154450X0120Y         S1      
327m2799            C909  -1          A01X+126422Y+149300X0120Y0150R270 S1      
327m2799            U6010 -AT35       A01X+125007Y+154246X0100Y0130     S1      
327m2800            C911  -1          A01X+125752Y+150270X0120Y0150R270 S1      
327m2800            U6010 -BC35       A01X+124534Y+154246X0100Y0130     S1      
327m2801            C913  -1          A01X+125082Y+151240X0120Y0150R270 S1      
327m2801            U6010 -BK35       A01X+124062Y+154246X0100Y0130     S1      
327m2802            C933  -1          A01X+117809Y+153849X0120Y0150R180 S1      
327m2802            U6010 -EY35       A01X+119338Y+154246X0100Y0130     S1      
327m2803            C914  -1          A01X+124102Y+149300X0120Y0150R270 S1      
327m2803            U6010 -BR34       A01X+123708Y+154450X0120Y         S1      
327m2804            C916  -1          A01X+123432Y+150270X0120Y0150R270 S1      
327m2804            U6010 -CB34       A01X+123235Y+154450X0120Y         S1      
327m2805            C918  -1          A01X+122762Y+151240X0120Y0150R270 S1      
327m2805            U6010 -CJ34       A01X+122763Y+154450X0120Y         S1      
327m2806            C920  -1          A01X+121422Y+149300X0120Y0150R270 S1      
327m2806            U6010 -CT34       A01X+122290Y+154450X0120Y         S1      
327m2807            C922  -1          A01X+120752Y+150270X0120Y0150R270 S1      
327m2807            U6010 -DC34       A01X+121818Y+154450X0120Y         S1      
327m2808            C924  -1          A01X+120082Y+151240X0120Y0150R270 S1      
327m2808            U6010 -DK34       A01X+121346Y+154450X0120Y         S1      
327m2809            C926  -1          A01X+118742Y+149300X0120Y0150R270 S1      
327m2809            U6010 -DU34       A01X+120873Y+154450X0120Y         S1      
327m2810            C928  -1          A01X+118072Y+150270X0120Y0150R270 S1      
327m2810            U6010 -ED34       A01X+120401Y+154450X0120Y         S1      
327m2811            C930  -1          A01X+117809Y+151669X0120Y0150R180 S1      
327m2811            U6010 -EN35       A01X+119810Y+154246X0100Y0130     S1      
327m2812            C902  -1          A01X+128139Y+153058X0120Y0150     S1      
327m2812            U6010 -N34        A01X+126542Y+154450X0120Y         S1      
327m2813            C904  -1          A01X+128139Y+151718X0120Y0150     S1      
327m2813            U6010 -Y34        A01X+126070Y+154450X0120Y         S1      
327m2814            C906  -1          A01X+127762Y+149300X0120Y0150R270 S1      
327m2814            U6010 -AJ35       A01X+125479Y+154246X0100Y0130     S1      
327m2815            C908  -1          A01X+126782Y+149300X0120Y0150R270 S1      
327m2815            U6010 -AP34       A01X+125125Y+154450X0120Y         S1      
327m2816            C910  -1          A01X+126112Y+150270X0120Y0150R270 S1      
327m2816            U6010 -BA34       A01X+124653Y+154450X0120Y         S1      
327m2817            C912  -1          A01X+125442Y+151240X0120Y0150R270 S1      
327m2817            U6010 -BH34       A01X+124180Y+154450X0120Y         S1      
327m2818            C932  -1          A01X+117809Y+153489X0120Y0150R180 S1      
327m2818            U6010 -EV34       A01X+119456Y+154450X0120Y         S1      
327m2819            C1793 -1          A01X+160506Y+006234X0120Y0150R090 S1      
327m2819            J38   -B47        A01X+159467Y+004437X0150Y0570R180 S1      
327m2820            C44   -1          A01X+161606Y+006834X0120Y0150R090 S1      
327m2820            J38   -B44        A01X+160176Y+004437X0150Y0570R180 S1      
327m2821            C1565 -1          A01X+162706Y+006234X0120Y0150R090 S1      
327m2821            J38   -B39        A01X+163054Y+004437X0150Y0570R180 S1      
327m2822            C47   -1          A01X+163927Y+006834X0120Y0150R090 S1      
327m2822            J38   -B36        A01X+163762Y+004437X0150Y0570R180 S1      
327m2823            C1569 -1          A01X+165027Y+006234X0120Y0150R090 S1      
327m2823            J38   -B33        A01X+164471Y+004437X0150Y0570R180 S1      
327m2824            C1571 -1          A01X+166127Y+006834X0120Y0150R090 S1      
327m2824            J38   -B30        A01X+165180Y+004437X0150Y0570R180 S1      
327m2825            C1573 -1          A01X+167227Y+006234X0120Y0150R090 S1      
327m2825            J38   -B26        A01X+167467Y+004437X0150Y0570R180 S1      
327m2826            C1575 -1          A01X+168340Y+006834X0120Y0150R090 S1      
327m2826            J38   -B23        A01X+168176Y+004437X0150Y0570R180 S1      
327m2827            C1577 -1          A01X+169440Y+006234X0120Y0150R090 S1      
327m2827            J38   -B20        A01X+168885Y+004437X0150Y0570R180 S1      
327m2828            C1549 -1          A01X+153906Y+006234X0120Y0150R090 S1      
327m2828            J38   -B65        A01X+155215Y+004437X0150Y0570R180 S1      
327m2829            C1792 -1          A01X+155006Y+006834X0120Y0150R090 S1      
327m2829            J38   -B62        A01X+155924Y+004437X0150Y0570R180 S1      
327m2830            C1553 -1          A01X+156106Y+006234X0120Y0150R090 S1      
327m2830            J38   -B59        A01X+156633Y+004437X0150Y0570R180 S1      
327m2831            C1555 -1          A01X+157206Y+006834X0120Y0150R090 S1      
327m2831            J38   -B56        A01X+157341Y+004437X0150Y0570R180 S1      
327m2832            C1557 -1          A01X+158306Y+006234X0120Y0150R090 S1      
327m2832            J38   -B53        A01X+158050Y+004437X0150Y0570R180 S1      
327m2833            C1559 -1          A01X+159406Y+006834X0120Y0150R090 S1      
327m2833            J38   -B50        A01X+158759Y+004437X0150Y0570R180 S1      
327m2834            C1579 -1          A01X+170540Y+006834X0120Y0150R090 S1      
327m2834            J38   -B17        A01X+169593Y+004437X0150Y0570R180 S1      
327m2835            C1560 -1          A01X+160146Y+006234X0120Y0150R090 S1      
327m2835            J38   -B48        A01X+159231Y+004437X0150Y0570R180 S1      
327m2836            C1794 -1          A01X+161246Y+006834X0120Y0150R090 S1      
327m2836            J38   -B45        A01X+159940Y+004437X0150Y0570R180 S1      
327m2837            C46   -1          A01X+162346Y+006234X0120Y0150R090 S1      
327m2837            J38   -B40        A01X+162818Y+004437X0150Y0570R180 S1      
327m2838            C1566 -1          A01X+163567Y+006834X0120Y0150R090 S1      
327m2838            J38   -B37        A01X+163526Y+004437X0150Y0570R180 S1      
327m2839            C1568 -1          A01X+164667Y+006234X0120Y0150R090 S1      
327m2839            J38   -B34        A01X+164235Y+004437X0150Y0570R180 S1      
327m2840            C1570 -1          A01X+165767Y+006834X0120Y0150R090 S1      
327m2840            J38   -B31        A01X+164944Y+004437X0150Y0570R180 S1      
327m2841            C1572 -1          A01X+166867Y+006234X0120Y0150R090 S1      
327m2841            J38   -B27        A01X+167231Y+004437X0150Y0570R180 S1      
327m2842            C1574 -1          A01X+167980Y+006834X0120Y0150R090 S1      
327m2842            J38   -B24        A01X+167940Y+004437X0150Y0570R180 S1      
327m2843            C1576 -1          A01X+169080Y+006234X0120Y0150R090 S1      
327m2843            J38   -B21        A01X+168648Y+004437X0150Y0570R180 S1      
327m2844            C1548 -1          A01X+153546Y+006234X0120Y0150R090 S1      
327m2844            J38   -B66        A01X+154979Y+004437X0150Y0570R180 S1      
327m2845            C1550 -1          A01X+154646Y+006834X0120Y0150R090 S1      
327m2845            J38   -B63        A01X+155688Y+004437X0150Y0570R180 S1      
327m2846            C1552 -1          A01X+155746Y+006234X0120Y0150R090 S1      
327m2846            J38   -B60        A01X+156396Y+004437X0150Y0570R180 S1      
327m2847            C41   -1          A01X+156846Y+006834X0120Y0150R090 S1      
327m2847            J38   -B57        A01X+157105Y+004437X0150Y0570R180 S1      
327m2848            C1556 -1          A01X+157946Y+006234X0120Y0150R090 S1      
327m2848            J38   -B54        A01X+157814Y+004437X0150Y0570R180 S1      
327m2849            C1558 -1          A01X+159046Y+006834X0120Y0150R090 S1      
327m2849            J38   -B51        A01X+158522Y+004437X0150Y0570R180 S1      
327m2850            C1578 -1          A01X+170180Y+006834X0120Y0150R090 S1      
327m2850            J38   -B18        A01X+169357Y+004437X0150Y0570R180 S1      
317m2851            VIA   -    MD0100PA00X+169844Y+146659X0200Y         S0      
317m2851            VIA   -    MD0100PA00X+176427Y+146008X0200Y         S0      
317m2851            VIA   -    M      A01X+178626Y+037906X0200Y         S2      
017m2851            VIA   -    M      A18X+178626Y+037906X0260Y         S2      
017m2851                  -    MD0100PA00X+178626Y+037906                       
327m2851            R4567 -1          A01X+127569Y+015403X0198Y0197R180 S1      
317m2851            VIA   -    MD0100PA00X+127805Y+015291X0200Y         S0      
317m2851            VIA   -    MD0100PA00X+107717Y+167669X0200Y         S0      
317m2851            J45   -A3   D0402PA00X+091878Y+171489X0657Y    R270 S3      
317m2851            VIA   -    MD0100PA00X+107703Y+145150X0200Y         S0      
327m2852            C2035 -1          A18X+005754Y+040007X0198Y0197R090 S2      
327m2852            C2031 -1          A18X+005374Y+040004X0198Y0197R090 S2      
327m2852            U268  -27         A01X+006487Y+039424X0100Y0290R270 S1      
317m2852            VIA   -    MD0100PA00X+006802Y+039522X0200Y         S0      
327m2852            U268  -28         A01X+006487Y+039621X0100Y0290R270 S1      
327m2852            C2038 -1          A18X+006539Y+039308X0198Y0197     S2      
327m2852            U268  -5          A01X+005341Y+039980X0100Y0290     S1      
317m2852            VIA   -    MD0100PA00X+005341Y+040286X0200Y         S0      
327m2852            C2033 -1          A18X+004568Y+039341X0198Y0197R180 S2      
317m2852            VIA   -    MD0100PA00X+004193Y+039565X0200Y         S0      
327m2852            U268  -9          A01X+004588Y+039424X0100Y0290R270 S1      
327m2852            R3655 -2          A18X+007417Y+038477X0198Y0197R270 S2      
327m2852            C2040 -1          A18X+007000Y+038481X0198Y0197R090 S2      
327m2852            VIA   -           A18X+007150Y+039081X0260Y         S2      
327m2852            C2039 -1          A18X+006540Y+038470X0198Y0197R090 S2      
327m2852            C2032 -1          A18X+006539Y+038846X0198Y0197     S2      
327m2852            C2034 -1          A18X+004552Y+038699X0198Y0197R180 S2      
317m2852            VIA   -    MD0100PA00X+004302Y+038294X0200Y         S0      
327m2852            U268  -14         A01X+004588Y+038440X0100Y0290R270 S1      
327m2852            R3662 -1          A01X+006768Y+036334X0198Y0197R090 S1      
317m2852            VIA   -    MD0100PA00X+006768Y+036070X0200Y         S0      
317m2853            VIA   -    MD0100PA18X+015494Y+162775X0200Y         S0      
327m2853            U26   -C41        A01X+043082Y+088067X0177Y    R180 S1      
317m2853            VIA   -    MD0100PA01X+038500Y+081353X0200Y         S0      
327m2853            C2073 -2          A18X+017276Y+162871X0120Y0150     S2      
317m2854            VIA   -    MD0100PA18X+016374Y+163197X0200Y         S0      
327m2854            C2075 -2          A18X+020263Y+163815X0120Y0150     S2      
327m2854            U26   -C44        A01X+041972Y+088067X0177Y    R180 S1      
317m2854            VIA   -    MD0100PA01X+037200Y+084303X0200Y         S0      
317m2855            VIA   -    MD0100PA18X+015494Y+162435X0200Y         S0      
327m2855            U26   -C42        A01X+042712Y+088067X0177Y    R180 S1      
317m2855            VIA   -    MD0100PA01X+038500Y+081693X0200Y         S0      
327m2855            C2074 -2          A18X+017276Y+162541X0120Y0150     S2      
317m2856            VIA   -    MD0100PA18X+016374Y+163537X0200Y         S0      
327m2856            C2076 -2          A18X+020263Y+164145X0120Y0150     S2      
327m2856            U26   -C45        A01X+041602Y+088067X0177Y    R180 S1      
317m2856            VIA   -    MD0100PA01X+037200Y+084643X0200Y         S0      
317m2857            VIA   -    MD0100P   X+005088Y+141896X0000Y0000     S0      
317m2857            J112  -P7   D0142PA01X+027815Y+166335X0302Y    R180 S3      
317m2857            VIA   -    MD0100PA01X+037200Y+082293X0200Y         S0      
327m2857            U26   -E41        A01X+043082Y+088705X0177Y    R180 S1      
317m2858            VIA   -    MD0100P   X+005835Y+140973X0000Y0000     S0      
327m2858            U26   -E44        A01X+041972Y+088705X0177Y    R180 S1      
317m2858            VIA   -    MD0100PA01X+037200Y+083520X0200Y         S0      
317m2858            J112  -O8   D0142PA01X+028602Y+166728X0302Y    R180 S3      
317m2859            VIA   -    MD0100P   X+005088Y+141556X0000Y0000     S0      
317m2859            J112  -O7   D0142PA01X+027815Y+166807X0302Y    R180 S3      
317m2859            VIA   -    MD0100PA01X+037200Y+081953X0200Y         S0      
327m2859            U26   -E40        A01X+043452Y+088705X0177Y    R180 S1      
317m2860            VIA   -    MD0100P   X+005835Y+140633X0000Y0000     S0      
327m2860            U26   -E43        A01X+042342Y+088705X0177Y    R180 S1      
317m2860            VIA   -    MD0100PA01X+037200Y+083180X0200Y         S0      
317m2860            J112  -N8   D0142PA01X+028602Y+167201X0302Y    R180 S3      
317m2861            VIA   -    MD0080PA01X+041906Y+115243X0160Y         S0      
317m2861            VIA   -    MD0100P   X+038863Y+123675X0000Y0000     S0      
327m2861            U26   -DE44       A01X+042090Y+115138X0177Y    R180 S1      
317m2861            VIA   -    MD0100P   X+003585Y+069982X0000Y0000     S0      
317m2861            VIA   -    MD0100PA01X+071670Y+020902X0200Y         S0      
327m2861            C1098 -2          A01X+071179Y+020892X0120Y0150     S1      
317m2862            VIA   -    MD0080PA01X+040796Y+115243X0160Y         S0      
317m2862            VIA   -    MD0100P   X+039097Y+121945X0000Y0000     S0      
327m2862            U26   -DE47       A01X+040980Y+115138X0177Y    R180 S1      
327m2862            C1100 -2          A01X+071179Y+019709X0120Y0150     S1      
317m2862            VIA   -    MD0100PA01X+071670Y+019719X0200Y         S0      
317m2862            VIA   -    MD0100P   X+003585Y+068892X0000Y0000     S0      
317m2863            VIA   -    MD0080PA01X+039686Y+115243X0160Y         S0      
317m2863            VIA   -    MD0100P   X+036873Y+121446X0000Y0000     S0      
327m2863            U26   -DE50       A01X+039869Y+115138X0177Y    R180 S1      
317m2863            VIA   -    MD0100P   X+003585Y+067801X0000Y0000     S0      
317m2863            VIA   -    MD0100PA01X+071670Y+018569X0200Y         S0      
327m2863            C9102 -2          A01X+071179Y+018559X0120Y0150     S1      
317m2864            VIA   -    MD0080PA01X+038575Y+115243X0160Y         S0      
317m2864            VIA   -    MD0100P   X+031328Y+121512X0000Y0000     S0      
327m2864            U26   -DE53       A01X+038759Y+115138X0177Y    R180 S1      
317m2864            VIA   -    MD0100P   X+003585Y+066704X0000Y0000     S0      
317m2864            VIA   -    MD0100PA01X+071670Y+017369X0200Y         S0      
327m2864            C9104 -2          A01X+071179Y+017359X0120Y0150     S1      
317m2865            VIA   -    MD0080PA01X+042276Y+115243X0160Y         S0      
317m2865            VIA   -    MD0100P   X+038863Y+124015X0000Y0000     S0      
327m2865            U26   -DE43       A01X+042460Y+115138X0177Y    R180 S1      
317m2865            VIA   -    MD0100P   X+003585Y+070322X0000Y0000     S0      
317m2865            VIA   -    MD0100PA01X+071670Y+021242X0200Y         S0      
327m2865            C1099 -2          A01X+071179Y+021252X0120Y0150     S1      
317m2866            VIA   -    MD0080PA01X+041166Y+115243X0160Y         S0      
317m2866            VIA   -    MD0100P   X+039097Y+122285X0000Y0000     S0      
327m2866            U26   -DE46       A01X+041350Y+115138X0177Y    R180 S1      
327m2866            C1101 -2          A01X+071179Y+020069X0120Y0150     S1      
317m2866            VIA   -    MD0100PA01X+071670Y+020059X0200Y         S0      
317m2866            VIA   -    MD0100P   X+003585Y+069232X0000Y0000     S0      
317m2867            VIA   -    MD0080PA01X+040056Y+115243X0160Y         S0      
317m2867            VIA   -    MD0100P   X+037213Y+121446X0000Y0000     S0      
327m2867            U26   -DE49       A01X+040239Y+115138X0177Y    R180 S1      
317m2867            VIA   -    MD0100P   X+003585Y+068141X0000Y0000     S0      
317m2867            VIA   -    MD0100PA01X+071670Y+018909X0200Y         S0      
327m2867            C9103 -2          A01X+071179Y+018919X0120Y0150     S1      
317m2868            VIA   -    MD0080PA01X+038945Y+115243X0160Y         S0      
317m2868            VIA   -    MD0100P   X+031328Y+121852X0000Y0000     S0      
327m2868            U26   -DE52       A01X+039129Y+115138X0177Y    R180 S1      
317m2868            VIA   -    MD0100P   X+003585Y+067044X0000Y0000     S0      
317m2868            VIA   -    MD0100PA01X+071670Y+017709X0200Y         S0      
327m2868            C9105 -2          A01X+071179Y+017719X0120Y0150     S1      
317m2869            VIA   -    MD0080PA01X+041536Y+115880X0160Y         S0      
327m2869            J59   -7          A01X+069728Y+021575X0110Y0630R270 S1      
317m2869            VIA   -    MD0100PA01X+070477Y+021503X0200Y         S0      
327m2869            U26   -DG45       A01X+041720Y+115776X0177Y    R180 S1      
317m2870            VIA   -    MD0080PA01X+040426Y+115880X0160Y         S0      
327m2870            J59   -19         A01X+069728Y+020394X0110Y0630R270 S1      
317m2870            VIA   -    MD0100PA01X+070477Y+020322X0200Y         S0      
327m2870            U26   -DG48       A01X+040609Y+115776X0177Y    R180 S1      
317m2871            VIA   -    MD0080PA01X+039315Y+115880X0160Y         S0      
327m2871            U26   -DG51       A01X+039499Y+115776X0177Y    R180 S1      
317m2871            VIA   -    MD0100PA01X+070477Y+019141X0200Y         S0      
327m2871            J59   -31         A01X+069728Y+019213X0110Y0630R270 S1      
317m2872            VIA   -    MD0080PA01X+038205Y+115880X0160Y         S0      
327m2872            U26   -DG54       A01X+038389Y+115776X0177Y    R180 S1      
327m2872            J59   -43         A01X+069728Y+018032X0110Y0630R270 S1      
317m2872            VIA   -    MD0100PA01X+070477Y+017960X0200Y         S0      
317m2873            VIA   -    MD0080PA01X+041906Y+115880X0160Y         S0      
317m2873            VIA   -    MD0100PA01X+070477Y+021843X0200Y         S0      
327m2873            J59   -5          A01X+069728Y+021772X0110Y0630R270 S1      
327m2873            U26   -DG44       A01X+042090Y+115776X0177Y    R180 S1      
317m2874            VIA   -    MD0080PA01X+040796Y+115880X0160Y         S0      
327m2874            J59   -17         A01X+069728Y+020590X0110Y0630R270 S1      
317m2874            VIA   -    MD0100PA01X+070477Y+020662X0200Y         S0      
327m2874            U26   -DG47       A01X+040980Y+115776X0177Y    R180 S1      
317m2875            VIA   -    MD0080PA01X+039686Y+115880X0160Y         S0      
327m2875            U26   -DG50       A01X+039869Y+115776X0177Y    R180 S1      
327m2875            J59   -29         A01X+069728Y+019409X0110Y0630R270 S1      
317m2875            VIA   -    MD0100PA01X+070477Y+019481X0200Y         S0      
317m2876            VIA   -    MD0080PA01X+038575Y+115880X0160Y         S0      
327m2876            U26   -DG53       A01X+038759Y+115776X0177Y    R180 S1      
317m2876            VIA   -    MD0100PA01X+070477Y+018300X0200Y         S0      
327m2876            J59   -41         A01X+069728Y+018228X0110Y0630R270 S1      
317m2877            VIA   -    MD0080PA01X+139520Y+115242X0160Y         S0      
317m2877            VIA   -    MD0100P   X+137068Y+122303X0000Y0000     S0      
317m2877            VIA   -    MD0100PA01X+100759Y+076495X0200Y         S0      
327m2877            C1989 -2          A01X+094260Y+022964X0120Y0150     S1      
327m2877            U25   -DE44       A01X+139704Y+115138X0177Y    R180 S1      
317m2878            VIA   -    MD0080PA01X+138410Y+115242X0160Y         S0      
317m2878            VIA   -    MD0100P   X+134606Y+121433X0000Y0000     S0      
327m2878            C1991 -2          A01X+094930Y+021895X0120Y0150     S1      
317m2878            VIA   -    MD0100PA01X+100759Y+077588X0200Y         S0      
327m2878            U25   -DE47       A01X+138594Y+115138X0177Y    R180 S1      
317m2879            VIA   -    MD0080PA01X+137300Y+115242X0160Y         S0      
317m2879            VIA   -    MD0100P   X+134204Y+120303X0000Y0000     S0      
327m2879            C1993 -2          A01X+094260Y+021190X0120Y0150     S1      
317m2879            VIA   -    MD0100PA01X+100759Y+078688X0200Y         S0      
327m2879            U25   -DE50       A01X+137484Y+115138X0177Y    R180 S1      
317m2880            VIA   -    MD0080PA01X+136189Y+115242X0160Y         S0      
317m2880            VIA   -    MD0100P   X+131566Y+119613X0000Y0000     S0      
317m2880            VIA   -    MD0100PA01X+100759Y+079788X0200Y         S0      
327m2880            C1995 -2          A01X+094260Y+020478X0120Y0150     S1      
327m2880            U25   -DE53       A01X+136373Y+115138X0177Y    R180 S1      
317m2881            VIA   -    MD0080PA01X+139890Y+115242X0160Y         S0      
317m2881            VIA   -    MD0100P   X+137068Y+122643X0000Y0000     S0      
317m2881            VIA   -    MD0100PA01X+100759Y+076155X0200Y         S0      
327m2881            C1990 -2          A01X+094260Y+022604X0120Y0150     S1      
327m2881            U25   -DE43       A01X+140074Y+115138X0177Y    R180 S1      
317m2882            VIA   -    MD0080PA01X+138780Y+115242X0160Y         S0      
317m2882            VIA   -    MD0100P   X+134606Y+121773X0000Y0000     S0      
327m2882            C1992 -2          A01X+094930Y+022255X0120Y0150     S1      
317m2882            VIA   -    MD0100PA01X+100759Y+077248X0200Y         S0      
327m2882            U25   -DE46       A01X+138964Y+115138X0177Y    R180 S1      
317m2883            VIA   -    MD0080PA01X+137670Y+115242X0160Y         S0      
317m2883            VIA   -    MD0100P   X+134204Y+120643X0000Y0000     S0      
317m2883            VIA   -    MD0100PA01X+100759Y+078348X0200Y         S0      
327m2883            C1994 -2          A01X+094260Y+021550X0120Y0150     S1      
327m2883            U25   -DE49       A01X+137854Y+115138X0177Y    R180 S1      
317m2884            VIA   -    MD0080PA01X+136560Y+115242X0160Y         S0      
317m2884            VIA   -    MD0100P   X+131566Y+119953X0000Y0000     S0      
317m2884            VIA   -    MD0100PA01X+100759Y+079448X0200Y         S0      
327m2884            C1996 -2          A01X+094260Y+020838X0120Y0150     S1      
327m2884            U25   -DE52       A01X+136743Y+115138X0177Y    R180 S1      
317m2885            VIA   -    MD0080PA01X+139150Y+115880X0160Y         S0      
317m2885            VIA   -    MD0100PA01X+100759Y+080882X0200Y         S0      
327m2885            J90   -A26        A01X+091339Y+022663X0150Y0500R090 S1      
327m2885            U25   -DG45       A01X+139334Y+115776X0177Y    R180 S1      
317m2886            VIA   -    MD0080PA01X+138040Y+115880X0160Y         S0      
317m2886            VIA   -    MD0100PA01X+100759Y+081975X0200Y         S0      
327m2886            J90   -A23        A01X+091339Y+021955X0150Y0500R090 S1      
327m2886            U25   -DG48       A01X+138224Y+115776X0177Y    R180 S1      
317m2887            VIA   -    MD0080PA01X+136930Y+115880X0160Y         S0      
317m2887            VIA   -    MD0100PA01X+100759Y+083075X0200Y         S0      
327m2887            J90   -A20        A01X+091339Y+021246X0150Y0500R090 S1      
327m2887            U25   -DG51       A01X+137113Y+115776X0177Y    R180 S1      
317m2888            VIA   -    MD0080PA01X+135819Y+115880X0160Y         S0      
327m2888            J90   -A17        A01X+091339Y+020537X0150Y0500R090 S1      
317m2888            VIA   -    MD0100PA01X+100759Y+084176X0200Y         S0      
327m2888            U25   -DG54       A01X+136003Y+115776X0177Y    R180 S1      
317m2889            VIA   -    MD0080PA01X+139520Y+115880X0160Y         S0      
317m2889            VIA   -    MD0100PA01X+100759Y+080542X0200Y         S0      
327m2889            J90   -A27        A01X+091339Y+022900X0150Y0500R090 S1      
327m2889            U25   -DG44       A01X+139704Y+115776X0177Y    R180 S1      
317m2890            VIA   -    MD0080PA01X+138410Y+115880X0160Y         S0      
317m2890            VIA   -    MD0100PA01X+100759Y+081635X0200Y         S0      
327m2890            J90   -A24        A01X+091339Y+022191X0150Y0500R090 S1      
327m2890            U25   -DG47       A01X+138594Y+115776X0177Y    R180 S1      
317m2891            VIA   -    MD0080PA01X+137300Y+115880X0160Y         S0      
327m2891            J90   -A21        A01X+091339Y+021482X0150Y0500R090 S1      
317m2891            VIA   -    MD0100PA01X+100759Y+082735X0200Y         S0      
327m2891            U25   -DG50       A01X+137484Y+115776X0177Y    R180 S1      
317m2892            VIA   -    MD0080PA01X+136189Y+115880X0160Y         S0      
317m2892            VIA   -    MD0100PA01X+100759Y+083836X0200Y         S0      
327m2892            J90   -A18        A01X+091339Y+020774X0150Y0500R090 S1      
327m2892            U25   -DG53       A01X+136373Y+115776X0177Y    R180 S1      
317m2893            VIA   -    MD0080PA00X+139772Y+088600X0160Y    R180 S0      
327m2893            J41   -A20        A01X+065932Y+005354X0150Y0570R180 S1      
327m2893            U25   -E43        A01X+139956Y+088705X0177Y    R180 S1      
317m2893            VIA   -    MD0100PA00X+086094Y+033086X0200Y         S0      
317m2894            VIA   -    MD0080PA00X+139402Y+088600X0160Y    R180 S0      
327m2894            J41   -A21        A01X+065696Y+005354X0150Y0570R180 S1      
327m2894            U25   -E44        A01X+139586Y+088705X0177Y    R180 S1      
317m2894            VIA   -    MD0100PA00X+086434Y+033086X0200Y         S0      
327m2895            VIA   -    M      A01X+082862Y+012570X0300Y    R090 S1      
327m2895            U265  -3          A01X+082450Y+013139X0090Y0240     S1      
327m2895            R4091 -2          A01X+083936Y+012066X0198Y0197R090 S1      
327m2895            R3561 -1   M      A01X+083511Y+012077X0198Y0197R270 S1      
317m2896            VIA   -    MD0100PA00X+072250Y+038316X0200Y    R090 S0      
327m2896            U18   -K5         A01X+072568Y+043249X0160Y    R090 S1      
317m2896            VIA   -    MD0100PA00X+072414Y+043096X0180Y    R090 S0      
317m2896            VIA   -    MD0100PA00X+065660Y+006054X0200Y         S0      
327m2896            R3561 -2          A01X+083511Y+011762X0198Y0197R270 S1      
317m2896            VIA   -    M      A01X+083512Y+011522X0200Y    R090 S2      
017m2896            VIA   -    M      A18X+083512Y+011522X0260Y    R090 S2      
017m2896                  -    MD0100PA00X+083512Y+011522                       
327m2897            R2530 -2          A01X+083475Y+056615X0198Y0197R270 S1      
327m2897            VIA   -    M      A01X+083475Y+056135X0300Y         S1      
327m2897            Q54   -D          A01X+082922Y+056135X0320Y0360R270 S1      
327m2898            U263  -3          A01X+028074Y+015382X0090Y0240R270 S1      
327m2898            VIA   -    M      A01X+027505Y+014871X0300Y         S1      
327m2898            R4092 -2          A01X+027012Y+014289X0198Y0197     S1      
327m2898            R3559 -1   M      A01X+027013Y+014720X0198Y0197R180 S1      
327m2899            R3563 -1   M      A01X+175114Y+037245X0198Y0197     S1      
327m2899            R4094 -2          A01X+176464Y+037245X0198Y0197R180 S1      
327m2899            U266  -3          A01X+174050Y+037137X0090Y0240R090 S1      
327m2899            VIA   -    M      A01X+174591Y+037352X0300Y         S1      
327NC_USB_HUB_SDA   VIA   -           A01X+007148Y+039944X0300Y         S1      
327NC_USB_HUB_SDA   U268  -26         A01X+006487Y+039227X0100Y0290R270 S1      
327NC_USB_HUB_DP4   VIA   -           A01X+004470Y+037526X0300Y         S1      
327NC_USB_HUB_DP4   U268  -16         A01X+005144Y+038080X0100Y0290     S1      
327NC_USB_HUB_DP3   U268  -13         A01X+004588Y+038636X0100Y0290R270 S1      
327NC_USB_HUB_DP2   VIA   -           A01X+003880Y+040656X0300Y         S1      
327NC_USB_HUB_DP2   U268  -7          A01X+004947Y+039980X0100Y0290     S1      
327NC_USB_HUB_DM4   VIA   -           A01X+003960Y+037856X0300Y         S1      
327NC_USB_HUB_DM4   U268  -15         A01X+004947Y+038080X0100Y0290     S1      
327NC_USB_HUB_DM3   U268  -12         A01X+004588Y+038833X0100Y0290R270 S1      
327NC_USB_HUB_DM2   VIA   -           A01X+004381Y+040814X0300Y         S1      
327NC_USB_HUB_DM2   U268  -6          A01X+005144Y+039980X0100Y0290     S1      
327m2900            U265  -16         A01X+081800Y+013394X0090Y0240R090 S1      
327m2900            VIA   -           A01X+081064Y+012826X0300Y    R090 S1      
327m2901            U265  -15         A01X+081800Y+013591X0090Y0240R090 S1      
327m2901            VIA   -           A01X+081081Y+013513X0300Y    R090 S1      
327m2902            U265  -14         A01X+081800Y+013788X0090Y0240R090 S1      
327m2902            VIA   -           A01X+081048Y+014176X0300Y    R090 S1      
327m2903            VIA   -           A01X+083332Y+014591X0300Y    R090 S1      
327m2903            U265  -8          A01X+082903Y+013985X0090Y0240R090 S1      
327m2904            VIA   -           A01X+083946Y+014604X0300Y    R090 S1      
327m2904            U265  -7          A01X+082903Y+013788X0090Y0240R090 S1      
327m2905            VIA   -           A01X+084619Y+014526X0300Y    R090 S1      
327m2905            U265  -6          A01X+082903Y+013591X0090Y0240R090 S1      
327m2906            VIA   -           A01X+060049Y+023282X0300Y         S1      
327m2906            U264  -16         A01X+060728Y+023039X0090Y0240     S1      
327m2907            VIA   -           A01X+060497Y+023551X0300Y         S1      
327m2907            U264  -15         A01X+060924Y+023039X0090Y0240     S1      
327m2908            VIA   -           A01X+061030Y+023538X0300Y         S1      
327m2908            U264  -14         A01X+061121Y+023039X0090Y0240     S1      
327m2909            VIA   -           A01X+062074Y+021517X0300Y         S1      
327m2909            U264  -8          A01X+061318Y+021936X0090Y0240     S1      
327m2910            VIA   -           A01X+061627Y+021296X0300Y         S1      
327m2910            U264  -7          A01X+061121Y+021936X0090Y0240     S1      
327m2911            VIA   -           A01X+061107Y+021406X0300Y         S1      
327m2911            U264  -6          A01X+060924Y+021936X0090Y0240     S1      
327m2912            U263  -16         A01X+028330Y+016032X0090Y0240     S1      
327m2912            VIA   -           A01X+027870Y+016510X0300Y         S1      
327m2913            U263  -15         A01X+028527Y+016032X0090Y0240     S1      
327m2913            VIA   -           A01X+028499Y+016802X0300Y         S1      
327m2914            U263  -14         A01X+028724Y+016032X0090Y0240     S1      
327m2914            VIA   -           A01X+029084Y+017008X0300Y         S1      
327m2915            U263  -8          A01X+028921Y+014929X0090Y0240     S1      
327m2915            VIA   -           A01X+029770Y+014416X0300Y         S1      
327m2916            U263  -7          A01X+028724Y+014929X0090Y0240     S1      
327m2916            VIA   -           A01X+029250Y+014402X0300Y         S1      
327m2917            U263  -6          A01X+028527Y+014929X0090Y0240     S1      
327m2917            VIA   -           A01X+028720Y+014396X0300Y         S1      
327m2918            U276  -16         A01X+084453Y+021990X0090Y0240     S1      
327m2918            VIA   -           A01X+083868Y+022475X0300Y         S1      
327m2919            U276  -15         A01X+084650Y+021990X0090Y0240     S1      
327m2919            VIA   -           A01X+083908Y+023325X0300Y         S1      
327m2920            VIA   -           A01X+084351Y+022896X0300Y         S1      
327m2920            U276  -14         A01X+084846Y+021990X0090Y0240     S1      
327m2921            U276  -8          A01X+085043Y+020888X0090Y0240     S1      
327m2921            VIA   -           A01X+085540Y+020477X0300Y         S1      
327m2922            U276  -7          A01X+084846Y+020888X0090Y0240     S1      
327m2922            VIA   -           A01X+085334Y+019993X0300Y         S1      
327m2923            U276  -6          A01X+084650Y+020888X0090Y0240     S1      
327m2923            VIA   -           A01X+084932Y+019653X0300Y         S1      
327m2924            U266  -16         A01X+173794Y+036487X0090Y0240R180 S1      
327m2924            VIA   -           A01X+174549Y+035700X0300Y         S1      
327m2925            U266  -15         A01X+173598Y+036487X0090Y0240R180 S1      
327m2925            VIA   -           A01X+173848Y+035808X0300Y         S1      
327m2926            U266  -14         A01X+173401Y+036487X0090Y0240R180 S1      
327m2926            VIA   -           A01X+173147Y+035802X0300Y         S1      
327m2927            U266  -8          A01X+173204Y+037590X0090Y0240R180 S1      
327m2927            VIA   -           A01X+172886Y+038703X0300Y         S1      
327m2928            U266  -7          A01X+173401Y+037590X0090Y0240R180 S1      
327m2928            VIA   -           A01X+173587Y+038708X0300Y         S1      
327m2929            U266  -6          A01X+173598Y+037590X0090Y0240R180 S1      
327m2929            VIA   -           A01X+174277Y+038711X0300Y         S1      
327m2930            U192  -1          A18X+071077Y+165109X0140Y0560R090 S2      
327m2930            VIA   -    M      A18X+072152Y+165186X0260Y         S2      
327m2930            R2796 -2          A18X+072552Y+165300X0198Y0197     S2      
327MB_FRU_ADDR2     R713  -2   M      A01X+120300Y+046020X0198Y0197     S1      
327MB_FRU_ADDR2     R714  -1          A01X+119150Y+046020X0198Y0197R180 S1      
327MB_FRU_ADDR2     U64   -3          A01X+121787Y+046038X0350Y0500R270 S1      
327MB_FRU_ADDR2     VIA   -    M      A01X+120994Y+046038X0300Y         S1      
327MB_FRU_ADDR1     R717  -2   M      A01X+120306Y+046527X0198Y0197     S1      
327MB_FRU_ADDR1     R718  -1          A01X+119156Y+046527X0198Y0197R180 S1      
327MB_FRU_ADDR1     U64   -2          A01X+121787Y+046538X0350Y0500R270 S1      
327MB_FRU_ADDR1     VIA   -    M      A01X+120994Y+046538X0300Y         S1      
327MB_FRU_ADDR0     R721  -2   M      A01X+120314Y+047038X0198Y0197     S1      
327MB_FRU_ADDR0     R722  -1          A01X+119162Y+047039X0198Y0197R180 S1      
327MB_FRU_ADDR0     U64   -1          A01X+121787Y+047038X0350Y0500R270 S1      
327MB_FRU_ADDR0     VIA   -    M      A01X+120994Y+047038X0300Y         S1      
327m2931            U264  -3          A01X+060472Y+022389X0090Y0240R270 S1      
327m2931            VIA   -    M      A01X+059903Y+021978X0300Y         S1      
327m2931            R4090 -2          A01X+059410Y+020899X0198Y0197     S1      
327m2931            R3560 -1   M      A01X+059410Y+021328X0198Y0197R180 S1      
317m2932            VIA   -    M      A01X+058822Y+021408X0200Y         S2      
017m2932            VIA   -    M      A18X+058822Y+021408X0260Y         S2      
017m2932                  -    MD0100PA00X+058822Y+021408                       
327m2932            R3560 -2          A01X+059095Y+021328X0198Y0197R180 S1      
317m2932            VIA   -    MD0100PA00X+067435Y+021858X0200Y         S0      
327m2932            U18   -M1         A01X+073198Y+041989X0160Y    R090 S1      
317m2932            VIA   -    MD0100PA00X+073351Y+041836X0180Y    R090 S0      
327INA230_5_A1      U265  -1          A01X+082056Y+013139X0090Y0240     S1      
327INA230_5_A1      VIA   -    M      A01X+081412Y+012077X0300Y    R090 S1      
327INA230_5_A1      R3624 -2          A01X+082311Y+012077X0198Y0197R090 S1      
327INA230_5_A1      R3612 -2   M      A01X+081911Y+012077X0198Y0197R090 S1      
327INA230_5_A0      U265  -2          A01X+082253Y+013139X0090Y0240     S1      
327INA230_5_A0      VIA   -    M      A01X+082253Y+012570X0300Y    R090 S1      
327INA230_5_A0      R3613 -2          A01X+083111Y+012077X0198Y0197R090 S1      
327INA230_5_A0      R3622 -2   M      A01X+082711Y+012077X0198Y0197R090 S1      
327INA230_4_A1      U264  -1          A01X+060472Y+022783X0090Y0240R270 S1      
327INA230_4_A1      VIA   -    M      A01X+059410Y+023428X0300Y         S1      
327INA230_4_A1      R3623 -2          A01X+059410Y+022528X0198Y0197     S1      
327INA230_4_A1      R3610 -2   M      A01X+059410Y+022928X0198Y0197     S1      
327INA230_4_A0      U264  -2          A01X+060472Y+022586X0090Y0240R270 S1      
327INA230_4_A0      VIA   -    M      A01X+059903Y+022586X0300Y         S1      
327INA230_4_A0      R3621 -2          A01X+059410Y+021728X0198Y0197     S1      
327INA230_4_A0      R3611 -2   M      A01X+059410Y+022128X0198Y0197     S1      
327INA230_3_A1      U263  -1          A01X+028074Y+015776X0090Y0240R270 S1      
327INA230_3_A1      R3608 -2          A01X+027013Y+015920X0198Y0197     S1      
327INA230_3_A1      VIA   -    M      A01X+027500Y+015921X0300Y         S1      
327INA230_3_A0      U263  -2          A01X+028074Y+015579X0090Y0240R270 S1      
327INA230_3_A0      VIA   -    M      A01X+027500Y+015386X0300Y         S1      
327INA230_3_A0      R3609 -2   M      A01X+027013Y+015520X0198Y0197     S1      
327INA230_3_A0      R3620 -1          A01X+027013Y+015120X0198Y0197R180 S1      
327INA230_2_A1      U276  -1          A01X+084197Y+021734X0090Y0240R270 S1      
327INA230_2_A1      VIA   -    M      A01X+083492Y+022030X0300Y         S1      
327INA230_2_A1      R3763 -2          A01X+083372Y+022499X0198Y0197R270 S1      
327INA230_2_A0      R3764 -2          A18X+084264Y+022036X0198Y0197     S2      
327INA230_2_A0      R3751 -1   M      A18X+084172Y+021594X0198Y0197R090 S2      
327INA230_2_A0      U276  -2          A01X+084197Y+021538X0090Y0240R270 S1      
317INA230_2_A0      VIA   -    M      A01X+083716Y+021821X0200Y         S2      
017INA230_2_A0      VIA   -    M      A18X+083716Y+021821X0260Y         S2      
017INA230_2_A0            -    MD0100PA00X+083716Y+021821                       
327INA230_1_A1      R3616 -2          A01X+176485Y+036415X0198Y0197R180 S1      
327INA230_1_A1      R3628 -2   M      A01X+175101Y+036405X0198Y0197R180 S1      
327INA230_1_A1      U266  -1          A01X+174050Y+036743X0090Y0240R090 S1      
327INA230_1_A1      VIA   -    M      A01X+174591Y+036311X0300Y         S1      
327INA230_1_A0      R3627 -2   M      A01X+175101Y+036805X0198Y0197R180 S1      
327INA230_1_A0      R3617 -2          A01X+176485Y+036815X0198Y0197R180 S1      
327INA230_1_A0      U266  -2          A01X+174050Y+036940X0090Y0240R090 S1      
327INA230_1_A0      VIA   -    M      A01X+174612Y+036813X0300Y         S1      
317m2933            J45   -C3   D0402PA00X+091878Y+169489X0657Y    R270 S3      
327m2933            VIA   -    M      A18X+092380Y+167094X0260Y         S2      
327m2933            R2802 -1          A18X+092780Y+166634X0198Y0197R090 S2      
327m2933            C65   -1   M      A18X+092380Y+166634X0198Y0197R090 S2      
327m2934            VIA   -    M      A01X+111936Y+172411X0300Y    R270 S1      
327m2934            R4553 -2          A01X+111936Y+171931X0198Y0197R090 S1      
327m2934            Q145  -5          A01X+111450Y+172155X0170Y0200R090 S1      
327m2934            Q145  -6   M      A01X+111450Y+172411X0170Y0200R090 S1      
327m2935            Q145  -3          A01X+110702Y+171899X0170Y0200R090 S1      
327m2935            R4554 -2   M      A01X+109851Y+171899X0198Y0197R090 S1      
327m2935            C70   -1   M      A01X+109451Y+171899X0198Y0197R270 S1      
317m2935            VIA   -    M      A01X+108903Y+171784X0200Y         S2      
017m2935            VIA   -    M      A18X+108903Y+171784X0260Y         S2      
017m2935                  -    MD0100PA00X+108903Y+171784                       
317m2935            VIA   -    MD0100PA00X+081311Y+045934X0200Y    R180 S0      
327m2935            R4557 -1          A01X+080951Y+045934X0198Y0197R180 S1      
317m2935            VIA   -    MD0100PA00X+148440Y+048758X0200Y         S0      
317HPDB_HSC_PWRGD   VIA   -    MD0100PA00X+092780Y+166076X0200Y         S0      
317HPDB_HSC_PWRGD   VIA   -    M      A01X+108903Y+172284X0200Y         S2      
017HPDB_HSC_PWRGD   VIA   -    M      A18X+108903Y+172284X0260Y         S2      
017HPDB_HSC_PWRGD         -    MD0100PA00X+108903Y+172284                       
327HPDB_HSC_PWRGD   R4552 -1   M      A01X+109451Y+172284X0198Y0197R090 S1      
327HPDB_HSC_PWRGD   R4551 -2   M      A01X+109851Y+172284X0198Y0197R270 S1      
327HPDB_HSC_PWRGD   Q145  -2          A01X+110702Y+172155X0170Y0200R090 S1      
327HPDB_HSC_PWRGD   R2802 -2          A18X+092780Y+166319X0198Y0197R090 S2      
327GPU_PRSNT_R      VIA   -    M      A01X+075777Y+163608X0300Y    R270 S1      
327GPU_PRSNT_R      R3770 -2          A01X+076177Y+163136X0198Y0197R090 S1      
327GPU_PRSNT_R      U278  -2          A01X+075777Y+164156X0220Y0320     S1      
327m2936            R4211 -2          A01X+145050Y+162058X0198Y0197R090 S1      
317m2936            VIA   -    MD0100PA00X+072350Y+036086X0200Y         S0      
317m2936            VIA   -    MD0100PA00X+081868Y+035640X0200Y         S0      
327m2936            R4209 -2   M      A01X+112981Y+005265X0198Y0197     S1      
327m2936            R4214 -1          A01X+113383Y+005260X0198Y0197     S1      
317m2936            VIA   -    MD0100PA00X+112483Y+005680X0200Y         S0      
327m2936            R6074 -1          A01X+072350Y+036329X0198Y0197R090 S1      
317m2936            VIA   -    MD0100PA00X+063081Y+012209X0200Y         S0      
317m2936            VIA   -    MD0100PA00X+041702Y+005476X0200Y         S0      
327m2936            R4212 -1          A01X+041942Y+005994X0198Y0197     S1      
327m2936            R4208 -2   M      A01X+041942Y+005476X0198Y0197R180 S1      
317m2936            VIA   -    MD0100PA00X+087089Y+013187X0200Y         S0      
317m2936            VIA   -    MD0100PA00X+081673Y+062920X0200Y         S0      
317m2936            VIA   -    MD0100PA00X+086547Y+078308X0200Y         S0      
317m2936            VIA   -    MD0100PA00X+068011Y+155433X0200Y         S0      
317m2936            VIA   -    MD0100PA00X+042168Y+156531X0200Y         S0      
317m2936            VIA   -    M      A01X+040038Y+162150X0200Y         S2      
017m2936            VIA   -    M      A18X+040038Y+162150X0260Y         S2      
017m2936                  -    MD0100PA00X+040038Y+162150                       
327m2936            R4213 -1          A01X+039482Y+162414X0198Y0197R090 S1      
327m2936            R4210 -2   M      A01X+039900Y+162414X0198Y0197R270 S1      
327m2936            R4215 -1          A01X+145050Y+162692X0198Y0197R090 S1      
317m2936            VIA   -    MD0100PA00X+145050Y+162400X0200Y         S0      
317m2936            VIA   -    MD0100PA00X+115171Y+166366X0200Y         S0      
327FM_P5V_EN        R333  -1          A01X+058620Y+042795X0198Y0197R180 S1      
317FM_P5V_EN        VIA   -    M      A01X+058872Y+042795X0200Y    R090 S2      
017FM_P5V_EN        VIA   -    M      A18X+058872Y+042795X0260Y    R090 S2      
017FM_P5V_EN              -    MD0100PA00X+058872Y+042795                       
327FM_P5V_EN        U18   -T16        A01X+074458Y+046714X0160Y    R090 S1      
317FM_P5V_EN        VIA   -    MD0100PA00X+074611Y+046867X0180Y    R090 S0      
317FM_P5V_EN        VIA   -    MD0100PA00X+075265Y+050411X0200Y         S0      
317FM_P5V_EN        VIA   -    MD0100PA00X+062438Y+050376X0200Y         S0      
327m2937            VIA   -    M      A01X+081495Y+056509X0300Y         S1      
327m2937            Q54   -G          A01X+082135Y+056509X0320Y0360R270 S1      
327m2937            R2529 -2          A01X+080982Y+056501X0198Y0197R090 S1      
327m2938            VIA   -    M      A01X+083689Y+053722X0300Y         S1      
327m2938            U158  -G          A01X+082987Y+053613X0320Y0360R090 S1      
327m2938            R2531 -2          A01X+084190Y+054222X0198Y0197R270 S1      
327m2939            U158  -D          A01X+082199Y+053987X0320Y0360R090 S1      
327m2939            VIA   -    M      A01X+080922Y+055147X0300Y         S1      
327m2939            R2528 -2   M      A01X+081128Y+054145X0198Y0197     S1      
327m2939            R2529 -1          A01X+080982Y+056186X0198Y0197R090 S1      
327m2940            VIA   -    M      A01X+042755Y+006002X0300Y         S1      
327m2940            U273  -3          A01X+043526Y+006002X0240Y0520R270 S1      
327m2940            R4212 -2          A01X+042257Y+005994X0198Y0197     S1      
327m2941            U272  -3          A01X+039482Y+163415X0240Y0520     S1      
317m2941            VIA   -    M      A01X+039482Y+162971X0200Y    R090 S2      
017m2941            VIA   -    M      A18X+039482Y+162971X0260Y    R090 S2      
017m2941                  -    MD0100PA00X+039482Y+162971                       
327m2941            R4213 -2          A01X+039482Y+162729X0198Y0197R090 S1      
317m2942            J45   -D2   D0402PA00X+092878Y+168489X0657Y    R270 S3      
327m2942            VIA   -    M      A18X+093180Y+167094X0260Y         S2      
327m2942            R2906 -1          A18X+093580Y+166634X0198Y0197R090 S2      
327m2942            C67   -1   M      A18X+093180Y+166634X0198Y0197R090 S2      
327m2943            VIA   -    M      A01X+076151Y+165648X0300Y    R090 S1      
327m2943            U278  -4          A01X+076151Y+165101X0220Y0320     S1      
327m2943            R2948 -1   M      A01X+076203Y+166301X0198Y0197R090 S1      
327m2943            R2944 -1          A01X+075403Y+166301X0198Y0197R090 S1      
327m2943            R2946 -2   M      A01X+075803Y+166301X0198Y0197R270 S1      
317m2944            VIA   -    M      A01X+075403Y+166926X0200Y    R090 S2      
017m2944            VIA   -    M      A18X+075403Y+166926X0260Y    R090 S2      
017m2944                  -    MD0100PA00X+075403Y+166926                       
317m2944            VIA   -    MD0100PA00X+091599Y+166733X0200Y         S0      
327m2944            R2906 -2          A18X+093580Y+166319X0198Y0197R090 S2      
327m2944            R2944 -2          A01X+075403Y+166616X0198Y0197R090 S1      
317FM_GPU_HSC_EN    VIA   -    MD0100PA00X+082875Y+045934X0200Y         S0      
317FM_GPU_HSC_EN    VIA   -    MD0100PA00X+089238Y+046643X0200Y         S0      
327FM_GPU_HSC_EN    R2939 -1          A01X+082399Y+045934X0198Y0197R180 S1      
317FM_GPU_HSC_EN    VIA   -    MD0100PA00X+090315Y+082509X0200Y         S0      
327FM_GPU_HSC_EN    U278  -1          A01X+075403Y+164156X0220Y0320     S1      
327FM_GPU_HSC_EN    R2941 -1   M      A01X+075177Y+163136X0198Y0197R270 S1      
327FM_GPU_HSC_EN    R2940 -2          A01X+075777Y+163136X0198Y0197R090 S1      
317FM_GPU_HSC_EN    VIA   -    M      A01X+075377Y+163608X0200Y    R270 S2      
017FM_GPU_HSC_EN    VIA   -    M      A18X+075377Y+163608X0260Y    R270 S2      
017FM_GPU_HSC_EN          -    MD0100PA00X+075377Y+163608                       
327m2945            U271  -3          A01X+114849Y+005819X0240Y0520R270 S1      
327m2945            VIA   -    M      A01X+114190Y+005669X0300Y         S1      
327m2945            R4214 -2          A01X+113698Y+005260X0198Y0197     S1      
327m2946            VIA   -    M      A01X+145150Y+163350X0300Y         S1      
327m2946            U270  -3          A01X+145058Y+164034X0240Y0520     S1      
327m2946            R4215 -2          A01X+145050Y+163008X0198Y0197R090 S1      
317m2947            J45   -D1   D0402PA00X+093878Y+168489X0657Y    R270 S3      
327m2947            VIA   -    M      A18X+094780Y+167094X0260Y         S2      
327m2947            R2803 -1          A18X+095180Y+166634X0198Y0197R090 S2      
327m2947            C66   -1   M      A18X+094780Y+166634X0198Y0197R090 S2      
327FM_FAN_PWR_EN    R2803 -2          A18X+095180Y+166319X0198Y0197R090 S2      
317FM_FAN_PWR_EN    VIA   -    MD0100PA00X+095180Y+166076X0200Y         S0      
327FM_FAN_PWR_EN    R9000 -2          A18X+095180Y+165830X0198Y0197R270 S2      
317FM_FAN_PWR_EN    VIA   -    MD0100PA00X+093907Y+144822X0200Y         S0      
317FM_FAN_PWR_EN    VIA   -    MD0100PA00X+082222Y+075698X0200Y         S0      
317FM_FAN_PWR_EN    VIA   -    M      A01X+064485Y+049558X0200Y         S2      
017FM_FAN_PWR_EN    VIA   -    M      A18X+064485Y+049558X0260Y         S2      
017FM_FAN_PWR_EN          -    MD0100PA00X+064485Y+049558                       
317FM_FAN_PWR_EN    VIA   -    MD0100PA00X+073849Y+067914X0200Y         S0      
327FM_FAN_PWR_EN    U18   -D12        A01X+070678Y+045454X0160Y    R090 S1      
317FM_FAN_PWR_EN    VIA   -    MD0100PA00X+070524Y+045607X0180Y    R090 S0      
327m2948            R4093 -2          A18X+083750Y+022308X0198Y0197R090 S2      
327m2948            R3752 -1          A18X+083344Y+022314X0198Y0197R270 S2      
327m2948            U276  -3          A01X+084197Y+021341X0090Y0240R270 S1      
317m2948            VIA   -    M      A01X+083716Y+021321X0200Y         S2      
017m2948            VIA   -    M      A18X+083716Y+021321X0260Y         S2      
017m2948                  -    MD0100PA00X+083716Y+021321                       
327m2949            U26   -DJ16       A01X+052082Y+116414X0177Y    R180 S1      
317m2949            VIA   -    MD0100PA00X+052082Y+116737X0200Y         S0      
327m2949            R5103 -1          A18X+059173Y+123408X0198Y0197     S2      
327m2950            U26   -DJ17       A01X+051712Y+116414X0177Y    R180 S1      
317m2950            VIA   -    MD0100PA00X+051712Y+116737X0200Y         S0      
327m2950            R571  -1   M      A18X+058158Y+123408X0198Y0197R180 S2      
327m2950            C236  -1   M      A18X+058473Y+123808X0198Y0197     S2      
327m2950            Y4    -1          A18X+058279Y+125072X0480Y0590R090 S2      
327m2951            U26   -DJ13       A01X+053192Y+116414X0177Y    R180 S1      
327m2951            R575  -2          A18X+060620Y+123450X0198Y0197R090 S2      
317m2951            VIA   -    MD0100PA00X+053192Y+116737X0200Y         S0      
317m2952            VIA   -    MD0100PA00X+153692Y+124084X0200Y         S0      
327m2952            R573  -2          A18X+153551Y+123851X0198Y0197R270 S2      
327m2952            U26   -DJ14       A01X+052822Y+116414X0177Y    R180 S1      
317m2952            VIA   -    MD0100PA00X+052822Y+116737X0200Y         S0      
327m2952            R574  -2   M      A18X+060220Y+123450X0198Y0197R090 S2      
317m2952            VIA   -    MD0100PA00X+059662Y+124037X0200Y    R180 S0      
317m2952            VIA   -    MD0100PA00X+082825Y+126650X0200Y         S0      
317m2952            VIA   -    M      A01X+087723Y+144158X0200Y         S2      
017m2952            VIA   -    M      A18X+087723Y+144158X0260Y         S2      
017m2952                  -    MD0100PA00X+087723Y+144158                       
327m2953            Y5    -2          A18X+060908Y+125408X0400Y0710     S2      
327m2953            VIA   -    M      A18X+060767Y+124609X0260Y    R180 S2      
327m2953            C239  -1   M      A18X+061217Y+124586X0198Y0197R090 S2      
327m2953            R575  -1          A18X+060620Y+123765X0198Y0197R090 S2      
327m2953            R572  -2   M      A18X+060573Y+124158X0198Y0197R180 S2      
327m2954            Y5    -1          A18X+059924Y+125408X0400Y0710R180 S2      
327m2954            VIA   -    M      A18X+060258Y+124689X0260Y    R180 S2      
327m2954            C238  -1   M      A18X+059797Y+124706X0198Y0197R090 S2      
327m2954            R572  -1   M      A18X+060258Y+124158X0198Y0197R180 S2      
327m2954            R574  -1          A18X+060220Y+123765X0198Y0197R090 S2      
327m2955            U25   -DJ16       A01X+149696Y+116413X0177Y    R180 S1      
317m2955            VIA   -    MD0100PA00X+149696Y+116739X0200Y         S0      
327m2955            R5102 -1          A18X+156825Y+123416X0198Y0197     S2      
327m2956            U25   -DJ17       A01X+149326Y+116413X0177Y    R180 S1      
327m2956            R432  -1   M      A18X+155810Y+123416X0198Y0197R180 S2      
327m2956            C213  -1   M      A18X+156084Y+123766X0198Y0197     S2      
327m2956            Y2    -1          A18X+156013Y+124981X0480Y0590R090 S2      
317m2956            VIA   -    MD0100PA00X+149326Y+116739X0200Y         S0      
327m2957            U25   -DJ13       A01X+150806Y+116413X0177Y    R180 S1      
317m2957            VIA   -    MD0100PA00X+150806Y+116739X0200Y         S0      
327m2957            Y3    -2          A18X+158622Y+124771X0400Y0710     S2      
327m2957            R433  -2   M      A18X+157938Y+123537X0198Y0197R180 S2      
327m2957            C216  -1   M      A18X+158323Y+123987X0198Y0197R180 S2      
327m2958            U25   -DJ14       A01X+150436Y+116413X0177Y    R180 S1      
327m2958            Y3    -1          A18X+157638Y+124771X0400Y0710R180 S2      
327m2958            C215  -1   M      A18X+157938Y+123987X0198Y0197     S2      
327m2958            R433  -1   M      A18X+157623Y+123537X0198Y0197R180 S2      
317m2958            VIA   -    MD0100PA00X+150436Y+116739X0200Y         S0      
317m2959            VIA   -    MD0080PA00X+040678Y+087962X0160Y    R180 S0      
317m2959            VIA   -    MD0080PA00X+137552Y+088600X0160Y    R180 S0      
327m2959            U25   -E49        A01X+137735Y+088705X0177Y    R180 S1      
327m2959            U26   -C47        A01X+040861Y+088067X0177Y    R180 S1      
327m2959            VIA   -    M      A18X+057656Y+074514X0160Y0041R324 S2      
317m2960            VIA   -    MD0080PA00X+040308Y+087962X0160Y    R180 S0      
317m2960            VIA   -    MD0080PA00X+137182Y+088600X0160Y    R180 S0      
327m2960            U25   -E50        A01X+137365Y+088705X0177Y    R180 S1      
327m2960            U26   -C48        A01X+040491Y+088067X0177Y    R180 S1      
327m2960            VIA   -    M      A18X+053538Y+077286X0160Y0041R324 S2      
317m2961            VIA   -    MD0080PA00X+041048Y+088600X0160Y    R180 S0      
317m2961            VIA   -    MD0080PA00X+137182Y+087962X0160Y    R180 S0      
327m2961            U25   -C50        A01X+137365Y+088067X0177Y    R180 S1      
327m2961            U26   -E46        A01X+041232Y+088705X0177Y    R180 S1      
327m2961            VIA   -    M      A18X+124045Y+073378X0160Y0041R030 S2      
317m2962            VIA   -    MD0080PA00X+040678Y+088600X0160Y    R180 S0      
317m2962            VIA   -    MD0080PA00X+136812Y+087962X0160Y    R180 S0      
327m2962            U25   -C51        A01X+136995Y+088067X0177Y    R180 S1      
327m2962            U26   -E47        A01X+040861Y+088705X0177Y    R180 S1      
327m2962            VIA   -    M      A18X+127115Y+074988X0160Y0041R030 S2      
317m2963            VIA   -    MD0080PA00X+057077Y+116518X0160Y         S0      
327m2963            PC639 -2   M      A01X+063048Y+135711X0198Y0197     S1      
327m2963            PU54  -22         A01X+063318Y+136281X0070Y0240R180 S1      
317m2963            VIA   -    MD0100PA00X+063048Y+135311X0200Y         S0      
327m2963            U26   -DJ3        A01X+056893Y+116414X0177Y    R180 S1      
317m2963            VIA   -    MD0100PA00X+043690Y+128969X0200Y    R180 S0      
317m2963            VIA   -    MD0100PA00X+066260Y+130850X0200Y         S0      
327m2963            PR288 -1          A01X+067102Y+130800X0198Y0197     S1      
327m2963            TP13  -1   M      A01X+066610Y+130805X0300Y    R180 S1      
317m2963            VIA   -    MD0100PA00X+059499Y+128958X0200Y    R180 S0      
327m2963            PR226 -1          A01X+043433Y+128969X0198Y0197R180 S1      
317m2963            VIA   -    MD0100PA00X+011008Y+141050X0200Y         S0      
327m2963            PC358 -2   M      A01X+011008Y+141450X0198Y0197     S1      
327m2963            PU34  -26         A01X+011291Y+142218X0070Y0260R180 S1      
317m2964            VIA   -    MD0080PA00X+154691Y+116518X0160Y         S0      
327m2964            U25   -DJ3        A01X+154507Y+116413X0177Y    R180 S1      
317m2964            VIA   -    MD0100PA00X+162633Y+130809X0200Y         S0      
317m2964            VIA   -    MD0100PA00X+164106Y+140639X0200Y         S0      
327m2964            PU21  -22         A01X+164377Y+141609X0070Y0240R180 S1      
327m2964            PC194 -2   M      A01X+164106Y+141040X0198Y0197     S1      
327m2964            PR115 -1          A01X+163476Y+130687X0198Y0197     S1      
317m2964            VIA   -    MD0100PA00X+160414Y+127136X0200Y    R180 S0      
317m2964            VIA   -    MD0100PA00X+160842Y+133109X0200Y         S0      
317m2964            VIA   -    MD0100PA00X+141417Y+128619X0200Y    R180 S0      
327m2964            TP3   -1          A01X+141096Y+128075X0300Y    R180 S1      
327m2964            PR49  -1   M      A01X+141076Y+128576X0198Y0197R180 S1      
327m2964            PU12  -26         A01X+121391Y+140868X0070Y0260R180 S1      
327m2964            PC68  -2   M      A01X+121108Y+140100X0198Y0197     S1      
317m2964            VIA   -    MD0100PA00X+121108Y+139520X0200Y         S0      
317m2965            VIA   -    MD0080PA00X+038205Y+105676X0160Y         S0      
327m2965            PU34  -39         A01X+013132Y+142799X0070Y0260R270 S1      
327m2965            PC361 -2   M      A01X+014092Y+141750X0198Y0197R180 S1      
317m2965            VIA   -    MD0100PA00X+014200Y+141450X0200Y         S0      
327m2965            U26   -BR54       A01X+038389Y+105571X0177Y    R180 S1      
317m2965            VIA   -    MD0100PA00X+008302Y+131161X0200Y    R180 S0      
317m2965            VIA   -    MD0100PA00X+033678Y+119211X0200Y         S0      
327m2965            TP12  -1   M      A01X+007876Y+131219X0300Y    R180 S1      
327m2965            PR460 -1          A01X+008700Y+131162X0198Y0197     S1      
317m2966            VIA   -    MD0080PA00X+135819Y+105676X0160Y         S0      
327m2966            U25   -BR54       A01X+136003Y+105571X0177Y    R180 S1      
317m2966            VIA   -    MD0100PA00X+105517Y+131120X0200Y         S0      
327m2966            TP2   -1          A01X+105064Y+131115X0300Y         S1      
327m2966            PR50  -1          A01X+105757Y+131120X0198Y0197     S1      
327m2966            PU12  -39         A01X+123232Y+141449X0070Y0260R270 S1      
317m2966            VIA   -    MD0100PA00X+124430Y+140350X0200Y         S0      
327m2966            PC71  -2   M      A01X+123992Y+140650X0198Y0197R180 S1      
317m2967            VIA   -    MD0080PA00X+056959Y+087962X0160Y    R180 S0      
327m2967            U26   -C3         A01X+056775Y+088067X0177Y    R180 S1      
317m2967            VIA   -    MD0100PA00X+052307Y+085594X0200Y         S0      
317m2967            VIA   -    MD0100PA00X+052647Y+084943X0200Y         S0      
317m2967            VIA   -    MD0100PA00X+040754Y+058049X0200Y    R180 S0      
327m2967            PC245 -2   M      A18X+039766Y+058049X0198Y0197R270 S2      
327m2967            PU25  -39         A18X+038798Y+057543X0070Y0260R270 S2      
327m2967            PU25  -26         A18X+036957Y+058123X0070Y0260     S2      
327m2967            PC244 -2   M      A18X+036516Y+059048X0198Y0197R180 S2      
317m2967            VIA   -    MD0100PA00X+036516Y+059358X0200Y    R180 S0      
317m2967            VIA   -    MD0100PA00X+022416Y+071292X0200Y         S0      
327m2967            PR162 -1          A01X+023271Y+071160X0198Y0197     S1      
327m2967            PR164 -1          A01X+054731Y+065949X0198Y0197R180 S1      
327m2967            TP11  -1   M      A01X+055590Y+065760X0300Y         S1      
317m2967            VIA   -    MD0100PA00X+054996Y+065848X0200Y         S0      
317m2968            VIA   -    MD0080PA00X+154573Y+087962X0160Y    R180 S0      
327m2968            U25   -C3         A01X+154389Y+088067X0177Y    R180 S1      
317m2968            VIA   -    MD0100PA00X+149947Y+086332X0200Y         S0      
327m2968            PU42  -26         A18X+148267Y+057180X0070Y0260     S2      
327m2968            PC463 -2   M      A18X+147926Y+058166X0198Y0197R180 S2      
317m2968            VIA   -    MD0100PA00X+147826Y+058414X0200Y    R180 S0      
317m2968            VIA   -    MD0100PA00X+134026Y+067511X0200Y    R180 S0      
327m2968            PR295 -1          A01X+134318Y+067444X0198Y0197     S1      
327m2968            TP1   -1          A18X+166132Y+068909X0260Y         S2      
317m2968            VIA   -    MD0100PA00X+166238Y+069330X0200Y         S0      
327m2968            PR297 -1          A01X+165972Y+069233X0198Y0197R180 S1      
327m2968            PU42  -39         A18X+150108Y+056599X0070Y0260R270 S2      
327m2968            PC464 -2   M      A18X+151076Y+057105X0198Y0197R270 S2      
327m2969            PU34  -40         A01X+013132Y+142956X0070Y0260R270 S1      
327m2969            PR246 -2          A01X+014800Y+141758X0198Y0197R090 S1      
327m2969            PC361 -1   M      A01X+014408Y+141750X0198Y0197R180 S1      
317m2970            VIA   -    MD0080PA00X+038575Y+105676X0160Y         S0      
317m2970            VIA   -    MD0100PA00X+014500Y+141442X0200Y         S0      
327m2970            PR246 -1          A01X+014800Y+141442X0198Y0197R090 S1      
327m2970            U26   -BR53       A01X+038759Y+105571X0177Y    R180 S1      
317m2970            VIA   -    MD0100PA00X+008295Y+130761X0200Y    R180 S0      
317m2970            VIA   -    MD0100PA00X+033928Y+119211X0200Y         S0      
327m2970            TP15  -1   M      A01X+007876Y+130711X0300Y    R180 S1      
327m2970            PR227 -1          A01X+008698Y+130750X0198Y0197     S1      
327m2971            PR69  -2          A01X+124700Y+140658X0198Y0197R090 S1      
327m2971            PC71  -1   M      A01X+124308Y+140650X0198Y0197R180 S1      
327m2971            PU12  -40         A01X+123232Y+141606X0070Y0260R270 S1      
317m2972            VIA   -    MD0080PA00X+136189Y+105676X0160Y         S0      
327m2972            U25   -BR53       A01X+136373Y+105571X0177Y    R180 S1      
317m2972            VIA   -    MD0100PA00X+105517Y+130720X0200Y    R180 S0      
327m2972            TP5   -1          A01X+105064Y+130715X0300Y         S1      
327m2972            PR52  -1          A01X+105757Y+130720X0198Y0197     S1      
327m2972            PR69  -1          A01X+124700Y+140342X0198Y0197R090 S1      
317m2972            VIA   -    MD0100PA00X+124960Y+140342X0200Y         S0      
327m2973            PU25  -40         A18X+038798Y+057385X0070Y0260R270 S2      
327m2973            PC245 -1   M      A18X+039766Y+057734X0198Y0197R270 S2      
327m2973            PR174 -2          A18X+040158Y+057742X0198Y0197     S2      
317m2974            VIA   -    MD0080PA00X+057144Y+087644X0160Y    R180 S0      
327m2974            U26   -B3         A01X+056960Y+087748X0177Y    R180 S1      
317m2974            VIA   -    MD0100PA00X+052647Y+085193X0200Y         S0      
317m2974            VIA   -    MD0100PA00X+054996Y+066148X0200Y         S0      
327m2974            PR163 -2          A01X+054731Y+066369X0198Y0197     S1      
327m2974            TP20  -1   M      A01X+055590Y+066260X0300Y         S1      
317m2974            VIA   -    MD0100PA00X+040754Y+057742X0200Y    R180 S0      
327m2974            PR174 -1          A18X+040473Y+057742X0198Y0197     S2      
327m2975            PU42  -40         A18X+150108Y+056441X0070Y0260R270 S2      
327m2975            PC464 -1   M      A18X+151076Y+056790X0198Y0197R270 S2      
327m2975            PR307 -2          A18X+151468Y+056798X0198Y0197     S2      
327m2976            U25   -B3         A01X+154574Y+087748X0177Y    R180 S1      
327m2976            TP10  -1          A18X+166101Y+070024X0260Y         S2      
317m2976            VIA   -    MD0100PA00X+166238Y+069630X0200Y         S0      
327m2976            PR296 -2          A01X+165974Y+069632X0198Y0197     S1      
327m2976            PR307 -1          A18X+151783Y+056798X0198Y0197     S2      
327m2977            PU34  -25         A01X+011134Y+142218X0070Y0260R180 S1      
327m2977            PR245 -2          A01X+010700Y+141058X0198Y0197R090 S1      
327m2977            PC358 -1   M      A01X+010692Y+141450X0198Y0197     S1      
327m2978            U26   -DG3        A01X+056893Y+115776X0177Y    R180 S1      
327m2978            PR228 -1   M      A01X+043433Y+128569X0198Y0197R180 S1      
327m2978            TP16  -1          A01X+043558Y+127999X0300Y    R180 S1      
317m2978            VIA   -    MD0100PA00X+043690Y+128569X0200Y    R180 S0      
317m2978            VIA   -    MD0100PA00X+059499Y+128558X0200Y    R180 S0      
327m2978            PR245 -1          A01X+010700Y+140742X0198Y0197R090 S1      
317m2978            VIA   -    MD0100PA00X+011000Y+140742X0200Y         S0      
327m2979            PR68  -2          A01X+120800Y+139708X0198Y0197R090 S1      
327m2979            PC68  -1   M      A01X+120792Y+140100X0198Y0197     S1      
327m2979            PU12  -25         A01X+121234Y+140868X0070Y0260R180 S1      
317m2980            VIA   -    MD0100PA00X+141416Y+128956X0200Y    R180 S0      
327m2980            PR51  -1          A01X+141076Y+128976X0198Y0197R180 S1      
327m2980            PR68  -1          A01X+120800Y+139392X0198Y0197R090 S1      
327m2980            TP6   -1          A18X+120760Y+139400X0300Y    R180 S2      
317m2980            VIA   -    MD0100PA00X+121100Y+139212X0200Y         S0      
317m2980            VIA   -    MD0100PA00X+160842Y+133359X0200Y         S0      
327m2980            U25   -DG3        A01X+154507Y+115776X0177Y    R180 S1      
327m2981            PU25  -25         A18X+036800Y+058123X0070Y0260     S2      
327m2981            PC244 -1   M      A18X+036201Y+059048X0198Y0197R180 S2      
327m2981            PR173 -2          A18X+036207Y+059440X0198Y0197R090 S2      
317m2982            VIA   -    MD0080PA00X+057329Y+087962X0160Y    R180 S0      
327m2982            U26   -C2         A01X+057145Y+088067X0177Y    R180 S1      
317m2982            VIA   -    MD0100PA00X+052307Y+085344X0200Y         S0      
317m2982            VIA   -    MD0100PA00X+036516Y+059755X0200Y    R180 S0      
327m2982            PR173 -1          A18X+036207Y+059755X0198Y0197R090 S2      
327m2982            TP17  -1   M      A01X+022716Y+071592X0300Y         S1      
327m2982            PR161 -2          A01X+023267Y+071582X0198Y0197R180 S1      
317m2982            VIA   -    MD0100PA00X+022416Y+071592X0200Y    R180 S0      
327m2983            PU42  -25         A18X+148110Y+057180X0070Y0260     S2      
327m2983            PC463 -1   M      A18X+147611Y+058166X0198Y0197R180 S2      
327m2983            PR306 -2          A18X+147547Y+058526X0198Y0197R090 S2      
317m2984            VIA   -    MD0080PA00X+154943Y+087962X0160Y    R180 S0      
327m2984            U25   -C2         A01X+154759Y+088067X0177Y    R180 S1      
317m2984            VIA   -    MD0100PA00X+149947Y+086032X0200Y         S0      
327m2984            PR306 -1          A18X+147547Y+058841X0198Y0197R090 S2      
317m2984            VIA   -    MD0100PA00X+147826Y+058811X0200Y    R180 S0      
327m2984            PR294 -2          A01X+134322Y+067839X0198Y0197R180 S1      
327m2984            TP7   -1   M      A01X+133726Y+067876X0300Y         S1      
317m2984            VIA   -    MD0100PA00X+134026Y+067776X0200Y    R180 S0      
327m2985            TP19  -1   M      A01X+024362Y+076218X0300Y         S1      
327m2985            U26   -C74        A01X+030869Y+088067X0177Y    R180 S1      
317m2985            VIA   -    MD0100PA00X+020620Y+071407X0200Y         S0      
317m2985            VIA   -    MD0100PA00X+028942Y+057510X0200Y    R270 S0      
327m2985            PR400 -2          A01X+028687Y+057040X0198Y0197     S1      
327m2986            TP14  -1   M      A01X+024862Y+076218X0300Y         S1      
327m2986            U26   -B73        A01X+031054Y+087748X0177Y    R180 S1      
317m2986            VIA   -    MD0100PA00X+021020Y+071407X0200Y         S0      
317m2986            VIA   -    MD0100PA00X+027410Y+057470X0200Y    R090 S0      
327m2986            PR401 -2          A01X+027685Y+057040X0198Y0197R180 S1      
327m2987            U25   -C74        A01X+128484Y+088067X0177Y    R180 S1      
317m2987            VIA   -    MD0100PA00X+120092Y+060613X0200Y         S0      
327m2987            TP9   -1          A01X+119564Y+060597X0300Y    R180 S1      
327m2987            PR434 -2          A01X+129279Y+054525X0198Y0197R270 S1      
317m2987            VIA   -    MD0100PA00X+129358Y+054272X0200Y    R180 S0      
327m2988            U25   -B73        A01X+128668Y+087748X0177Y    R180 S1      
317m2988            VIA   -    MD0100PA00X+120092Y+060173X0200Y         S0      
327m2988            TP4   -1          A01X+119564Y+060187X0300Y    R180 S1      
327m2988            PR435 -2          A01X+129616Y+055902X0198Y0197R090 S1      
317m2988            VIA   -    MD0100PA00X+129494Y+056133X0200Y    R180 S0      
327m2989            PR384 -2          A01X+062670Y+135326X0198Y0197R090 S1      
327m2989            PC639 -1   M      A01X+062733Y+135711X0198Y0197     S1      
327m2989            PU54  -21         A01X+063161Y+136281X0070Y0240R180 S1      
317m2990            VIA   -    MD0080PA00X+057262Y+116199X0160Y         S0      
327m2990            PR384 -1          A01X+062670Y+135011X0198Y0197R090 S1      
317m2990            VIA   -    MD0100PA00X+063048Y+135011X0200Y    R180 S0      
327m2990            U26   -DH3        A01X+057078Y+116095X0177Y    R180 S1      
317m2990            VIA   -    MD0100PA00X+066260Y+131150X0200Y         S0      
327m2990            PR229 -2          A01X+067102Y+131250X0198Y0197R180 S1      
327m2990            TP18  -1   M      A01X+066610Y+131250X0300Y         S1      
327m2991            PR121 -2          A01X+163433Y+140952X0198Y0197R090 S1      
327m2991            PU21  -21         A01X+164220Y+141609X0070Y0240R180 S1      
327m2991            PC194 -1   M      A01X+163792Y+141040X0198Y0197     S1      
317m2992            VIA   -    MD0080PA00X+154876Y+116199X0160Y         S0      
327m2992            PR121 -1          A01X+163433Y+140636X0198Y0197R090 S1      
327m2992            U25   -DH3        A01X+154692Y+116094X0177Y    R180 S1      
317m2992            VIA   -    MD0100PA00X+162633Y+131109X0200Y         S0      
317m2992            VIA   -    MD0100PA00X+164106Y+140339X0200Y         S0      
327m2992            PR114 -2          A01X+163476Y+131187X0198Y0197R180 S1      
327m2992            TP8   -1   M      A01X+162983Y+131209X0300Y         S1      
317m2992            VIA   -    MD0100PA00X+160727Y+127198X0200Y    R180 S0      
327m2993            R3996 -1          A01X+077471Y+015803X0198Y0197     S1      
317m2993            VIA   -    M      A01X+077143Y+015803X0200Y         S2      
017m2993            VIA   -    M      A18X+077143Y+015803X0260Y         S2      
017m2993                  -    MD0100PA00X+077143Y+015803                       
317m2993            VIA   -    MD0100PA00X+062555Y+015268X0200Y         S0      
317m2993            VIA   -    MD0100PA00X+062660Y+036020X0200Y         S0      
327m2993            R6031 -1          A01X+064309Y+047390X0198Y0197     S1      
327VIRTUAL_RESEAT   J41   -OA14       A01X+072150Y+005354X0150Y0570R180 S1      
317VIRTUAL_RESEAT   VIA   -    M      A01X+071447Y+004667X0200Y         S2      
017VIRTUAL_RESEAT   VIA   -    M      A18X+071447Y+004667X0260Y         S2      
017VIRTUAL_RESEAT         -    MD0100PA00X+071447Y+004667                       
327VIRTUAL_RESEAT   U18   -F16        A01X+071308Y+046714X0160Y    R090 S1      
317VIRTUAL_RESEAT   VIA   -    MD0100PA00X+071154Y+046867X0180Y    R090 S0      
317UV_ALERT_N       VIA   -    M      A01X+064850Y+045386X0200Y         S2      
017UV_ALERT_N       VIA   -    M      A18X+064850Y+045386X0260Y         S2      
017UV_ALERT_N             -    MD0100PA00X+064850Y+045386                       
327UV_ALERT_N       R6038 -1          A01X+064608Y+045386X0198Y0197R180 S1      
327UV_ALERT_N       U18   -B10        A01X+070048Y+044824X0160Y    R090 S1      
317UV_ALERT_N       VIA   -    MD0100PA00X+069895Y+044670X0180Y    R090 S0      
317m2994            VIA   -    MD0100PA18X+020548Y+164873X0200Y         S0      
327m2994            R5234 -2          A18X+020126Y+164845X0198Y0197R180 S2      
317m2994            J112  -S1   D0142PA01X+023090Y+164917X0302Y    R180 S3      
317m2995            VIA   -    MD0100PA18X+020548Y+165213X0200Y         S0      
327m2995            R5236 -2          A18X+020126Y+165245X0198Y0197R180 S2      
317m2995            J112  -R1   D0142PA01X+023090Y+165390X0302Y    R180 S3      
327m2996            J41   -B50        A01X+055806Y+006516X0150Y0570R180 S1      
327m2996            R3651 -2          A01X+006019Y+041392X0180Y0200R270 S1      
327m2996            R2790 -1   M      A01X+006019Y+041392X0180Y0200R270 S1      
327m2996            R4419 -1          A01X+005616Y+041393X0198Y0197R090 S1      
317m2996            VIA   -    MD0100PA01X+006281Y+041600X0200Y    R090 S0      
317m2996            VIA   -    MD0100PA01X+055858Y+007144X0200Y    R180 S0      
327m2997            J41   -B51        A01X+055570Y+006516X0150Y0570R180 S1      
327m2997            R2791 -1          A01X+006553Y+041404X0180Y0200R270 S1      
327m2997            R3652 -2   M      A01X+006553Y+041404X0180Y0200R270 S1      
317m2997            VIA   -    MD0100PA01X+006281Y+041210X0200Y    R090 S0      
317m2997            VIA   -    MD0100PA01X+055518Y+007144X0200Y    R180 S0      
327m2997            R4420 -1          A01X+006952Y+041393X0198Y0197R090 S1      
317m2998            VIA   -    MD0080PA00X+145321Y+087324X0160Y    R180 S0      
327m2998            J41   -B53        A01X+055097Y+006516X0150Y0570R180 S1      
327m2998            U25   -A28        A01X+145137Y+087429X0177Y    R180 S1      
317m2998            VIA   -    MD0100PA00X+055172Y+007937X0200Y         S2      
317m2999            VIA   -    MD0080PA00X+144951Y+087324X0160Y    R180 S0      
327m2999            J41   -B54        A01X+054861Y+006516X0150Y0570R180 S1      
327m2999            U25   -A29        A01X+144767Y+087429X0177Y    R180 S1      
317m2999            VIA   -    MD0100PA00X+054782Y+007937X0200Y         S2      
317m3000            VIA   -    MD0080PA00X+131008Y+116518X0160Y         S0      
327m3000            U25   -DJ67       A01X+131192Y+116413X0177Y    R180 S1      
327m3000            R3178 -2          A01X+005462Y+006190X0198Y0197R090 S1      
317m3000            VIA   -    MD0100PA00X+087318Y+075047X0200Y         S2      
317m3001            VIA   -    MD0080PA00X+130823Y+116199X0160Y         S0      
327m3001            U25   -DH67       A01X+131007Y+116094X0177Y    R180 S1      
327m3001            R3177 -2          A01X+005030Y+006190X0198Y0197R090 S1      
317m3001            VIA   -    MD0100PA00X+086928Y+075047X0200Y         S2      
317m3002            VIA   -    MD0080PA00X+146061Y+087324X0160Y    R180 S0      
327m3002            U25   -A26        A01X+145877Y+087429X0177Y    R180 S1      
317m3002            VIA   -    MD0100PA00X+051602Y+010927X0200Y    R270 S2      
327m3002            R6190 -1   M      A01X+051377Y+010732X0120Y0150R090 S1      
327m3002            R6192 -1   M      A01X+051377Y+010732X0120Y0150R270 S1      
327m3002            R339  -1   M      A01X+051377Y+010732X0120Y0150R180 S1      
317m3003            VIA   -    MD0080PA00X+146431Y+087324X0160Y    R180 S0      
327m3003            U25   -A25        A01X+146247Y+087429X0177Y    R180 S1      
317m3003            VIA   -    MD0100PA00X+051602Y+010537X0200Y    R270 S2      
327m3003            R6191 -1   M      A01X+051827Y+010732X0120Y0150R090 S1      
327m3003            R6193 -1   M      A01X+051827Y+010732X0120Y0150R270 S1      
327m3003            R340  -1   M      A01X+051827Y+010732X0120Y0150     S1      
327m3004            J41   -OB8        A01X+073568Y+006516X0150Y0570R180 S1      
317m3004            VIA   -    M      A01X+073686Y+007494X0200Y    R180 S2      
017m3004            VIA   -    M      A18X+073686Y+007494X0260Y    R180 S2      
017m3004                  -    MD0100PA00X+073686Y+007494                       
327m3004            R6064 -1          A01X+073438Y+007494X0198Y0197R090 S1      
327USB2_P10_DP      R3178 -1          A01X+005462Y+005874X0198Y0197R090 S1      
327USB2_P10_DP      J35   -A69        A01X+006830Y+003276X0150Y0570R180 S1      
327USB2_P10_DN      R3177 -1          A01X+005030Y+005874X0198Y0197R090 S1      
327USB2_P10_DN      J35   -A68        A01X+007066Y+003276X0150Y0570R180 S1      
317UART_VCC_J13     J13   -1    D0320PA00X+143118Y+008743X0480Y0480R180 S3      
317UART_VCC_J13     VIA   -    M      A01X+143126Y+006139X0200Y    R180 S2      
017UART_VCC_J13     VIA   -    M      A18X+143126Y+006139X0260Y    R180 S2      
017UART_VCC_J13           -    MD0100PA00X+143126Y+006139                       
327UART_VCC_J13     R821  -2   M      A01X+143426Y+005847X0198Y0197R090 S1      
327UART_VCC_J13     R820  -1          A01X+143826Y+005847X0198Y0197R270 S1      
327UART_LS_EN_R_N   Q61   -D          A01X+141764Y+011297X0400Y0480R270 S1      
327UART_LS_EN_R_N   R1253 -2          A01X+143211Y+011766X0198Y0197R180 S1      
327UART_LS_EN_R_N   VIA   -    M      A01X+142427Y+011285X0300Y    R270 S1      
327UART_LS_EN_R_N   R1419 -2   M      A01X+142917Y+011289X0198Y0197R090 S1      
327UART_LS_EN_N     R1253 -1          A01X+143526Y+011766X0198Y0197R180 S1      
327UART_LS_EN_N     VIA   -    M      A01X+143355Y+012482X0300Y    R180 S1      
327UART_LS_EN_N     U116  -9          A01X+143831Y+013482X0140Y0630R180 S1      
327UART_LS_EN       R1563 -1          A01X+080848Y+043963X0198Y0197R180 S1      
317UART_LS_EN       VIA   -    M      A01X+081311Y+044334X0300Y    R180 S1      
017UART_LS_EN       VIA   -    M      A18X+081311Y+044334X0200Y    R180 S1      
017UART_LS_EN             -    MD0100PA00X+081311Y+044334                       
317UART_LS_EN       VIA   -    MD0100PA00X+082225Y+030997X0200Y         S0      
317UART_LS_EN       VIA   -    MD0100PA00X+140492Y+011691X0200Y    R270 S0      
327UART_LS_EN       Q61   -G          A01X+140882Y+011691X0400Y0480R270 S1      
327m3005            R405  -1          A18X+136389Y+121464X0198Y0197     S2      
317m3005            VIA   -    M      A01X+116207Y+057005X0200Y    R180 S2      
017m3005            VIA   -    M      A18X+116207Y+057005X0260Y    R180 S2      
017m3005                  -    MD0100PA00X+116207Y+057005                       
317m3005            VIA   -    MD0100PA00X+144477Y+016384X0200Y    R180 S0      
327m3005            U116  -5          A01X+144599Y+015687X0140Y0630R180 S1      
327m3005            R814  -2          A01X+144477Y+016864X0198Y0197R270 S1      
317m3005            VIA   -    MD0100PA00X+106515Y+073628X0200Y         S0      
327m3006            U25   -DJ34       A01X+143035Y+116413X0177Y    R180 S1      
317m3006            VIA   -    MD0100PA00X+134901Y+120497X0200Y         S0      
327m3006            VIA   -    M      A18X+135620Y+121775X0260Y    R180 S2      
327m3006            R405  -2          A18X+136074Y+121464X0198Y0197     S2      
327m3007            U116  -6          A01X+144343Y+015687X0140Y0630R180 S1      
327m3007            VIA   -    M      A01X+143564Y+016618X0300Y    R180 S1      
327m3007            R817  -2          A01X+143977Y+016864X0198Y0197R270 S1      
317m3008            VIA   -    MD0080PA00X+142848Y+115880X0160Y         S0      
327m3008            U25   -DG35       A01X+142665Y+115776X0177Y    R180 S1      
317m3008            VIA   -    MD0100PA00X+158984Y+130529X0200Y    R180 S0      
327m3008            R817  -1          A01X+143977Y+017179X0198Y0197R270 S1      
317m3008            VIA   -    MD0100PA00X+143977Y+017422X0200Y    R180 S0      
327m3008            R813  -2          A01X+143977Y+017664X0198Y0197R270 S1      
317m3008            VIA   -    M      A01X+124269Y+048344X0200Y         S2      
017m3008            VIA   -    M      A18X+124269Y+048344X0260Y         S2      
017m3008                  -    MD0100PA00X+124269Y+048344                       
327m3009            R729  -2   M      A18X+133675Y+120799X0198Y0197R180 S2      
327m3009            R747  -2          A18X+133675Y+121149X0198Y0197R180 S2      
327m3009            R2318 -2   M      A18X+133360Y+120399X0198Y0197     S2      
317m3009            VIA   -    MD0100PA00X+107850Y+064820X0200Y         S0      
327m3009            R815  -2          A01X+145477Y+016864X0198Y0197R270 S1      
327m3009            U116  -3          A01X+145111Y+015687X0140Y0630R180 S1      
317m3009            VIA   -    M      A01X+145477Y+016384X0200Y    R180 S2      
017m3009            VIA   -    M      A18X+145477Y+016384X0260Y    R180 S2      
017m3009                  -    MD0100PA00X+145477Y+016384                       
317m3009            VIA   -    MD0100PA00X+104406Y+073619X0200Y         S0      
327m3010            VIA   -    M      A18X+135273Y+121406X0260Y    R180 S2      
327m3010            R2318 -1          A18X+133675Y+120399X0198Y0197     S2      
317m3010            VIA   -    MD0100PA00X+136128Y+120672X0200Y         S0      
327m3010            U25   -DJ32       A01X+143775Y+116413X0177Y    R180 S1      
327m3011            U116  -4          A01X+144855Y+015687X0140Y0630R180 S1      
327m3011            VIA   -    M      A01X+144977Y+016384X0300Y    R180 S1      
327m3011            R1423 -2          A01X+144977Y+016864X0198Y0197R270 S1      
317m3012            VIA   -    MD0100PA00X+136281Y+121107X0200Y         S0      
327m3012            U25   -DH33       A01X+143590Y+116094X0177Y    R180 S1      
317m3012            VIA   -    M      A01X+144977Y+017422X0200Y    R180 S2      
017m3012            VIA   -    M      A18X+144977Y+017422X0260Y    R180 S2      
017m3012                  -    MD0100PA00X+144977Y+017422                       
327m3012            R816  -2          A01X+144977Y+017664X0198Y0197R270 S1      
327m3012            R1423 -1          A01X+144977Y+017179X0198Y0197R270 S1      
317m3012            VIA   -    MD0100PA00X+108328Y+065160X0200Y         S0      
317m3012            VIA   -    MD0100PA00X+106182Y+073636X0200Y         S0      
327m3013            C62   -1   M      A01X+121558Y+008577X0198Y0197R090 S1      
327m3013            R6065 -2          A01X+072938Y+007809X0198Y0197R090 S1      
317m3013            VIA   -    M      A01X+072938Y+008052X0200Y         S2      
017m3013            VIA   -    M      A18X+072938Y+008052X0260Y         S2      
017m3013                  -    MD0100PA00X+072938Y+008052                       
317m3013            VIA   -    MD0100PA00X+120593Y+008687X0200Y    R270 S0      
317m3013            J8    -3    D0320PA00X+123340Y+006038X0480Y         S3      
317m3013            VIA   -    MD0100PA00X+145204Y+011302X0200Y    R180 S0      
327m3013            R1425 -2          A01X+145455Y+011687X0198Y0197R270 S1      
327m3013            R822  -2   M      A01X+145455Y+011302X0198Y0197R090 S1      
327m3014            R1425 -1          A01X+145455Y+012002X0198Y0197R270 S1      
327m3014            VIA   -    M      A01X+145092Y+012504X0300Y    R180 S1      
327m3014            U116  -14         A01X+145111Y+013482X0140Y0630R180 S1      
327m3015            C63   -1          A01X+122346Y+008577X0198Y0197R090 S1      
317m3015            VIA   -    MD0100PA00X+123877Y+007532X0200Y    R270 S0      
317m3015            J8    -2    D0320PA00X+124128Y+006038X0480Y         S3      
317m3015            VIA   -    MD0100PA00X+144604Y+012022X0200Y    R180 S0      
327m3015            R823  -2   M      A01X+144855Y+012022X0198Y0197R090 S1      
327m3015            U116  -13         A01X+144855Y+013482X0140Y0630R180 S1      
327m3015            R6064 -2          A01X+073438Y+007809X0198Y0197R090 S1      
317m3015            VIA   -    M      A01X+073438Y+008052X0200Y         S2      
017m3015            VIA   -    M      A18X+073438Y+008052X0260Y         S2      
017m3015                  -    MD0100PA00X+073438Y+008052                       
327m3016            VIA   -    M      A01X+145072Y+010366X0300Y         S1      
327m3016            C363  -1   M      A01X+144687Y+011144X0198Y0197R270 S1      
327m3016            R824  -2   M      A01X+144305Y+011302X0198Y0197R090 S1      
327m3016            R818  -2          A01X+144305Y+011687X0198Y0197R270 S1      
317m3016            J13   -3    D0320PA00X+144692Y+008743X0480Y    R180 S3      
327m3017            U116  -12         A01X+144599Y+013482X0140Y0630R180 S1      
327m3017            VIA   -    M      A01X+144355Y+012482X0300Y    R180 S1      
327m3017            R818  -1          A01X+144305Y+012002X0198Y0197R270 S1      
327m3018            U116  -11         A01X+144343Y+013482X0140Y0630R180 S1      
327m3018            VIA   -    M      A01X+143855Y+012482X0300Y    R180 S1      
327m3018            R819  -1          A01X+143905Y+012002X0198Y0197R270 S1      
327m3019            VIA   -    M      A01X+143182Y+010422X0300Y         S1      
327m3019            C364  -1   M      A01X+143451Y+011298X0198Y0197R270 S1      
327m3019            R825  -2   M      A01X+143905Y+011302X0198Y0197R090 S1      
327m3019            R819  -2          A01X+143905Y+011687X0198Y0197R270 S1      
317m3019            J13   -2    D0320PA00X+143905Y+008743X0480Y    R180 S3      
327m3020            J41   -OB5        A01X+074276Y+006516X0150Y0570R180 S1      
317m3020            J106  -N8   D0142PA00X+155807Y+167201X0302Y    R180 S3      
317m3020            VIA   -    MD0100PA00X+170016Y+169883X0200Y         S0      
317m3020            VIA   -    M      A01X+121843Y+042101X0200Y         S2      
017m3020            VIA   -    M      A18X+121843Y+042101X0260Y         S2      
017m3020                  -    MD0100PA00X+121843Y+042101                       
317m3020            VIA   -    MD0100PA00X+081932Y+005696X0200Y         S0      
317m3020            VIA   -    MD0100PA00X+073477Y+006076X0200Y         S0      
327m3021            R3033 -2          A01X+141562Y+161334X0198Y0197R090 S1      
327m3021            VIA   -    M      A01X+141600Y+161700X0300Y    R180 S1      
327m3021            U204  -2          A01X+141618Y+162563X0170Y0240     S1      
327m3022            VIA   -    M      A01X+141874Y+163817X0300Y         S1      
327m3022            R4173 -2          A01X+141874Y+164697X0198Y0197R180 S1      
327m3022            R3036 -1   M      A01X+141874Y+164297X0198Y0197     S1      
327m3022            U204  -4          A01X+141874Y+163311X0170Y0240     S1      
317m3023            J106  -N6   D0142PA00X+154232Y+167201X0302Y    R180 S3      
317m3023            VIA   -    MD0100PA00X+146304Y+168706X0200Y         S0      
317m3023            VIA   -    M      A01X+141800Y+160750X0200Y         S2      
017m3023            VIA   -    M      A18X+141800Y+160750X0260Y         S2      
017m3023                  -    MD0100PA00X+141800Y+160750                       
327m3023            R3033 -1          A01X+141562Y+161019X0198Y0197R090 S1      
327m3023            R4515 -2   M      A01X+141962Y+161019X0198Y0197R270 S1      
327m3024            J41   -OB6        A01X+074040Y+006516X0150Y0570R180 S1      
317m3024            VIA   -    M      A01X+142189Y+163550X0200Y    R090 S2      
017m3024            VIA   -    M      A18X+142189Y+163550X0260Y    R090 S2      
017m3024                  -    MD0100PA00X+142189Y+163550                       
327m3024            R3036 -2          A01X+142189Y+164297X0198Y0197     S1      
317m3024            VIA   -    MD0100PA00X+097400Y+032085X0200Y         S0      
317m3024            VIA   -    MD0100PA00X+074054Y+007356X0200Y         S0      
317m3024            VIA   -    MD0100PA00X+141991Y+160278X0200Y         S0      
327U212_EN_N        U212  -6          A01X+050694Y+023044X0160Y0540R270 S1      
317U212_EN_N        JP6000-2    D0410PA00X+008973Y+028982X0610Y    R270 S3      
317U212_EN_N        VIA   -    M      A01X+050021Y+022788X0200Y         S2      
017U212_EN_N        VIA   -    M      A18X+050021Y+022788X0260Y         S2      
017U212_EN_N              -    MD0100PA00X+050021Y+022788                       
327U160_EN_N        U160  -6          A01X+042890Y+022776X0160Y0540R270 S1      
317U160_EN_N        JP6001-2    D0410PA00X+008973Y+031026X0610Y    R270 S3      
317U160_EN_N        VIA   -    M      A01X+042294Y+022350X0200Y         S2      
017U160_EN_N        VIA   -    M      A18X+042294Y+022350X0260Y         S2      
017U160_EN_N              -    MD0100PA00X+042294Y+022350                       
327U152_OE_N        R1637 -1          A01X+052830Y+021407X0198Y0197R270 S1      
327U152_OE_N        VIA   -    M      A01X+052350Y+021407X0300Y    R270 S1      
327U152_OE_N        U152  -2          A01X+051483Y+021407X0070Y0320R270 S1      
317m3025            VIA   -     D0080PA00X+038390Y+105357X0160Y         S0      
327m3025            U26   -BP53       A01X+038574Y+105252X0177Y    R180 S1      
317m3026            VIA   -     D0080PA00X+136004Y+105357X0160Y         S0      
327m3026            U25   -BP53       A01X+136188Y+105252X0177Y    R180 S1      
317m3027            VIA   -     D0080PA00X+143404Y+115561X0160Y         S0      
327m3027            U25   -DF34       A01X+143220Y+115457X0177Y    R180 S1      
327TP_U27_EN        U27   -5          A01X+069739Y+058893X0240Y0460     S1      
327TP_U27_EN        VIA   -           A01X+069168Y+058608X0300Y         S1      
327m3028            J41   -B48        A01X+056278Y+006516X0150Y0570R180 S1      
327m3028            VIA   -           A01X+056278Y+007830X0300Y         S1      
327m3029            J41   -B47        A01X+056515Y+006516X0150Y0570R180 S1      
327m3029            VIA   -           A01X+056282Y+008426X0300Y         S1      
327m3030            J41   -B46        A01X+056751Y+006516X0150Y0570R180 S1      
327m3030            VIA   -           A01X+056751Y+008105X0300Y         S1      
327m3031            J41   -B45        A01X+056987Y+006516X0150Y0570R180 S1      
327m3031            VIA   -           A01X+056752Y+008736X0300Y         S1      
327m3032            J41   -B44        A01X+057223Y+006516X0150Y0570R180 S1      
327m3032            VIA   -           A01X+057223Y+007786X0300Y         S1      
327m3033            J41   -B43        A01X+057460Y+006516X0150Y0570R180 S1      
327m3033            VIA   -           A01X+057222Y+008356X0300Y         S1      
327TP_PCIE_TXP<3>   J41   -B68        A01X+051554Y+006516X0150Y0570R180 S1      
327TP_PCIE_TXP<3>   R3254 -1          A01X+051554Y+008257X0198Y0197R090 S1      
327TP_PCIE_TXP<3>   VIA   -    M      A01X+051554Y+007777X0300Y         S1      
327TP_PCIE_TXP<1>   J41   -B62        A01X+052971Y+006516X0150Y0570R180 S1      
327TP_PCIE_TXP<1>   VIA   -           A01X+052821Y+007777X0300Y         S1      
327TP_PCIE_TXN<1>   J41   -B63        A01X+052735Y+006516X0150Y0570R180 S1      
327TP_PCIE_TXN<1>   VIA   -           A01X+052315Y+007777X0300Y         S1      
327TP_PCIE_RXP<1>   J41   -A62        A01X+052971Y+005354X0150Y0570R180 S1      
317TP_PCIE_RXP<1>   VIA   -           A01X+052971Y+003335X0200Y         S2      
017TP_PCIE_RXP<1>   VIA   -           A18X+052971Y+003335X0260Y         S2      
017TP_PCIE_RXP<1>         -     D0100PA00X+052971Y+003335                       
327TP_PCIE_RXN<1>   J41   -A63        A01X+052735Y+005354X0150Y0570R180 S1      
317TP_PCIE_RXN<1>   VIA   -           A01X+052471Y+003335X0200Y         S2      
017TP_PCIE_RXN<1>   VIA   -           A18X+052471Y+003335X0260Y         S2      
017TP_PCIE_RXN<1>         -     D0100PA00X+052471Y+003335                       
327m3034            J35   -B69        A01X+006830Y+004437X0150Y0570R180 S1      
327m3034            VIA   -           A01X+005941Y+005706X0300Y         S1      
327m3035            VIA   -           A01X+005530Y+005354X0300Y         S1      
327m3035            J35   -B68        A01X+007066Y+004437X0150Y0570R180 S1      
327TP_OCP_SFF_B69   VIA   -           A01X+153382Y+005718X0300Y         S1      
327TP_OCP_SFF_B69   J38   -B69        A01X+154270Y+004437X0150Y0570R180 S1      
327TP_OCP_SFF_B68   VIA   -           A01X+153088Y+006257X0300Y         S1      
327TP_OCP_SFF_B68   J38   -B68        A01X+154507Y+004437X0150Y0570R180 S1      
317m3036            VIA   -     D0080PA00X+054301Y+102806X0160Y         S0      
327m3036            U26   -BF11       A01X+054117Y+102701X0177Y    R180 S1      
317m3037            VIA   -     D0080PA00X+151915Y+102806X0160Y         S0      
327m3037            U25   -BF11       A01X+151732Y+102701X0177Y    R180 S1      
317m3038            VIA   -     D0080PA00X+055781Y+102806X0160Y         S0      
327m3038            U26   -BF7        A01X+055598Y+102701X0177Y    R180 S1      
317m3039            VIA   -     D0080PA00X+153396Y+102806X0160Y         S0      
327m3039            U25   -BF7        A01X+153212Y+102701X0177Y    R180 S1      
317m3040            VIA   -     D0080PA00X+051710Y+102806X0160Y         S0      
327m3040            U26   -BF18       A01X+051527Y+102701X0177Y    R180 S1      
317m3041            VIA   -     D0080PA00X+149325Y+102806X0160Y         S0      
327m3041            U25   -BF18       A01X+149141Y+102701X0177Y    R180 S1      
317m3042            VIA   -     D0080PA00X+050600Y+102806X0160Y         S0      
327m3042            U26   -BF21       A01X+050416Y+102701X0177Y    R180 S1      
317m3043            VIA   -     D0080PA00X+148214Y+102806X0160Y         S0      
327m3043            U25   -BF21       A01X+148031Y+102701X0177Y    R180 S1      
317m3044            VIA   -     D0080PA00X+053191Y+102806X0160Y         S0      
327m3044            U26   -BF14       A01X+053007Y+102701X0177Y    R180 S1      
317m3045            VIA   -     D0080PA00X+150805Y+102806X0160Y         S0      
327m3045            U25   -BF14       A01X+150621Y+102701X0177Y    R180 S1      
317m3046            VIA   -     D0080PA00X+056892Y+102806X0160Y         S0      
327m3046            U26   -BF4        A01X+056708Y+102701X0177Y    R180 S1      
317m3047            VIA   -     D0080PA00X+154506Y+102806X0160Y         S0      
327m3047            U25   -BF4        A01X+154322Y+102701X0177Y    R180 S1      
317m3048            VIA   -     D0080PA00X+033949Y+102806X0160Y         S0      
327m3048            U26   -BF65       A01X+034133Y+102701X0177Y    R180 S1      
317m3049            VIA   -     D0080PA00X+131563Y+102806X0160Y         S0      
327m3049            U25   -BF65       A01X+131747Y+102701X0177Y    R180 S1      
317m3050            VIA   -     D0080PA00X+032469Y+102806X0160Y         S0      
327m3050            U26   -BF69       A01X+032653Y+102701X0177Y    R180 S1      
317m3051            VIA   -     D0080PA00X+130083Y+102806X0160Y         S0      
327m3051            U25   -BF69       A01X+130267Y+102701X0177Y    R180 S1      
317m3052            VIA   -     D0080PA00X+036540Y+102806X0160Y         S0      
327m3052            U26   -BF58       A01X+036724Y+102701X0177Y    R180 S1      
317m3053            VIA   -     D0080PA00X+134154Y+102806X0160Y         S0      
327m3053            U25   -BF58       A01X+134338Y+102701X0177Y    R180 S1      
317m3054            VIA   -     D0080PA00X+037650Y+102806X0160Y         S0      
327m3054            U26   -BF55       A01X+037834Y+102701X0177Y    R180 S1      
317m3055            VIA   -     D0080PA00X+135264Y+102806X0160Y         S0      
327m3055            U25   -BF55       A01X+135448Y+102701X0177Y    R180 S1      
317m3056            VIA   -     D0080PA00X+035060Y+102806X0160Y         S0      
327m3056            U26   -BF62       A01X+035243Y+102701X0177Y    R180 S1      
317m3057            VIA   -     D0080PA00X+132674Y+102806X0160Y         S0      
327m3057            U25   -BF62       A01X+132858Y+102701X0177Y    R180 S1      
317m3058            VIA   -     D0080PA00X+035866Y+087962X0160Y    R180 S0      
327m3058            U26   -C60        A01X+036050Y+088067X0177Y    R180 S1      
317m3059            VIA   -     D0080PA00X+031359Y+102806X0160Y         S0      
327m3059            U26   -BF72       A01X+031542Y+102701X0177Y    R180 S1      
317m3060            VIA   -     D0080PA00X+133481Y+087962X0160Y    R180 S0      
327m3060            U25   -C60        A01X+133665Y+088067X0177Y    R180 S1      
317m3061            VIA   -     D0080PA00X+128973Y+102806X0160Y         S0      
327m3061            U25   -BF72       A01X+129157Y+102701X0177Y    R180 S1      
327m3062            U160  -1          A01X+042890Y+024095X0240Y0540R270 S1      
327m3062            VIA   -           A01X+042358Y+024587X0300Y    R270 S1      
327m3063            U212  -1          A01X+050694Y+024363X0240Y0540R270 S1      
327m3063            VIA   -           A01X+051069Y+024865X0300Y    R270 S1      
327m3064            U212  -12         A01X+052998Y+023300X0160Y0540R270 S1      
317m3064            VIA   -           A01X+053861Y+023300X0200Y    R180 S2      
017m3064            VIA   -           A18X+053861Y+023300X0260Y    R180 S2      
017m3064                  -     D0100PA00X+053861Y+023300                       
327m3065            U160  -12         A01X+045193Y+023032X0160Y0540R270 S1      
317m3065            VIA   -           A01X+046062Y+023032X0200Y    R180 S2      
017m3065            VIA   -           A18X+046062Y+023032X0260Y    R180 S2      
017m3065                  -     D0100PA00X+046062Y+023032                       
327TP_STBY_EN       J41   -A45        A01X+056987Y+005354X0150Y0570R180 S1      
317TP_STBY_EN       VIA   -           A01X+057021Y+004798X0200Y         S2      
017TP_STBY_EN       VIA   -           A18X+057021Y+004798X0260Y         S2      
017TP_STBY_EN             -     D0100PA00X+057021Y+004798                       
327TP_E1S_0_RFU     J90   -B8         A01X+093150Y+018411X0150Y0500R090 S1      
327TP_E1S_0_RFU     VIA   -           A01X+089546Y+015562X0300Y    R180 S1      
327TP_E1S_0_MFG     VIA   -           A01X+090046Y+015562X0300Y    R180 S1      
327TP_E1S_0_MFG     J90   -B7         A01X+093150Y+018175X0150Y0500R090 S1      
317m3066            VIA   -     D0080PA00X+046159Y+116199X0160Y         S0      
327m3066            U26   -DH33       A01X+045976Y+116095X0177Y    R180 S1      
317m3067            VIA   -     D0080PA00X+045604Y+116518X0160Y         S0      
327m3067            U26   -DJ34       A01X+045420Y+116414X0177Y    R180 S1      
317m3068            VIA   -     D0080PA00X+045234Y+115880X0160Y         S0      
327m3068            U26   -DG35       A01X+045050Y+115776X0177Y    R180 S1      
317m3069            VIA   -     D0080PA00X+045789Y+115562X0160Y         S0      
327m3069            U26   -DF34       A01X+045606Y+115457X0177Y    R180 S1      
317m3070            VIA   -     D0080PA00X+045604Y+115880X0160Y         S0      
327m3070            U26   -DG34       A01X+045420Y+115776X0177Y    R180 S1      
317m3071            VIA   -     D0080PA00X+045974Y+116518X0160Y         S0      
327m3071            U26   -DJ33       A01X+045790Y+116414X0177Y    R180 S1      
317m3072            VIA   -     D0080PA00X+038575Y+110140X0160Y         S0      
327m3072            U26   -CJ53       A01X+038759Y+110036X0177Y    R180 S1      
317m3073            VIA   -     D0080PA00X+049557Y+093702X0160Y    R180 S0      
327m3073            U26   -AA23       A01X+049373Y+093807X0177Y    R180 S1      
317m3074            VIA   -     D0080PA00X+038945Y+110140X0160Y         S0      
327m3074            U26   -CJ52       A01X+039129Y+110036X0177Y    R180 S1      
317m3075            VIA   -     D0080PA00X+047336Y+093702X0160Y    R180 S0      
327m3075            U26   -AA29       A01X+047153Y+093807X0177Y    R180 S1      
317m3076            VIA   -     D0080PA00X+047455Y+110140X0160Y         S0      
327m3076            U26   -CJ29       A01X+047271Y+110036X0177Y    R180 S1      
317m3077            VIA   -     D0080PA00X+040678Y+093702X0160Y    R180 S0      
327m3077            U26   -AA47       A01X+040861Y+093807X0177Y    R180 S1      
317m3078            VIA   -     D0080PA00X+039937Y+093702X0160Y    R180 S0      
327m3078            U26   -AA49       A01X+040121Y+093807X0177Y    R180 S1      
317m3079            VIA   -     D0080PA00X+040863Y+093384X0160Y    R180 S0      
327m3079            U26   -Y46        A01X+041046Y+093488X0177Y    R180 S1      
317m3080            VIA   -     D0080PA00X+041166Y+110140X0160Y         S0      
327m3080            U26   -CJ46       A01X+041350Y+110036X0177Y    R180 S1      
317m3081            VIA   -     D0080PA00X+047084Y+110140X0160Y         S0      
327m3081            U26   -CJ30       A01X+046901Y+110036X0177Y    R180 S1      
317m3082            VIA   -     D0080PA00X+041048Y+093702X0160Y    R180 S0      
327m3082            U26   -AA46       A01X+041232Y+093807X0177Y    R180 S1      
317m3083            VIA   -     D0080PA00X+049187Y+093702X0160Y    R180 S0      
327m3083            U26   -AA24       A01X+049003Y+093807X0177Y    R180 S1      
317m3084            VIA   -     D0080PA00X+047640Y+110459X0160Y         S0      
327m3084            U26   -CK29       A01X+047456Y+110354X0177Y    R180 S1      
317m3085            VIA   -     D0080PA00X+040492Y+093384X0160Y    R180 S0      
327m3085            U26   -Y47        A01X+040676Y+093488X0177Y    R180 S1      
317m3086            VIA   -     D0080PA00X+048447Y+093702X0160Y    R180 S0      
327m3086            U26   -AA26       A01X+048263Y+093807X0177Y    R180 S1      
317m3087            VIA   -     D0080PA00X+039315Y+110140X0160Y         S0      
327m3087            U26   -CJ51       A01X+039499Y+110036X0177Y    R180 S1      
317m3088            VIA   -     D0080PA00X+048935Y+110140X0160Y         S0      
327m3088            U26   -CJ25       A01X+048751Y+110036X0177Y    R180 S1      
317m3089            VIA   -     D0080PA00X+038457Y+093702X0160Y    R180 S0      
327m3089            U26   -AA53       A01X+038641Y+093807X0177Y    R180 S1      
317m3090            VIA   -     D0080PA00X+047152Y+093384X0160Y    R180 S0      
327m3090            U26   -Y30        A01X+046968Y+093488X0177Y    R180 S1      
317m3091            VIA   -     D0080PA00X+040056Y+110140X0160Y         S0      
327m3091            U26   -CJ49       A01X+040239Y+110036X0177Y    R180 S1      
317m3092            VIA   -     D0080PA00X+047522Y+093384X0160Y    R180 S0      
327m3092            U26   -Y29        A01X+047338Y+093488X0177Y    R180 S1      
317m3093            VIA   -     D0080PA00X+040611Y+110459X0160Y         S0      
327m3093            U26   -CK47       A01X+040794Y+110354X0177Y    R180 S1      
317m3094            VIA   -     D0080PA00X+048195Y+110140X0160Y         S0      
327m3094            U26   -CJ27       A01X+048011Y+110036X0177Y    R180 S1      
317m3095            VIA   -     D0080PA00X+039197Y+093702X0160Y    R180 S0      
327m3095            U26   -AA51       A01X+039381Y+093807X0177Y    R180 S1      
327m3096            U26   -B61        A01X+035495Y+087748X0177Y    R180 S1      
317m3097            VIA   -     D0080PA00X+048817Y+093702X0160Y    R180 S0      
327m3097            U26   -AA25       A01X+048633Y+093807X0177Y    R180 S1      
317m3098            VIA   -     D0080PA00X+047270Y+110459X0160Y         S0      
327m3098            U26   -CK30       A01X+047086Y+110354X0177Y    R180 S1      
317m3099            VIA   -     D0080PA00X+040308Y+093702X0160Y    R180 S0      
327m3099            U26   -AA48       A01X+040491Y+093807X0177Y    R180 S1      
317m3100            VIA   -     D0080PA00X+048077Y+093702X0160Y    R180 S0      
327m3100            U26   -AA27       A01X+047893Y+093807X0177Y    R180 S1      
317m3101            VIA   -     D0080PA00X+039686Y+110140X0160Y         S0      
327m3101            U26   -CJ50       A01X+039869Y+110036X0177Y    R180 S1      
317m3102            VIA   -     D0080PA00X+048565Y+110140X0160Y         S0      
327m3102            U26   -CJ26       A01X+048381Y+110036X0177Y    R180 S1      
317m3103            VIA   -     D0080PA00X+038827Y+093702X0160Y    R180 S0      
327m3103            U26   -AA52       A01X+039011Y+093807X0177Y    R180 S1      
317m3104            VIA   -     D0080PA00X+046966Y+093702X0160Y    R180 S0      
327m3104            U26   -AA30       A01X+046783Y+093807X0177Y    R180 S1      
317m3105            VIA   -     D0080PA00X+040426Y+110140X0160Y         S0      
327m3105            U26   -CJ48       A01X+040609Y+110036X0177Y    R180 S1      
317m3106            VIA   -     D0080PA00X+047707Y+093702X0160Y    R180 S0      
327m3106            U26   -AA28       A01X+047523Y+093807X0177Y    R180 S1      
317m3107            VIA   -     D0080PA00X+040796Y+110140X0160Y         S0      
327m3107            U26   -CJ47       A01X+040980Y+110036X0177Y    R180 S1      
317m3108            VIA   -     D0080PA00X+047825Y+110140X0160Y         S0      
327m3108            U26   -CJ28       A01X+047641Y+110036X0177Y    R180 S1      
317m3109            VIA   -     D0080PA00X+039567Y+093702X0160Y    R180 S0      
327m3109            U26   -AA50       A01X+039751Y+093807X0177Y    R180 S1      
317m3110            VIA   -     D0080PA00X+055663Y+088281X0160Y    R180 S0      
327m3110            U26   -D7         A01X+055480Y+088386X0177Y    R180 S1      
317m3111            VIA   -     D0080PA00X+036422Y+087644X0160Y    R180 S0      
327m3111            U26   -B58        A01X+036606Y+087748X0177Y    R180 S1      
317m3112            VIA   -     D0080PA00X+046226Y+088600X0160Y    R180 S0      
327m3112            U26   -E32        A01X+046042Y+088705X0177Y    R180 S1      
317m3113            VIA   -     D0080PA00X+040981Y+110459X0160Y         S0      
327m3113            U26   -CK46       A01X+041164Y+110354X0177Y    R180 S1      
317m3114            VIA   -     D0080PA00X+049305Y+110140X0160Y         S0      
327m3114            U26   -CJ24       A01X+049121Y+110036X0177Y    R180 S1      
327m3115            U26   -B60        A01X+035865Y+087748X0177Y    R180 S1      
317m3116            VIA   -     D0080PA00X+046596Y+093065X0160Y    R180 S0      
327m3116            U26   -W31        A01X+046413Y+093169X0177Y    R180 S1      
317m3117            VIA   -     D0080PA00X+143218Y+115880X0160Y         S0      
327m3117            U25   -DG34       A01X+143035Y+115776X0177Y    R180 S1      
317m3118            VIA   -     D0080PA00X+136189Y+110140X0160Y         S0      
327m3118            U25   -CJ53       A01X+136373Y+110036X0177Y    R180 S1      
317m3119            VIA   -     D0080PA00X+147171Y+093702X0160Y    R180 S0      
327m3119            U25   -AA23       A01X+146987Y+093807X0177Y    R180 S1      
317m3120            VIA   -     D0080PA00X+136560Y+110140X0160Y         S0      
327m3120            U25   -CJ52       A01X+136743Y+110036X0177Y    R180 S1      
317m3121            VIA   -     D0080PA00X+144951Y+093702X0160Y    R180 S0      
327m3121            U25   -AA29       A01X+144767Y+093807X0177Y    R180 S1      
317m3122            VIA   -     D0080PA00X+145069Y+110140X0160Y         S0      
327m3122            U25   -CJ29       A01X+144885Y+110036X0177Y    R180 S1      
317m3123            VIA   -     D0080PA00X+138292Y+093702X0160Y    R180 S0      
327m3123            U25   -AA47       A01X+138476Y+093807X0177Y    R180 S1      
317m3124            VIA   -     D0080PA00X+137552Y+093702X0160Y    R180 S0      
327m3124            U25   -AA49       A01X+137735Y+093807X0177Y    R180 S1      
317m3125            VIA   -     D0080PA00X+138477Y+093384X0160Y    R180 S0      
327m3125            U25   -Y46        A01X+138661Y+093488X0177Y    R180 S1      
317m3126            VIA   -     D0080PA00X+138780Y+110140X0160Y         S0      
327m3126            U25   -CJ46       A01X+138964Y+110036X0177Y    R180 S1      
317m3127            VIA   -     D0080PA00X+144699Y+110140X0160Y         S0      
327m3127            U25   -CJ30       A01X+144515Y+110036X0177Y    R180 S1      
317m3128            VIA   -     D0080PA00X+138662Y+093702X0160Y    R180 S0      
327m3128            U25   -AA46       A01X+138846Y+093807X0177Y    R180 S1      
317m3129            VIA   -     D0080PA00X+146801Y+093702X0160Y    R180 S0      
327m3129            U25   -AA24       A01X+146617Y+093807X0177Y    R180 S1      
317m3130            VIA   -     D0080PA00X+145254Y+110459X0160Y         S0      
327m3130            U25   -CK29       A01X+145070Y+110354X0177Y    R180 S1      
317m3131            VIA   -     D0080PA00X+138107Y+093384X0160Y    R180 S0      
327m3131            U25   -Y47        A01X+138290Y+093488X0177Y    R180 S1      
317m3132            VIA   -     D0080PA00X+146061Y+093702X0160Y    R180 S0      
327m3132            U25   -AA26       A01X+145877Y+093807X0177Y    R180 S1      
317m3133            VIA   -     D0080PA00X+136930Y+110140X0160Y         S0      
327m3133            U25   -CJ51       A01X+137113Y+110036X0177Y    R180 S1      
317m3134            VIA   -     D0080PA00X+146549Y+110140X0160Y         S0      
327m3134            U25   -CJ25       A01X+146365Y+110036X0177Y    R180 S1      
317m3135            VIA   -     D0080PA00X+136071Y+093702X0160Y    R180 S0      
327m3135            U25   -AA53       A01X+136255Y+093807X0177Y    R180 S1      
317m3136            VIA   -     D0080PA00X+144766Y+093384X0160Y    R180 S0      
327m3136            U25   -Y30        A01X+144582Y+093488X0177Y    R180 S1      
317m3137            VIA   -     D0080PA00X+137670Y+110140X0160Y         S0      
327m3137            U25   -CJ49       A01X+137854Y+110036X0177Y    R180 S1      
317m3138            VIA   -     D0080PA00X+145136Y+093384X0160Y    R180 S0      
327m3138            U25   -Y29        A01X+144952Y+093488X0177Y    R180 S1      
317m3139            VIA   -     D0080PA00X+138225Y+110459X0160Y         S0      
327m3139            U25   -CK47       A01X+138409Y+110354X0177Y    R180 S1      
317m3140            VIA   -     D0080PA00X+145809Y+110140X0160Y         S0      
327m3140            U25   -CJ27       A01X+145625Y+110036X0177Y    R180 S1      
317m3141            VIA   -     D0080PA00X+136812Y+093702X0160Y    R180 S0      
327m3141            U25   -AA51       A01X+136995Y+093807X0177Y    R180 S1      
317m3142            VIA   -     D0080PA00X+132926Y+087643X0160Y    R180 S0      
327m3142            U25   -B61        A01X+133109Y+087748X0177Y    R180 S1      
317m3143            VIA   -     D0080PA00X+146431Y+093702X0160Y    R180 S0      
327m3143            U25   -AA25       A01X+146247Y+093807X0177Y    R180 S1      
317m3144            VIA   -     D0080PA00X+144884Y+110459X0160Y         S0      
327m3144            U25   -CK30       A01X+144700Y+110354X0177Y    R180 S1      
317m3145            VIA   -     D0080PA00X+137922Y+093702X0160Y    R180 S0      
327m3145            U25   -AA48       A01X+138106Y+093807X0177Y    R180 S1      
317m3146            VIA   -     D0080PA00X+145691Y+093702X0160Y    R180 S0      
327m3146            U25   -AA27       A01X+145507Y+093807X0177Y    R180 S1      
317m3147            VIA   -     D0080PA00X+137300Y+110140X0160Y         S0      
327m3147            U25   -CJ50       A01X+137484Y+110036X0177Y    R180 S1      
317m3148            VIA   -     D0080PA00X+146179Y+110140X0160Y         S0      
327m3148            U25   -CJ26       A01X+145995Y+110036X0177Y    R180 S1      
317m3149            VIA   -     D0080PA00X+136441Y+093702X0160Y    R180 S0      
327m3149            U25   -AA52       A01X+136625Y+093807X0177Y    R180 S1      
317m3150            VIA   -     D0080PA00X+144581Y+093702X0160Y    R180 S0      
327m3150            U25   -AA30       A01X+144397Y+093807X0177Y    R180 S1      
317m3151            VIA   -     D0080PA00X+138040Y+110140X0160Y         S0      
327m3151            U25   -CJ48       A01X+138224Y+110036X0177Y    R180 S1      
317m3152            VIA   -     D0080PA00X+145321Y+093702X0160Y    R180 S0      
327m3152            U25   -AA28       A01X+145137Y+093807X0177Y    R180 S1      
317m3153            VIA   -     D0080PA00X+138410Y+110140X0160Y         S0      
327m3153            U25   -CJ47       A01X+138594Y+110036X0177Y    R180 S1      
317m3154            VIA   -     D0080PA00X+145439Y+110140X0160Y         S0      
327m3154            U25   -CJ28       A01X+145255Y+110036X0177Y    R180 S1      
317m3155            VIA   -     D0080PA00X+137182Y+093702X0160Y    R180 S0      
327m3155            U25   -AA50       A01X+137365Y+093807X0177Y    R180 S1      
317m3156            VIA   -     D0080PA00X+153278Y+088281X0160Y    R180 S0      
327m3156            U25   -D7         A01X+153094Y+088386X0177Y    R180 S1      
317m3157            VIA   -     D0080PA00X+134036Y+087643X0160Y    R180 S0      
327m3157            U25   -B58        A01X+134220Y+087748X0177Y    R180 S1      
317m3158            VIA   -     D0080PA00X+143840Y+088600X0160Y    R180 S0      
327m3158            U25   -E32        A01X+143657Y+088705X0177Y    R180 S1      
317m3159            VIA   -     D0080PA00X+138595Y+110459X0160Y         S0      
327m3159            U25   -CK46       A01X+138779Y+110354X0177Y    R180 S1      
317m3160            VIA   -     D0080PA00X+146919Y+110140X0160Y         S0      
327m3160            U25   -CJ24       A01X+146735Y+110036X0177Y    R180 S1      
317m3161            VIA   -     D0080PA00X+133296Y+087643X0160Y    R180 S0      
327m3161            U25   -B60        A01X+133480Y+087748X0177Y    R180 S1      
317m3162            VIA   -     D0080PA00X+144211Y+093065X0160Y    R180 S0      
327m3162            U25   -W31        A01X+144027Y+093169X0177Y    R180 S1      
327TP_CLK_50M_Y3    VIA   -           A01X+085226Y+005489X0300Y    R090 S1      
327TP_CLK_50M_Y3    U90   -8          A01X+084772Y+005845X0140Y0590R180 S1      
327m3163            VIA   -           A01X+089950Y+020190X0300Y         S1      
327m3163            J90   -A15        A01X+091339Y+020065X0150Y0500R090 S1      
327m3164            VIA   -           A01X+089370Y+020180X0300Y         S1      
327m3164            J90   -A14        A01X+091339Y+019829X0150Y0500R090 S1      
327m3165            PU55  -20         A01X+078958Y+133604X0120Y0790R180 S1      
327m3165            PC128 -2          A01X+080650Y+132692X0198Y0197R270 S1      
327m3165            PL72  -1          A01X+079128Y+132101X0848Y1300R270 S1      
327m3166            PR8000-1          A01X+079942Y+133000X0198Y0197     S1      
327m3166            PU55  -1          A01X+079608Y+133447X0354Y0118R180 S1      
327m3167            PR491 -1          A01X+009812Y+135664X0198Y0197R090 S1      
327m3167            PC176 -2          A01X+009648Y+135322X0198Y0197R180 S1      
327m3168            PC176 -1          A01X+009963Y+135322X0198Y0197R180 S1      
327m3168            PU53  -10_1       A01X+011260Y+135363X0240Y1700R090 S1      
327m3168            PL67  -1          A01X+011306Y+134509X0950Y1780R270 S1      
327m3169            PR492 -1          A01X+013072Y+135664X0198Y0197R090 S1      
327m3169            PC177 -2          A01X+012908Y+135322X0198Y0197R180 S1      
327m3170            PU52  -10_1       A01X+014520Y+135363X0240Y1700R090 S1      
327m3170            PC177 -1          A01X+013223Y+135322X0198Y0197R180 S1      
327m3170            PL68  -1          A01X+014566Y+134509X0950Y1780R270 S1      
327m3171            PC175 -2          A01X+016178Y+135322X0198Y0197R180 S1      
327m3171            PR489 -1          A01X+016342Y+135664X0198Y0197R090 S1      
327m3172            PC175 -1          A01X+016493Y+135322X0198Y0197R180 S1      
327m3172            PU40  -10_1       A01X+017790Y+135363X0240Y1700R090 S1      
327m3172            PL48  -1          A01X+017816Y+134509X0950Y1780R270 S1      
327m3173            PC174 -2          A01X+019468Y+135322X0198Y0197R180 S1      
327m3173            PR488 -1          A01X+019632Y+135664X0198Y0197R090 S1      
327m3174            PU39  -10_1       A01X+021080Y+135363X0240Y1700R090 S1      
327m3174            PC174 -1          A01X+019783Y+135322X0198Y0197R180 S1      
327m3174            PL47  -1          A01X+021076Y+134509X0950Y1780R270 S1      
327m3175            PC630 -2          A01X+011963Y+138178X0198Y0197R270 S1      
327m3175            PU53  -32         A01X+011717Y+137646X0090Y0240     S1      
327m3176            PC631 -2          A01X+015223Y+138178X0198Y0197R270 S1      
327m3176            PU52  -32         A01X+014977Y+137646X0090Y0240     S1      
327m3177            PC445 -2          A01X+018493Y+138178X0198Y0197R270 S1      
327m3177            PU40  -32         A01X+018247Y+137646X0090Y0240     S1      
327m3178            PC447 -2          A01X+021783Y+138178X0198Y0197R270 S1      
327m3178            PU39  -32         A01X+021537Y+137646X0090Y0240     S1      
327m3179            PC630 -1          A01X+011963Y+138493X0198Y0197R270 S1      
327m3179            PR372 -2          A01X+011559Y+138493X0198Y0197R090 S1      
327m3180            PR372 -1          A01X+011559Y+138178X0198Y0197R090 S1      
327m3180            PU53  -33         A01X+011540Y+137646X0090Y0240     S1      
327m3181            PC631 -1          A01X+015223Y+138493X0198Y0197R270 S1      
327m3181            PR373 -2          A01X+014819Y+138493X0198Y0197R090 S1      
327m3182            PR373 -1          A01X+014819Y+138178X0198Y0197R090 S1      
327m3182            PU52  -33         A01X+014800Y+137646X0090Y0240     S1      
327m3183            PC445 -1          A01X+018493Y+138493X0198Y0197R270 S1      
327m3183            PR278 -2          A01X+018089Y+138493X0198Y0197R090 S1      
327m3184            PR278 -1          A01X+018089Y+138178X0198Y0197R090 S1      
327m3184            PU40  -33         A01X+018070Y+137646X0090Y0240     S1      
327m3185            PC447 -1          A01X+021783Y+138493X0198Y0197R270 S1      
327m3185            PR279 -2          A01X+021379Y+138493X0198Y0197R090 S1      
327m3186            PR279 -1          A01X+021379Y+138178X0198Y0197R090 S1      
327m3186            PU39  -33         A01X+021360Y+137646X0090Y0240     S1      
327m3187            PC163 -2          A01X+106822Y+135320X0198Y0197R180 S1      
327m3187            PR291 -1          A01X+106986Y+135662X0198Y0197R090 S1      
327m3188            PC163 -1          A01X+107137Y+135320X0198Y0197R180 S1      
327m3188            PU20  -10_1       A01X+108434Y+135361X0240Y1700R090 S1      
327m3188            PL20  -1          A01X+108480Y+134508X0950Y1780R270 S1      
327m3189            PR379 -1          A01X+110246Y+135662X0198Y0197R090 S1      
327m3189            PC166 -2          A01X+110082Y+135320X0198Y0197R180 S1      
327m3190            PU19  -10_1       A01X+111694Y+135361X0240Y1700R090 S1      
327m3190            PC166 -1          A01X+110397Y+135320X0198Y0197R180 S1      
327m3190            PL21  -1          A01X+111740Y+134508X0950Y1780R270 S1      
327m3191            PC159 -2          A01X+113352Y+135320X0198Y0197R180 S1      
327m3191            PR223 -1          A01X+113516Y+135662X0198Y0197R090 S1      
327m3192            PC159 -1          A01X+113667Y+135320X0198Y0197R180 S1      
327m3192            PU18  -10_1       A01X+114964Y+135361X0240Y1700R090 S1      
327m3192            PL18  -1          A01X+115010Y+134508X0950Y1780R270 S1      
327m3193            PC158 -2          A01X+116642Y+135320X0198Y0197R180 S1      
327m3193            PR221 -1          A01X+116806Y+135662X0198Y0197R090 S1      
327m3194            PU17  -10_1       A01X+118254Y+135361X0240Y1700R090 S1      
327m3194            PC158 -1          A01X+116957Y+135320X0198Y0197R180 S1      
327m3194            PL17  -1          A01X+118300Y+134508X0950Y1780R270 S1      
327m3195            PC183 -2          A01X+109137Y+138176X0198Y0197R270 S1      
327m3195            PU20  -32         A01X+108891Y+137644X0090Y0240     S1      
327m3196            PC186 -2          A01X+112397Y+138176X0198Y0197R270 S1      
327m3196            PU19  -32         A01X+112151Y+137644X0090Y0240     S1      
327m3197            PC156 -2          A01X+115667Y+138176X0198Y0197R270 S1      
327m3197            PU18  -32         A01X+115421Y+137644X0090Y0240     S1      
327m3198            PC155 -2          A01X+118957Y+138176X0198Y0197R270 S1      
327m3198            PU17  -32         A01X+118711Y+137644X0090Y0240     S1      
327m3199            PC183 -1          A01X+109137Y+138491X0198Y0197R270 S1      
327m3199            PR109 -2          A01X+108733Y+138491X0198Y0197R090 S1      
327m3200            PR109 -1          A01X+108733Y+138176X0198Y0197R090 S1      
327m3200            PU20  -33         A01X+108713Y+137644X0090Y0240     S1      
327m3201            PC186 -1          A01X+112397Y+138491X0198Y0197R270 S1      
327m3201            PR110 -2          A01X+111993Y+138491X0198Y0197R090 S1      
327m3202            PR110 -1          A01X+111993Y+138176X0198Y0197R090 S1      
327m3202            PU19  -33         A01X+111973Y+137644X0090Y0240     S1      
327m3203            PC156 -1          A01X+115667Y+138491X0198Y0197R270 S1      
327m3203            PR102 -2          A01X+115263Y+138491X0198Y0197R090 S1      
327m3204            PR102 -1          A01X+115263Y+138176X0198Y0197R090 S1      
327m3204            PU18  -33         A01X+115243Y+137644X0090Y0240     S1      
327m3205            PC155 -1          A01X+118957Y+138491X0198Y0197R270 S1      
327m3205            PR101 -2          A01X+118553Y+138491X0198Y0197R090 S1      
327m3206            PR101 -1          A01X+118553Y+138176X0198Y0197R090 S1      
327m3206            PU17  -33         A01X+118533Y+137644X0090Y0240     S1      
327m3207            PR511 -1          A01X+053583Y+062467X0198Y0197R270 S1      
327m3207            PC195 -2          A01X+053747Y+062809X0198Y0197     S1      
327m3208            PC195 -1          A01X+053432Y+062809X0198Y0197     S1      
327m3208            PL38  -1          A01X+052206Y+063621X0950Y1780R090 S1      
327m3208            PU32  -10_1       A01X+052136Y+062768X0240Y1700R270 S1      
327m3209            PR526 -1          A01X+050253Y+065877X0198Y0197R270 S1      
327m3209            PC149 -2          A01X+050417Y+066219X0198Y0197     S1      
327m3210            PL36  -1          A01X+048946Y+067031X0950Y1780R090 S1      
327m3210            PU31  -10_1       A01X+048806Y+066178X0240Y1700R270 S1      
327m3210            PC149 -1          A01X+050102Y+066219X0198Y0197     S1      
327m3211            PR525 -1          A01X+046993Y+068527X0198Y0197R270 S1      
327m3211            PC141 -2          A01X+047157Y+068869X0198Y0197     S1      
327m3212            PC141 -1          A01X+046842Y+068869X0198Y0197     S1      
327m3212            PL35  -1          A01X+045709Y+069681X0950Y1780R090 S1      
327m3212            PU30  -10_1       A01X+045546Y+068828X0240Y1700R270 S1      
327m3213            PU32  -32         A01X+051679Y+060485X0090Y0240R180 S1      
327m3213            PC353 -2          A01X+051432Y+059952X0198Y0197R090 S1      
327m3214            PU31  -32         A01X+048349Y+063895X0090Y0240R180 S1      
327m3214            PC334 -2          A01X+048102Y+063362X0198Y0197R090 S1      
327m3215            PU30  -32         A01X+045089Y+066545X0090Y0240R180 S1      
327m3215            PC333 -2          A01X+044842Y+066012X0198Y0197R090 S1      
327m3216            PC353 -1          A01X+051432Y+059638X0198Y0197R090 S1      
327m3216            PR215 -2          A01X+051837Y+059638X0198Y0197R270 S1      
327m3217            PR215 -1          A01X+051837Y+059952X0198Y0197R270 S1      
327m3217            PU32  -33         A01X+051856Y+060485X0090Y0240R180 S1      
327m3218            PR210 -2          A01X+048507Y+063048X0198Y0197R270 S1      
327m3218            PC334 -1          A01X+048102Y+063048X0198Y0197R090 S1      
327m3219            PR210 -1          A01X+048507Y+063362X0198Y0197R270 S1      
327m3219            PU31  -33         A01X+048526Y+063895X0090Y0240R180 S1      
327m3220            PR209 -2          A01X+045247Y+065698X0198Y0197R270 S1      
327m3220            PC333 -1          A01X+044842Y+065698X0198Y0197R090 S1      
327m3221            PR209 -1          A01X+045247Y+066012X0198Y0197R270 S1      
327m3221            PU30  -33         A01X+045266Y+066545X0090Y0240R180 S1      
327m3222            PC188 -2          A01X+164812Y+065658X0198Y0197     S1      
327m3222            PR505 -1          A01X+164648Y+065316X0198Y0197R270 S1      
327m3223            PL66  -1          A01X+163304Y+066470X0950Y1780R090 S1      
327m3223            PC188 -1          A01X+164498Y+065658X0198Y0197     S1      
327m3223            PU51  -10_1       A01X+163201Y+065617X0240Y1700R270 S1      
327m3224            PC187 -2          A01X+161512Y+067558X0198Y0197     S1      
327m3224            PR503 -1          A01X+161348Y+067216X0198Y0197R270 S1      
327m3225            PC187 -1          A01X+161198Y+067558X0198Y0197     S1      
327m3225            PL64  -1          A01X+160024Y+068370X0950Y1780R090 S1      
327m3225            PU50  -10_1       A01X+159901Y+067517X0240Y1700R270 S1      
327m3226            PC185 -2          A01X+158236Y+070935X0198Y0197     S1      
327m3226            PR502 -1          A01X+158071Y+070593X0198Y0197R270 S1      
327m3227            PL63  -1          A01X+156711Y+071747X0950Y1780R090 S1      
327m3227            PC185 -1          A01X+157920Y+070935X0198Y0197     S1      
327m3227            PU49  -10_1       A01X+156624Y+070894X0240Y1700R270 S1      
327m3228            PU51  -32         A01X+162744Y+063334X0090Y0240R180 S1      
327m3228            PC612 -2          A01X+162498Y+062802X0198Y0197R090 S1      
327m3229            PU50  -32         A01X+159444Y+065234X0090Y0240R180 S1      
327m3229            PC594 -2          A01X+159198Y+064702X0198Y0197R090 S1      
327m3230            PU49  -32         A01X+156167Y+068611X0090Y0240R180 S1      
327m3230            PC593 -2          A01X+155921Y+068078X0198Y0197R090 S1      
327m3231            PC612 -1          A01X+162498Y+062487X0198Y0197R090 S1      
327m3231            PR366 -2          A01X+162902Y+062487X0198Y0197R270 S1      
327m3232            PR366 -1          A01X+162902Y+062802X0198Y0197R270 S1      
327m3232            PU51  -33         A01X+162921Y+063334X0090Y0240R180 S1      
327m3233            PC594 -1          A01X+159198Y+064387X0198Y0197R090 S1      
327m3233            PR361 -2          A01X+159602Y+064387X0198Y0197R270 S1      
327m3234            PR361 -1          A01X+159602Y+064702X0198Y0197R270 S1      
327m3234            PU50  -33         A01X+159621Y+065234X0090Y0240R180 S1      
327m3235            PC593 -1          A01X+155921Y+067764X0198Y0197R090 S1      
327m3235            PR360 -2          A01X+156325Y+067764X0198Y0197R270 S1      
327m3236            PR360 -1          A01X+156325Y+068078X0198Y0197R270 S1      
327m3236            PU49  -33         A01X+156344Y+068611X0090Y0240R180 S1      
327m3237            PR518 -1          A01X+039391Y+132994X0198Y0197R090 S1      
327m3237            PC208 -2          A01X+039226Y+132652X0198Y0197R180 S1      
327m3238            PL69  -1          A01X+040885Y+131839X0950Y1780R270 S1      
327m3238            PU33  -10_1       A01X+040838Y+132693X0240Y1700R090 S1      
327m3238            PC208 -1          A01X+039542Y+132652X0198Y0197R180 S1      
327m3239            PC207 -2          A01X+035968Y+130718X0198Y0197R180 S1      
327m3239            PR517 -1          A01X+036132Y+131061X0198Y0197R090 S1      
327m3240            PU38  -10_1       A01X+037580Y+130760X0240Y1700R090 S1      
327m3240            PC207 -1          A01X+036283Y+130718X0198Y0197R180 S1      
327m3240            PL45  -1          A01X+037596Y+129892X0950Y1780R270 S1      
327m3241            PC205 -2          A01X+022748Y+135322X0198Y0197R180 S1      
327m3241            PR515 -1          A01X+022912Y+135664X0198Y0197R090 S1      
327m3242            PU36  -10_1       A01X+024360Y+135363X0240Y1700R090 S1      
327m3242            PC205 -1          A01X+023063Y+135322X0198Y0197R180 S1      
327m3242            PL43  -1          A01X+024336Y+134509X0950Y1780R270 S1      
327m3243            PR516 -1          A01X+026272Y+131050X0198Y0197R090 S1      
327m3243            PC206 -2          A01X+026108Y+130707X0198Y0197R180 S1      
327m3244            PU37  -10_1       A01X+027720Y+130748X0240Y1700R090 S1      
327m3244            PC206 -1          A01X+026423Y+130707X0198Y0197R180 S1      
327m3244            PL44  -1          A01X+027766Y+129895X0950Y1780R270 S1      
327m3245            PC202 -2          A01X+029398Y+130704X0198Y0197R180 S1      
327m3245            PR513 -1          A01X+029562Y+131047X0198Y0197R090 S1      
327m3246            PC202 -1          A01X+029713Y+130704X0198Y0197R180 S1      
327m3246            PU5   -10_1       A01X+031010Y+130745X0240Y1700R090 S1      
327m3246            PL41  -1          A01X+031056Y+129886X0950Y1780R270 S1      
327m3247            PC201 -2          A01X+032688Y+130698X0198Y0197R180 S1      
327m3247            PR512 -1          A01X+032852Y+131041X0198Y0197R090 S1      
327m3248            PC201 -1          A01X+033003Y+130698X0198Y0197R180 S1      
327m3248            PU35  -10_1       A01X+034300Y+130740X0240Y1700R090 S1      
327m3248            PL40  -1          A01X+034346Y+129886X0950Y1780R270 S1      
327m3249            PC146 -2          A01X+041541Y+135508X0198Y0197R270 S1      
327m3249            PU33  -32         A01X+041295Y+134976X0090Y0240     S1      
327m3250            PC428 -2          A01X+038283Y+133575X0198Y0197R270 S1      
327m3250            PU38  -32         A01X+038037Y+133043X0090Y0240     S1      
327m3251            PC413 -2          A01X+025063Y+138178X0198Y0197R270 S1      
327m3251            PU36  -32         A01X+024817Y+137646X0090Y0240     S1      
327m3252            PC414 -2          A01X+028423Y+133564X0198Y0197R270 S1      
327m3252            PU37  -32         A01X+028177Y+133032X0090Y0240     S1      
327m3253            PC386 -2          A01X+031713Y+133561X0198Y0197R270 S1      
327m3253            PU5   -32         A01X+031466Y+133029X0090Y0240     S1      
327m3254            PC383 -2          A01X+035003Y+133555X0198Y0197R270 S1      
327m3254            PU35  -32         A01X+034757Y+133023X0090Y0240     S1      
327m3255            PR428 -2          A01X+041137Y+135823X0198Y0197R090 S1      
327m3255            PC146 -1          A01X+041541Y+135823X0198Y0197R270 S1      
327m3256            PR428 -1          A01X+041137Y+135508X0198Y0197R090 S1      
327m3256            PU33  -33         A01X+041118Y+134976X0090Y0240     S1      
327m3257            PC428 -1          A01X+038283Y+133890X0198Y0197R270 S1      
327m3257            PR272 -2          A01X+037879Y+133890X0198Y0197R090 S1      
327m3258            PR272 -1          A01X+037879Y+133575X0198Y0197R090 S1      
327m3258            PU38  -33         A01X+037860Y+133043X0090Y0240     S1      
327m3259            PC413 -1          A01X+025063Y+138493X0198Y0197R270 S1      
327m3259            PR266 -2          A01X+024659Y+138493X0198Y0197R090 S1      
327m3260            PR266 -1          A01X+024659Y+138178X0198Y0197R090 S1      
327m3260            PU36  -33         A01X+024640Y+137646X0090Y0240     S1      
327m3261            PC414 -1          A01X+028423Y+133879X0198Y0197R270 S1      
327m3261            PR267 -2          A01X+028019Y+133879X0198Y0197R090 S1      
327m3262            PR267 -1          A01X+028019Y+133564X0198Y0197R090 S1      
327m3262            PU37  -33         A01X+028000Y+133032X0090Y0240     S1      
327m3263            PC386 -1          A01X+031713Y+133876X0198Y0197R270 S1      
327m3263            PR259 -2          A01X+031309Y+133876X0198Y0197R090 S1      
327m3264            PR259 -1          A01X+031309Y+133561X0198Y0197R090 S1      
327m3264            PU5   -33         A01X+031289Y+133029X0090Y0240     S1      
327m3265            PC383 -1          A01X+035003Y+133870X0198Y0197R270 S1      
327m3265            PR258 -2          A01X+034599Y+133870X0198Y0197R090 S1      
327m3266            PR258 -1          A01X+034599Y+133555X0198Y0197R090 S1      
327m3266            PU35  -33         A01X+034580Y+133023X0090Y0240     S1      
327m3267            PR155 -1          A01X+137004Y+132992X0198Y0197R090 S1      
327m3267            PC154 -2          A01X+136839Y+132650X0198Y0197R180 S1      
327m3268            PL7   -1          A01X+138498Y+131838X0950Y1780R270 S1      
327m3268            PU11  -10_1       A01X+138451Y+132691X0240Y1700R090 S1      
327m3268            PC154 -1          A01X+137154Y+132650X0198Y0197R180 S1      
327m3269            PC157 -2          A01X+133581Y+130717X0198Y0197R180 S1      
327m3269            PR158 -1          A01X+133745Y+131059X0198Y0197R090 S1      
327m3270            PU16  -10_1       A01X+135193Y+130758X0240Y1700R090 S1      
327m3270            PC157 -1          A01X+133896Y+130717X0198Y0197R180 S1      
327m3270            PL15  -1          A01X+135209Y+129890X0950Y1780R270 S1      
327m3271            PC191 -2          A01X+119922Y+135320X0198Y0197R180 S1      
327m3271            PR509 -1          A01X+120086Y+135662X0198Y0197R090 S1      
327m3272            PU14  -10_1       A01X+121534Y+135361X0240Y1700R090 S1      
327m3272            PC191 -1          A01X+120237Y+135320X0198Y0197R180 S1      
327m3272            PL13  -1          A01X+121580Y+134508X0950Y1780R270 S1      
327m3273            PR510 -1          A01X+123885Y+131048X0198Y0197R090 S1      
327m3273            PC192 -2          A01X+123721Y+130705X0198Y0197R180 S1      
327m3274            PC192 -1          A01X+124036Y+130705X0198Y0197R180 S1      
327m3274            PU15  -10_1       A01X+125333Y+130746X0240Y1700R090 S1      
327m3274            PL14  -1          A01X+125379Y+129893X0950Y1780R270 S1      
327m3275            PR507 -1          A01X+127175Y+131045X0198Y0197R090 S1      
327m3275            PC190 -2          A01X+127011Y+130702X0198Y0197R180 S1      
327m3276            PU2   -10_1       A01X+128623Y+130743X0240Y1700R090 S1      
327m3276            PC190 -1          A01X+127326Y+130702X0198Y0197R180 S1      
327m3276            PL11  -1          A01X+128669Y+129884X0950Y1780R270 S1      
327m3277            PC189 -2          A01X+130301Y+130697X0198Y0197R180 S1      
327m3277            PR506 -1          A01X+130465Y+131039X0198Y0197R090 S1      
327m3278            PC189 -1          A01X+130616Y+130697X0198Y0197R180 S1      
327m3278            PU13  -10_1       A01X+131913Y+130738X0240Y1700R090 S1      
327m3278            PL10  -1          A01X+131959Y+129884X0950Y1780R270 S1      
327m3279            PC117 -2          A01X+139154Y+135506X0198Y0197R270 S1      
327m3279            PU11  -32         A01X+138908Y+134974X0090Y0240     S1      
327m3280            PC137 -2          A01X+135896Y+133573X0198Y0197R270 S1      
327m3280            PU16  -32         A01X+135650Y+133041X0090Y0240     S1      
327m3281            PC121 -2          A01X+122237Y+138176X0198Y0197R270 S1      
327m3281            PU14  -32         A01X+121991Y+137644X0090Y0240     S1      
327m3282            PC122 -2          A01X+126036Y+133562X0198Y0197R270 S1      
327m3282            PU15  -32         A01X+125790Y+133030X0090Y0240     S1      
327m3283            PC94  -2          A01X+129326Y+133559X0198Y0197R270 S1      
327m3283            PU2   -32         A01X+129079Y+133027X0090Y0240     S1      
327m3284            PC92  -2          A01X+132616Y+133553X0198Y0197R270 S1      
327m3284            PU13  -32         A01X+132370Y+133021X0090Y0240     S1      
327m3285            PR420 -2          A01X+138750Y+135821X0198Y0197R090 S1      
327m3285            PC117 -1          A01X+139154Y+135821X0198Y0197R270 S1      
327m3286            PR420 -1          A01X+138750Y+135506X0198Y0197R090 S1      
327m3286            PU11  -33         A01X+138731Y+134974X0090Y0240     S1      
327m3287            PC137 -1          A01X+135896Y+133888X0198Y0197R270 S1      
327m3287            PR95  -2          A01X+135492Y+133888X0198Y0197R090 S1      
327m3288            PR95  -1          A01X+135492Y+133573X0198Y0197R090 S1      
327m3288            PU16  -33         A01X+135472Y+133041X0090Y0240     S1      
327m3289            PC121 -1          A01X+122237Y+138491X0198Y0197R270 S1      
327m3289            PR89  -2          A01X+121833Y+138491X0198Y0197R090 S1      
327m3290            PR89  -1          A01X+121833Y+138176X0198Y0197R090 S1      
327m3290            PU14  -33         A01X+121813Y+137644X0090Y0240     S1      
327m3291            PC122 -1          A01X+126036Y+133877X0198Y0197R270 S1      
327m3291            PR90  -2          A01X+125632Y+133877X0198Y0197R090 S1      
327m3292            PR90  -1          A01X+125632Y+133562X0198Y0197R090 S1      
327m3292            PU15  -33         A01X+125612Y+133030X0090Y0240     S1      
327m3293            PC94  -1          A01X+129326Y+133874X0198Y0197R270 S1      
327m3293            PR81  -2          A01X+128922Y+133874X0198Y0197R090 S1      
327m3294            PR81  -1          A01X+128922Y+133559X0198Y0197R090 S1      
327m3294            PU2   -33         A01X+128902Y+133027X0090Y0240     S1      
327m3295            PC92  -1          A01X+132616Y+133868X0198Y0197R270 S1      
327m3295            PR82  -2          A01X+132212Y+133868X0198Y0197R090 S1      
327m3296            PR82  -1          A01X+132212Y+133553X0198Y0197R090 S1      
327m3296            PU13  -33         A01X+132192Y+133021X0090Y0240     S1      
327m3297            PR524 -1          A01X+027293Y+067348X0198Y0197R270 S1      
327m3297            PC321 -2          A01X+027457Y+067690X0198Y0197     S1      
327m3298            PL8   -1          A01X+025799Y+068502X0950Y1780R090 S1      
327m3298            PU24  -10_1       A01X+025846Y+067649X0240Y1700R270 S1      
327m3298            PC321 -1          A01X+027142Y+067690X0198Y0197     S1      
327m3299            PR46  -1          A01X+030566Y+070772X0198Y0197R270 S1      
327m3299            PC318 -2          A01X+030730Y+071114X0198Y0197     S1      
327m3300            PC318 -1          A01X+030415Y+071114X0198Y0197     S1      
327m3300            PL33  -1          A01X+029072Y+071926X0950Y1780R090 S1      
327m3300            PU29  -10_1       A01X+029118Y+071073X0240Y1700R270 S1      
327m3301            PR523 -1          A01X+043753Y+070987X0198Y0197R270 S1      
327m3301            PC317 -2          A01X+043917Y+071329X0198Y0197     S1      
327m3302            PL32  -1          A01X+042556Y+072143X0950Y1780R090 S1      
327m3302            PC317 -1          A01X+043602Y+071329X0198Y0197     S1      
327m3302            PU28  -10_1       A01X+042306Y+071288X0240Y1700R270 S1      
327m3303            PC316 -2          A01X+040617Y+073109X0198Y0197     S1      
327m3303            PR522 -1          A01X+040453Y+072767X0198Y0197R270 S1      
327m3304            PL31  -1          A01X+038959Y+073921X0950Y1780R090 S1      
327m3304            PC316 -1          A01X+040302Y+073109X0198Y0197     S1      
327m3304            PU27  -10_1       A01X+039006Y+073068X0240Y1700R270 S1      
327m3305            PC173 -2          A01X+037313Y+073102X0198Y0197     S1      
327m3305            PR486 -1          A01X+037149Y+072760X0198Y0197R270 S1      
327m3306            PL29  -1          A01X+035655Y+073933X0950Y1780R090 S1      
327m3306            PC173 -1          A01X+036998Y+073102X0198Y0197     S1      
327m3306            PU26  -10_1       A01X+035702Y+073061X0240Y1700R270 S1      
327m3307            PC170 -2          A01X+034007Y+073129X0198Y0197     S1      
327m3307            PR485 -1          A01X+033843Y+072787X0198Y0197R270 S1      
327m3308            PL28  -1          A01X+032349Y+073941X0950Y1780R090 S1      
327m3308            PC170 -1          A01X+033692Y+073129X0198Y0197     S1      
327m3308            PU4   -10_1       A01X+032396Y+073088X0240Y1700R270 S1      
327m3309            PU24  -32         A01X+025389Y+065366X0090Y0240R180 S1      
327m3309            PC133 -2          A01X+025142Y+064833X0198Y0197R090 S1      
327m3310            PU29  -32         A01X+028662Y+068790X0090Y0240R180 S1      
327m3310            PC314 -2          A01X+028415Y+068258X0198Y0197R090 S1      
327m3311            PU28  -32         A01X+041849Y+069005X0090Y0240R180 S1      
327m3311            PC301 -2          A01X+041602Y+068472X0198Y0197R090 S1      
327m3312            PU27  -32         A01X+038549Y+070785X0090Y0240R180 S1      
327m3312            PC300 -2          A01X+038302Y+070252X0198Y0197R090 S1      
327m3313            PU26  -32         A01X+035245Y+070778X0090Y0240R180 S1      
327m3313            PC271 -2          A01X+034998Y+070246X0198Y0197R090 S1      
327m3314            PU4   -32         A01X+031939Y+070805X0090Y0240R180 S1      
327m3314            PC270 -2          A01X+031692Y+070272X0198Y0197R090 S1      
327m3315            PC133 -1          A01X+025142Y+064518X0198Y0197R090 S1      
327m3315            PR424 -2          A01X+025547Y+064518X0198Y0197R270 S1      
327m3316            PR424 -1          A01X+025547Y+064833X0198Y0197R270 S1      
327m3316            PU24  -33         A01X+025566Y+065366X0090Y0240R180 S1      
327m3317            PC314 -1          A01X+028415Y+067942X0198Y0197R090 S1      
327m3317            PR203 -2          A01X+028820Y+067942X0198Y0197R270 S1      
327m3318            PR203 -1          A01X+028820Y+068258X0198Y0197R270 S1      
327m3318            PU29  -33         A01X+028839Y+068790X0090Y0240R180 S1      
327m3319            PR198 -2          A01X+042007Y+068158X0198Y0197R270 S1      
327m3319            PC301 -1          A01X+041602Y+068158X0198Y0197R090 S1      
327m3320            PR198 -1          A01X+042007Y+068472X0198Y0197R270 S1      
327m3320            PU28  -33         A01X+042026Y+069005X0090Y0240R180 S1      
327m3321            PC300 -1          A01X+038302Y+069938X0198Y0197R090 S1      
327m3321            PR197 -2          A01X+038707Y+069938X0198Y0197R270 S1      
327m3322            PR197 -1          A01X+038707Y+070252X0198Y0197R270 S1      
327m3322            PU27  -33         A01X+038726Y+070785X0090Y0240R180 S1      
327m3323            PC271 -1          A01X+034998Y+069931X0198Y0197R090 S1      
327m3323            PR190 -2          A01X+035403Y+069931X0198Y0197R270 S1      
327m3324            PR190 -1          A01X+035403Y+070246X0198Y0197R270 S1      
327m3324            PU26  -33         A01X+035422Y+070778X0090Y0240R180 S1      
327m3325            PC270 -1          A01X+031692Y+069958X0198Y0197R090 S1      
327m3325            PR189 -2          A01X+032097Y+069958X0198Y0197R270 S1      
327m3326            PR189 -1          A01X+032097Y+070272X0198Y0197R270 S1      
327m3326            PU4   -33         A01X+032116Y+070805X0090Y0240R180 S1      
327m3327            PC182 -2          A01X+138512Y+064624X0198Y0197     S1      
327m3327            PR500 -1          A01X+138348Y+064281X0198Y0197R270 S1      
327m3328            PL70  -1          A01X+136886Y+065436X0950Y1780R090 S1      
327m3328            PC182 -1          A01X+138198Y+064624X0198Y0197     S1      
327m3328            PU10  -10_1       A01X+136901Y+064582X0240Y1700R270 S1      
327m3329            PC184 -2          A01X+141782Y+067914X0198Y0197     S1      
327m3329            PR501 -1          A01X+141618Y+067571X0198Y0197R270 S1      
327m3330            PL61  -1          A01X+140124Y+068726X0950Y1780R090 S1      
327m3330            PC184 -1          A01X+141468Y+067914X0198Y0197     S1      
327m3330            PU48  -10_1       A01X+140171Y+067872X0240Y1700R270 S1      
327m3331            PC181 -2          A01X+154922Y+073129X0198Y0197     S1      
327m3331            PR499 -1          A01X+154758Y+072787X0198Y0197R270 S1      
327m3332            PL60  -1          A01X+153264Y+073941X0950Y1780R090 S1      
327m3332            PC181 -1          A01X+154608Y+073129X0198Y0197     S1      
327m3332            PU47  -10_1       A01X+153311Y+073088X0240Y1700R270 S1      
327m3333            PC180 -2          A01X+151642Y+073129X0198Y0197     S1      
327m3333            PR498 -1          A01X+151478Y+072787X0198Y0197R270 S1      
327m3334            PL59  -1          A01X+149984Y+073941X0950Y1780R090 S1      
327m3334            PC180 -1          A01X+151328Y+073129X0198Y0197     S1      
327m3334            PU46  -10_1       A01X+150031Y+073105X0240Y1700R270 S1      
327m3335            PC179 -2          A01X+148334Y+073129X0198Y0197     S1      
327m3335            PR496 -1          A01X+148170Y+072787X0198Y0197R270 S1      
327m3336            PL52  -1          A01X+146676Y+073941X0950Y1780R090 S1      
327m3336            PC179 -1          A01X+148019Y+073129X0198Y0197     S1      
327m3336            PU43  -10_1       A01X+146722Y+073088X0240Y1700R270 S1      
327m3337            PC178 -2          A01X+145042Y+071172X0198Y0197     S1      
327m3337            PR495 -1          A01X+144878Y+070829X0198Y0197R270 S1      
327m3338            PC178 -1          A01X+144728Y+071172X0198Y0197     S1      
327m3338            PL51  -1          A01X+143384Y+071984X0950Y1780R090 S1      
327m3338            PU6   -10_1       A01X+143431Y+071130X0240Y1700R270 S1      
327m3339            PC161 -2          A01X+136198Y+061767X0198Y0197R090 S1      
327m3339            PU10  -32         A01X+136444Y+062299X0090Y0240R180 S1      
327m3340            PU48  -32         A01X+139714Y+065589X0090Y0240R180 S1      
327m3340            PC574 -2          A01X+139468Y+065057X0198Y0197R090 S1      
327m3341            PU47  -32         A01X+152854Y+070805X0090Y0240R180 S1      
327m3341            PC561 -2          A01X+152608Y+070272X0198Y0197R090 S1      
327m3342            PU46  -32         A01X+149574Y+070822X0090Y0240R180 S1      
327m3342            PC560 -2          A01X+149328Y+070272X0198Y0197R090 S1      
327m3343            PU43  -32         A01X+146266Y+070805X0090Y0240R180 S1      
327m3343            PC490 -2          A01X+146019Y+070272X0198Y0197R090 S1      
327m3344            PU6   -32         A01X+142974Y+068847X0090Y0240R180 S1      
327m3344            PC489 -2          A01X+142728Y+068315X0198Y0197R090 S1      
327m3345            PR432 -2          A01X+136602Y+061452X0198Y0197R270 S1      
327m3345            PC161 -1          A01X+136198Y+061452X0198Y0197R090 S1      
327m3346            PR432 -1          A01X+136602Y+061767X0198Y0197R270 S1      
327m3346            PU10  -33         A01X+136621Y+062299X0090Y0240R180 S1      
327m3347            PR354 -2          A01X+139872Y+064742X0198Y0197R270 S1      
327m3347            PC574 -1          A01X+139468Y+064742X0198Y0197R090 S1      
327m3348            PR354 -1          A01X+139872Y+065057X0198Y0197R270 S1      
327m3348            PU48  -33         A01X+139891Y+065589X0090Y0240R180 S1      
327m3349            PC561 -1          A01X+152608Y+069958X0198Y0197R090 S1      
327m3349            PR349 -2          A01X+153012Y+069958X0198Y0197R270 S1      
327m3350            PR349 -1          A01X+153012Y+070272X0198Y0197R270 S1      
327m3350            PU47  -33         A01X+153031Y+070805X0090Y0240R180 S1      
327m3351            PC560 -1          A01X+149328Y+069958X0198Y0197R090 S1      
327m3351            PR348 -2          A01X+149732Y+069958X0198Y0197R270 S1      
327m3352            PU46  -33         A01X+149751Y+070822X0090Y0240R180 S1      
327m3352            PR348 -1          A01X+149732Y+070272X0198Y0197R270 S1      
327m3353            PC490 -1          A01X+146019Y+069958X0198Y0197R090 S1      
327m3353            PR323 -2          A01X+146424Y+069958X0198Y0197R270 S1      
327m3354            PR323 -1          A01X+146424Y+070272X0198Y0197R270 S1      
327m3354            PU43  -33         A01X+146443Y+070805X0090Y0240R180 S1      
327m3355            PC489 -1          A01X+142728Y+068000X0198Y0197R090 S1      
327m3355            PR322 -2          A01X+143132Y+068000X0198Y0197R270 S1      
327m3356            PR322 -1          A01X+143132Y+068315X0198Y0197R270 S1      
327m3356            PU6   -33         A01X+143151Y+068847X0090Y0240R180 S1      
327m3357            PC19  -2          A01X+026077Y+058400X0198Y0197R180 S1      
327m3357            PL57  -1          A01X+025202Y+059441X1380Y1380R180 S1      
327m3357            PU3   -20         A01X+026989Y+060092X0120Y0790R090 S1      
327m3358            PR8002-1          A01X+026387Y+059103X0198Y0197R270 S1      
327m3358            PU3   -1          A01X+026831Y+059442X0354Y0118R090 S1      
327m3359            PL78  -1          A01X+132216Y+057750X1380Y1380R090 S1      
327m3359            PU57  -20         A01X+132210Y+055973X0120Y0790     S1      
327m3359            PC209 -2          A01X+130519Y+056885X0198Y0197R090 S1      
327m3360            PR8001-1          A01X+131226Y+056577X0198Y0197R180 S1      
327m3360            PU57  -1          A01X+131561Y+056130X0354Y0118     S1      
327m3361            PR519 -1          A01X+073846Y+137475X0198Y0197R090 S1      
327m3361            PC255 -2          A01X+073682Y+137132X0198Y0197R180 S1      
327m3362            PC255 -1          A01X+073997Y+137132X0198Y0197R180 S1      
327m3362            PU45  -10_1       A01X+075294Y+137174X0240Y1700R090 S1      
327m3362            PL55  -1          A01X+075294Y+136137X1300Y1660R270 S1      
327m3363            PR520 -1          A01X+070568Y+137465X0198Y0197R090 S1      
327m3363            PC315 -2          A01X+070404Y+137122X0198Y0197R180 S1      
327m3364            PU44  -10_1       A01X+072016Y+137164X0240Y1700R090 S1      
327m3364            PC315 -1          A01X+070719Y+137122X0198Y0197R180 S1      
327m3364            PL54  -1          A01X+072016Y+136127X1300Y1660R270 S1      
327m3365            PU45  -32         A01X+075751Y+139457X0090Y0240     S1      
327m3365            PC520 -2          A01X+075997Y+139970X0198Y0197R270 S1      
327m3366            PC519 -2          A01X+072719Y+139960X0198Y0197R270 S1      
327m3366            PU44  -32         A01X+072472Y+139447X0090Y0240     S1      
327m3367            PR331 -2          A01X+075593Y+140285X0198Y0197R090 S1      
327m3367            PC520 -1          A01X+075997Y+140285X0198Y0197R270 S1      
327m3368            PR331 -1          A01X+075593Y+139970X0198Y0197R090 S1      
327m3368            PU45  -33         A01X+075573Y+139457X0090Y0240     S1      
327m3369            PR330 -2          A01X+072315Y+140275X0198Y0197R090 S1      
327m3369            PC519 -1          A01X+072719Y+140275X0198Y0197R270 S1      
327m3370            PR330 -1          A01X+072315Y+139960X0198Y0197R090 S1      
327m3370            PU44  -33         A01X+072295Y+139447X0090Y0240     S1      
327m3371            PR389 -1          A01X+168620Y+137404X0198Y0197R090 S1      
327m3371            PC168 -2          A01X+168455Y+137061X0198Y0197R180 S1      
327m3372            PU23  -10_1       A01X+170067Y+137102X0240Y1700R090 S1      
327m3372            PC168 -1          A01X+168770Y+137061X0198Y0197R180 S1      
327m3372            PL22  -1          A01X+170067Y+136066X1300Y1660R270 S1      
327m3373            PR482 -1          A01X+165341Y+137394X0198Y0197R090 S1      
327m3373            PC169 -2          A01X+165177Y+137051X0198Y0197R180 S1      
327m3374            PC169 -1          A01X+165492Y+137051X0198Y0197R180 S1      
327m3374            PU22  -10_1       A01X+166789Y+137092X0240Y1700R090 S1      
327m3374            PL23  -1          A01X+166789Y+136056X1300Y1660R270 S1      
327m3375            PC218 -2          A01X+170770Y+139899X0198Y0197R270 S1      
327m3375            PU23  -32         A01X+170524Y+139386X0090Y0240     S1      
327m3376            PC217 -2          A01X+167492Y+139889X0198Y0197R270 S1      
327m3376            PU22  -32         A01X+167246Y+139376X0090Y0240     S1      
327m3377            PC218 -1          A01X+170770Y+140214X0198Y0197R270 S1      
327m3377            PR136 -2          A01X+170366Y+140214X0198Y0197R090 S1      
327m3378            PR136 -1          A01X+170366Y+139899X0198Y0197R090 S1      
327m3378            PU23  -33         A01X+170347Y+139386X0090Y0240     S1      
327m3379            PC217 -1          A01X+167492Y+140204X0198Y0197R270 S1      
327m3379            PR135 -2          A01X+167088Y+140204X0198Y0197R090 S1      
327m3380            PR135 -1          A01X+167088Y+139889X0198Y0197R090 S1      
327m3380            PU22  -33         A01X+167068Y+139376X0090Y0240     S1      
327SW_P5V_AUX_SW    U326  -20         A01X+162823Y+055938X0120Y0790     S1      
327SW_P5V_AUX_SW    PC1847-2          A01X+161751Y+056800X0198Y0197R090 S1      
327SW_P5V_AUX_SW    PL8065-1          A01X+162718Y+057685X1300Y1300R090 S1      
327SW_P5V_AUX_FLT   U326  -21         A01X+162587Y+055938X0120Y0790     S1      
327SW_P5V_AUX_FLT   U326  -10         A01X+162587Y+054915X0120Y0790     S1      
327SW_P5V_AUX_FLT   PC1850-1          A01X+162614Y+052623X0400Y0500R180 S1      
327SW_P5V_AUX_FLT   PL8064-2          A01X+162076Y+052596X0280Y0320R270 S1      
327SW_P5V_AUX_FLT   VIA   -           A01X+162780Y+051925X0300Y    R270 S1      
327SW_P5V_AUX_FLT   PC1849-1          A01X+162614Y+053313X0400Y0500R180 S1      
327SW_P5V_AUX_FLT   PC1898-1          A01X+162614Y+054003X0400Y0500R180 S1      
327SW_P5V_AUX_FLT   PC1846-1          A01X+162554Y+056680X0198Y0197R180 S1      
327SW_P5V_AUX_BST   U326  -1          A01X+162173Y+056096X0354Y0118     S1      
327SW_P5V_AUX_BST   PC1847-1          A01X+161751Y+056485X0198Y0197R090 S1      
327SW_P3V3_EN       R496  -2   M      A01X+080642Y+050800X0198Y0197R180 S1      
327SW_P3V3_EN       R487  -1          A01X+080642Y+051200X0198Y0197     S1      
317SW_P3V3_EN       VIA   -    M      A01X+079050Y+050183X0200Y         S2      
017SW_P3V3_EN       VIA   -    M      A18X+079050Y+050183X0260Y         S2      
017SW_P3V3_EN             -    MD0100PA00X+079050Y+050183                       
317SW_P3V3_EN       VIA   -    MD0100PA00X+075871Y+047182X0180Y    R090 S0      
327SW_P3V3_EN       U18   -Y17        A01X+075717Y+047029X0160Y    R090 S1      
327SW_P3V3_EN       R6050 -1   M      A01X+080642Y+050400X0198Y0197     S1      
327SW_P3V3_AUX_SW   PU9   -11_1       A01X+179724Y+021173X0236Y1496R090 S1      
327SW_P3V3_AUX_SW   PL8066-1          A01X+179580Y+022224X1280Y1970R090 S1      
317m3381            VIA   -    MD0100PA00X+176509Y+020233X0200Y         S0      
317m3381            VIA   -    MD0100PA00X+176256Y+020233X0200Y         S0      
317m3381            VIA   -    MD0100PA00X+175803Y+020226X0200Y         S0      
317m3381            VIA   -    MD0100PA00X+175550Y+020226X0200Y         S0      
327m3381            PC8013-1          A18X+176398Y+020596X0400Y0500R090 S2      
327m3381            PC8014-1          A18X+175692Y+020590X0400Y0500R090 S2      
327m3381            PC571 -1          A18X+177082Y+020456X0400Y0500R090 S2      
327m3381            PC8071-1          A18X+177786Y+020457X0400Y0500R090 S2      
327m3381            VIA   -           A18X+174917Y+020685X0260Y    R180 S2      
327m3381            PC2344-1          A18X+177235Y+019053X0400Y0500R270 S2      
317m3381            PC3   -1   MD0400PA00X+170128Y+019861X0600Y0600R180 S3      
327m3381            PL8045-2          A01X+171578Y+018445X0420Y0990R090 S1      
317m3381            PC566 -1   MD0400PA00X+173166Y+019861X0600Y0600R180 S3      
327m3381            PC2262-1          A01X+175079Y+019060X0400Y0500R090 S1      
327m3381            PC2260-1          A01X+175785Y+019053X0400Y0500R090 S1      
327m3381            PC2343-1          A01X+177185Y+019053X0400Y0500R090 S1      
327m3381            PC576 -1          A01X+176485Y+019053X0400Y0500R090 S1      
317m3381            VIA   -    MD0100PA00X+177464Y+020100X0200Y         S0      
317m3381            VIA   -    MD0100PA00X+177717Y+020100X0200Y         S0      
317m3381            VIA   -    MD0100PA00X+177106Y+019412X0200Y         S0      
317m3381            VIA   -    MD0100PA00X+177358Y+019412X0200Y         S0      
317m3381            VIA   -    MD0100PA00X+176940Y+020092X0200Y         S0      
317m3381            VIA   -    MD0100PA00X+177193Y+020092X0200Y         S0      
327m3381            PC2263-1          A01X+174983Y+020590X0400Y0500R270 S1      
327m3381            PC2261-1          A01X+175692Y+020590X0400Y0500R270 S1      
327m3381            PC2342-1          A01X+176398Y+020596X0400Y0500R270 S1      
327m3381            PC570 -1          A01X+177785Y+020456X0400Y0500R270 S1      
327m3381            PC8567-1          A01X+177085Y+020456X0400Y0500R270 S1      
327m3381            PU9   -20_2       A01X+179021Y+020400X0679Y0905R180 S1      
327m3381            PC577 -1          A01X+178345Y+020738X0198Y0197R090 S1      
327m3382            PR835 -2          A01X+177850Y+019440X0198Y0197R180 S1      
327m3382            PC568 -2          A01X+177856Y+019790X0198Y0197R180 S1      
327m3383            PC568 -1          A01X+178171Y+019790X0198Y0197R180 S1      
327m3383            PU9   -25         A01X+178799Y+019810X0110Y0240R270 S1      
327m3384            PR835 -1          A01X+178165Y+019440X0198Y0197R180 S1      
327m3384            PU9   -26         A01X+178799Y+019613X0110Y0240R270 S1      
327m3385            PC8000-1          A18X+079067Y+136230X0400Y0500R180 S2      
327m3385            PC8001-1          A18X+079067Y+135540X0400Y0500R180 S2      
327m3385            PL71  -2          A01X+079754Y+136419X0280Y0320R090 S1      
327m3385            PC119 -1          A01X+079067Y+136230X0400Y0500     S1      
317m3385            VIA   -    MD0100PA00X+079427Y+136150X0200Y         S0      
317m3385            VIA   -    MD0100PA00X+079427Y+136450X0200Y         S0      
327m3385            PC123 -1          A01X+079797Y+135798X0400Y0500R180 S1      
327m3385            PC120 -1          A01X+079067Y+135540X0400Y0500     S1      
317m3385            VIA   -    MD0100PA00X+079427Y+135760X0200Y         S0      
317m3385            VIA   -    MD0100PA00X+079427Y+135460X0200Y         S0      
327m3385            PU55  -10         A01X+079194Y+134628X0120Y0790R180 S1      
327m3385            PU55  -21         A01X+079194Y+133604X0120Y0790R180 S1      
327m3385            PC126 -1          A01X+079227Y+132866X0198Y0197     S1      
327m3386            PC7001-1          A18X+012419Y+139021X0400Y0500R180 S2      
317m3386            VIA   -    MD0100PA00X+016306Y+140655X0200Y         S0      
317m3386            VIA   -    MD0100PA00X+016306Y+140905X0200Y         S0      
317m3386            VIA   -    MD0100PA00X+016287Y+141161X0200Y         S0      
317m3386            VIA   -    MD0100PA00X+016310Y+141440X0200Y         S0      
317m3386            VIA   -    MD0100PA00X+017320Y+141425X0200Y         S0      
317m3386            VIA   -    MD0100PA00X+017298Y+141146X0200Y         S0      
317m3386            VIA   -    MD0100PA00X+017316Y+140890X0200Y         S0      
317m3386            VIA   -    MD0100PA00X+017316Y+140640X0200Y         S0      
317m3386            VIA   -    MD0100PA00X+019931Y+140988X0200Y         S0      
317m3386            VIA   -    MD0100PA00X+019681Y+140988X0200Y         S0      
317m3386            VIA   -    MD0100PA00X+019431Y+140988X0200Y         S0      
317m3386            VIA   -    MD0100PA00X+019181Y+140988X0200Y         S0      
317m3386            VIA   -    MD0100PA00X+018851Y+140988X0200Y         S0      
327m3386            PC454 -1          A01X+016807Y+141147X0630Y1380     S1      
317m3386            VIA   -    MD0100PA00X+019950Y+140731X0200Y         S0      
317m3386            VIA   -    MD0100PA00X+019950Y+140481X0200Y         S0      
317m3386            VIA   -    MD0100PA00X+019700Y+140731X0200Y         S0      
317m3386            VIA   -    MD0100PA00X+019700Y+140481X0200Y         S0      
317m3386            VIA   -    MD0100PA00X+019450Y+140731X0200Y         S0      
317m3386            VIA   -    MD0100PA00X+019450Y+140481X0200Y         S0      
317m3386            VIA   -    MD0100PA00X+019200Y+140731X0200Y         S0      
317m3386            VIA   -    MD0100PA00X+019200Y+140481X0200Y         S0      
317m3386            VIA   -    MD0100PA00X+018870Y+140731X0200Y         S0      
317m3386            VIA   -    MD0100PA00X+018870Y+140481X0200Y         S0      
327m3386            PL49  -1   M      A01X+019534Y+140748X0650Y1030R090 S1      
327m3386            PU39  -30         A01X+021891Y+137646X0090Y0240     S1      
327m3386            PC623_-1          A01X+022574Y+138230X0198Y0197     S1      
327m3386            PC438_-1          A01X+019294Y+138230X0198Y0197     S1      
327m3386            PU40  -30         A01X+018601Y+137646X0090Y0240     S1      
327m3386            PC439_-1          A01X+016004Y+138230X0198Y0197     S1      
327m3386            PU52  -30         A01X+015331Y+137646X0090Y0240     S1      
327m3386            PC622_-1          A01X+012734Y+138230X0198Y0197     S1      
327m3386            PU53  -30         A01X+012071Y+137646X0090Y0240     S1      
327m3386            PC440_-1          A01X+022511Y+136721X0198Y0197R270 S1      
327m3386            PC441_-1          A01X+019221Y+136721X0198Y0197R270 S1      
327m3386            PC624_-1          A01X+015951Y+136698X0198Y0197R270 S1      
327m3386            PC625_-1          A01X+012691Y+136721X0198Y0197R270 S1      
327m3386            PC442_-1          A18X+021522Y+137705X0400Y0500R090 S2      
327m3386            PC446_-1          A18X+018232Y+137705X0400Y0500R090 S2      
327m3386            PC628_-1          A18X+014962Y+137705X0400Y0500R090 S2      
327m3386            PC629_-1          A18X+011702Y+137705X0400Y0500R090 S2      
327m3386            PC444_-1          A18X+022360Y+136881X0400Y0500R270 S2      
327m3386            PC448_-1          A18X+021522Y+136881X0400Y0500R270 S2      
327m3386            PC449_-1          A18X+019070Y+136881X0400Y0500R270 S2      
327m3386            PC443_-1          A18X+018232Y+136881X0400Y0500R270 S2      
327m3386            PC626_-1          A18X+014962Y+136881X0400Y0500R270 S2      
327m3386            PC632_-1          A18X+015800Y+136881X0400Y0500R270 S2      
327m3386            PC627_-1          A18X+012540Y+136881X0400Y0500R270 S2      
327m3386            PC633_-1          A18X+011702Y+136881X0400Y0500R270 S2      
317m3386            VIA   -    MD0100PA00X+022114Y+137631X0200Y         S0      
317m3386            VIA   -    MD0100PA00X+022321Y+137458X0200Y         S0      
317m3386            VIA   -    MD0100PA00X+022331Y+137758X0200Y         S0      
317m3386            VIA   -    MD0100PA00X+022114Y+137921X0200Y         S0      
317m3386            VIA   -    MD0100PA00X+022541Y+137608X0200Y         S0      
317m3386            VIA   -    MD0100PA00X+022541Y+137898X0200Y         S0      
317m3386            VIA   -    MD0100PA00X+019251Y+137608X0200Y         S0      
317m3386            VIA   -    MD0100PA00X+018824Y+137631X0200Y         S0      
317m3386            VIA   -    MD0100PA00X+019031Y+137458X0200Y         S0      
317m3386            VIA   -    MD0100PA00X+019251Y+137898X0200Y         S0      
317m3386            VIA   -    MD0100PA00X+019041Y+137758X0200Y         S0      
317m3386            VIA   -    MD0100PA00X+018824Y+137921X0200Y         S0      
317m3386            VIA   -    MD0100PA00X+015761Y+137458X0200Y         S0      
317m3386            VIA   -    MD0100PA00X+015771Y+137758X0200Y         S0      
317m3386            VIA   -    MD0100PA00X+015981Y+137608X0200Y         S0      
317m3386            VIA   -    MD0100PA00X+015981Y+137898X0200Y         S0      
317m3386            VIA   -    MD0100PA00X+015554Y+137631X0200Y         S0      
317m3386            VIA   -    MD0100PA00X+015554Y+137921X0200Y         S0      
317m3386            VIA   -    MD0100PA00X+012294Y+137631X0200Y         S0      
317m3386            VIA   -    MD0100PA00X+012501Y+137458X0200Y         S0      
317m3386            VIA   -    MD0100PA00X+012721Y+137608X0200Y         S0      
317m3386            VIA   -    MD0100PA00X+012294Y+137921X0200Y         S0      
317m3386            VIA   -    MD0100PA00X+012511Y+137758X0200Y         S0      
317m3386            VIA   -    MD0100PA00X+012721Y+137898X0200Y         S0      
317m3386            VIA   -    MD0100PA00X+022541Y+137318X0200Y         S0      
317m3386            VIA   -    MD0100PA00X+021595Y+137287X0193Y         S0      
317m3386            VIA   -    MD0100PA00X+021352Y+137287X0193Y         S0      
317m3386            VIA   -    MD0100PA00X+021940Y+136717X0200Y         S0      
317m3386            VIA   -    MD0100PA00X+021940Y+137007X0200Y         S0      
317m3386            VIA   -    MD0100PA00X+021838Y+137287X0193Y         S0      
327m3386            PU39  -25_2M      A01X+021690Y+137008X0810Y0910R270 S1      
317m3386            VIA   -    MD0100PA00X+019251Y+137318X0200Y         S0      
317m3386            VIA   -    MD0100PA00X+018648Y+136725X0200Y         S0      
317m3386            VIA   -    MD0100PA00X+018648Y+137015X0200Y         S0      
317m3386            VIA   -    MD0100PA00X+018062Y+137287X0193Y         S0      
317m3386            VIA   -    MD0100PA00X+018305Y+137287X0193Y         S0      
317m3386            VIA   -    MD0100PA00X+018548Y+137287X0193Y         S0      
327m3386            PU40  -25_2M      A01X+018400Y+137008X0810Y0910R270 S1      
317m3386            VIA   -    MD0100PA00X+015981Y+137318X0200Y         S0      
317m3386            VIA   -    MD0100PA00X+015374Y+136708X0200Y         S0      
317m3386            VIA   -    MD0100PA00X+015374Y+136998X0200Y         S0      
317m3386            VIA   -    MD0100PA00X+014792Y+137287X0193Y         S0      
317m3386            VIA   -    MD0100PA00X+015035Y+137287X0193Y         S0      
317m3386            VIA   -    MD0100PA00X+015278Y+137287X0193Y         S0      
327m3386            PU52  -25_2M      A01X+015130Y+137008X0810Y0910R270 S1      
317m3386            VIA   -    MD0100PA00X+012721Y+137318X0200Y         S0      
317m3386            VIA   -    MD0100PA00X+012124Y+136995X0200Y         S0      
317m3386            VIA   -    MD0100PA00X+012124Y+136705X0200Y         S0      
317m3386            VIA   -    MD0100PA00X+011775Y+137287X0193Y         S0      
317m3386            VIA   -    MD0100PA00X+012018Y+137287X0193Y         S0      
317m3386            VIA   -    MD0100PA00X+011532Y+137287X0193Y         S0      
327m3386            PU53  -25_2M      A01X+011870Y+137008X0810Y0910R270 S1      
327m3387            PC7000-1          A18X+114442Y+139308X0400Y0500R270 S2      
327m3387            PL19  -1          A01X+113356Y+140904X0650Y1030R090 S1      
327m3387            PU17  -30         A01X+119065Y+137644X0090Y0240     S1      
327m3387            PC178_-1          A01X+119754Y+138209X0198Y0197     S1      
327m3387            PU18  -30         A01X+115775Y+137644X0090Y0240     S1      
327m3387            PC148_-1          A01X+116468Y+138229X0198Y0197     S1      
327m3387            PC149_-1          A01X+113178Y+138229X0198Y0197     S1      
327m3387            PU19  -30         A01X+112505Y+137644X0090Y0240     S1      
327m3387            PC177_-1          A01X+109908Y+138229X0198Y0197     S1      
327m3387            PU20  -30         A01X+109245Y+137644X0090Y0240     S1      
327m3387            PC150_-1          A01X+119685Y+136719X0198Y0197R270 S1      
327m3387            PC151_-1          A01X+116395Y+136719X0198Y0197R270 S1      
327m3387            PC179_-1          A01X+113125Y+136719X0198Y0197R270 S1      
327m3387            PC180_-1          A01X+109865Y+136719X0198Y0197R270 S1      
317m3387            PC164 -1   MD0400PA00X+116654Y+141248X0600Y0600R180 S3      
327m3387            PC154_-1          A18X+118696Y+137704X0400Y0500R090 S2      
327m3387            PC157_-1          A18X+115406Y+137704X0400Y0500R090 S2      
327m3387            PC187_-1          A18X+112136Y+137704X0400Y0500R090 S2      
327m3387            PC188_-1          A18X+108876Y+137704X0400Y0500R090 S2      
327m3387            PC158_-1          A18X+119533Y+136879X0400Y0500R270 S2      
327m3387            PC152_-1          A18X+118696Y+136879X0400Y0500R270 S2      
327m3387            PC159_-1          A18X+116243Y+136879X0400Y0500R270 S2      
327m3387            PC153_-1          A18X+115406Y+136879X0400Y0500R270 S2      
327m3387            PC184_-1          A18X+112973Y+136879X0400Y0500R270 S2      
327m3387            PC181_-1          A18X+112136Y+136879X0400Y0500R270 S2      
327m3387            PC182_-1          A18X+108876Y+136879X0400Y0500R270 S2      
327m3387            PC185_-1          A18X+109713Y+136879X0400Y0500R270 S2      
317m3387            VIA   -    MD0100PA00X+113746Y+140388X0200Y    R180 S0      
317m3387            VIA   -    MD0100PA00X+113496Y+140388X0200Y    R180 S0      
317m3387            VIA   -    MD0100PA00X+113496Y+140138X0200Y    R180 S0      
317m3387            VIA   -    MD0100PA00X+113746Y+140138X0200Y    R180 S0      
317m3387            VIA   -    MD0100PA00X+113742Y+139874X0200Y    R180 S0      
317m3387            VIA   -    MD0100PA00X+113242Y+139874X0200Y    R180 S0      
317m3387            VIA   -    MD0100PA00X+113492Y+139874X0200Y    R180 S0      
317m3387            VIA   -    MD0100PA00X+112742Y+139874X0200Y    R180 S0      
317m3387            VIA   -    MD0100PA00X+112992Y+139874X0200Y    R180 S0      
317m3387            VIA   -    MD0100PA00X+113246Y+140138X0200Y    R180 S0      
317m3387            VIA   -    MD0100PA00X+113246Y+140388X0200Y    R180 S0      
317m3387            VIA   -    MD0100PA00X+112746Y+140138X0200Y    R180 S0      
317m3387            VIA   -    MD0100PA00X+112996Y+140138X0200Y    R180 S0      
317m3387            VIA   -    MD0100PA00X+112746Y+140388X0200Y    R180 S0      
317m3387            VIA   -    MD0100PA00X+112996Y+140388X0200Y    R180 S0      
317m3387            VIA   -    MD0100PA00X+119715Y+137606X0200Y         S0      
317m3387            VIA   -    MD0100PA00X+119495Y+137456X0200Y         S0      
317m3387            VIA   -    MD0100PA00X+119288Y+137629X0200Y         S0      
317m3387            VIA   -    MD0100PA00X+119715Y+137896X0200Y         S0      
317m3387            VIA   -    MD0100PA00X+119505Y+137756X0200Y         S0      
317m3387            VIA   -    MD0100PA00X+119288Y+137919X0200Y         S0      
317m3387            VIA   -    MD0100PA00X+116215Y+137756X0200Y         S0      
317m3387            VIA   -    MD0100PA00X+115998Y+137919X0200Y         S0      
317m3387            VIA   -    MD0100PA00X+116425Y+137896X0200Y         S0      
317m3387            VIA   -    MD0100PA00X+116205Y+137456X0200Y         S0      
317m3387            VIA   -    MD0100PA00X+115998Y+137629X0200Y         S0      
317m3387            VIA   -    MD0100PA00X+116425Y+137606X0200Y         S0      
317m3387            VIA   -    MD0100PA00X+113155Y+137606X0200Y         S0      
317m3387            VIA   -    MD0100PA00X+113155Y+137896X0200Y         S0      
317m3387            VIA   -    MD0100PA00X+112935Y+137456X0200Y         S0      
317m3387            VIA   -    MD0100PA00X+112728Y+137629X0200Y         S0      
317m3387            VIA   -    MD0100PA00X+112945Y+137756X0200Y         S0      
317m3387            VIA   -    MD0100PA00X+112728Y+137919X0200Y         S0      
317m3387            VIA   -    MD0100PA00X+109675Y+137456X0200Y         S0      
317m3387            VIA   -    MD0100PA00X+109895Y+137606X0200Y         S0      
317m3387            VIA   -    MD0100PA00X+109468Y+137629X0200Y         S0      
317m3387            VIA   -    MD0100PA00X+109685Y+137756X0200Y         S0      
317m3387            VIA   -    MD0100PA00X+109895Y+137896X0200Y         S0      
317m3387            VIA   -    MD0100PA00X+109468Y+137919X0200Y         S0      
317m3387            VIA   -    MD0100PA00X+119715Y+137316X0200Y         S0      
317m3387            VIA   -    MD0100PA00X+118526Y+137285X0193Y         S0      
317m3387            VIA   -    MD0100PA00X+118769Y+137285X0193Y         S0      
317m3387            VIA   -    MD0100PA00X+119105Y+137009X0200Y         S0      
317m3387            VIA   -    MD0100PA00X+119105Y+136719X0200Y         S0      
317m3387            VIA   -    MD0100PA00X+119012Y+137285X0193Y         S0      
327m3387            PU17  -25_2M      A01X+118864Y+137006X0810Y0910R270 S1      
317m3387            VIA   -    MD0100PA00X+116425Y+137316X0200Y         S0      
317m3387            VIA   -    MD0100PA00X+115806Y+136992X0200Y         S0      
317m3387            VIA   -    MD0100PA00X+115806Y+136702X0200Y         S0      
317m3387            VIA   -    MD0100PA00X+115479Y+137285X0193Y         S0      
317m3387            VIA   -    MD0100PA00X+115236Y+137285X0193Y         S0      
317m3387            VIA   -    MD0100PA00X+115722Y+137285X0193Y         S0      
327m3387            PU18  -25_2M      A01X+115574Y+137006X0810Y0910R270 S1      
317m3387            VIA   -    MD0100PA00X+113155Y+137316X0200Y         S0      
317m3387            VIA   -    MD0100PA00X+112547Y+137001X0200Y         S0      
317m3387            VIA   -    MD0100PA00X+112547Y+136711X0200Y         S0      
317m3387            VIA   -    MD0100PA00X+112209Y+137285X0193Y         S0      
317m3387            VIA   -    MD0100PA00X+111966Y+137285X0193Y         S0      
317m3387            VIA   -    MD0100PA00X+112452Y+137285X0193Y         S0      
327m3387            PU19  -25_2M      A01X+112304Y+137006X0810Y0910R270 S1      
317m3387            VIA   -    MD0100PA00X+109895Y+137316X0200Y         S0      
317m3387            VIA   -    MD0100PA00X+109289Y+137018X0200Y         S0      
317m3387            VIA   -    MD0100PA00X+109289Y+136728X0200Y         S0      
317m3387            VIA   -    MD0100PA00X+109192Y+137285X0193Y         S0      
317m3387            VIA   -    MD0100PA00X+108949Y+137285X0193Y         S0      
317m3387            VIA   -    MD0100PA00X+108706Y+137285X0193Y         S0      
327m3387            PU20  -25_2M      A01X+109044Y+137006X0810Y0910R270 S1      
327m3388            PC8012-1          A18X+046201Y+064626X0400Y0500R090 S2      
327m3388            PC8011-1          A18X+049528Y+061216X0400Y0500R090 S2      
317m3388            VIA   -    MD0100PA00X+046021Y+060101X0200Y    R180 S0      
317m3388            VIA   -    MD0100PA00X+045771Y+060101X0200Y    R180 S0      
317m3388            VIA   -    MD0100PA00X+046021Y+059851X0200Y    R180 S0      
317m3388            VIA   -    MD0100PA00X+045771Y+059851X0200Y    R180 S0      
317m3388            VIA   -    MD0100PA00X+044721Y+067454X0200Y    R180 S0      
317m3388            VIA   -    MD0100PA00X+044721Y+067164X0200Y    R180 S0      
317m3388            VIA   -    MD0100PA00X+047981Y+064814X0200Y    R180 S0      
317m3388            VIA   -    MD0100PA00X+047981Y+064524X0200Y    R180 S0      
317m3388            VIA   -    MD0100PA00X+051301Y+061394X0200Y    R180 S0      
317m3388            VIA   -    MD0100PA00X+051301Y+061104X0200Y    R180 S0      
327m3388            PC323_-1          A01X+044114Y+067484X0198Y0197R090 S1      
327m3388            PC325_-1          A01X+043731Y+067485X0198Y0197R090 S1      
327m3388            PU30  -30         A01X+044734Y+066545X0090Y0240R180 S1      
327m3388            PC324_-1          A01X+047373Y+064846X0198Y0197R090 S1      
327m3388            PC326_-1          A01X+046988Y+064846X0198Y0197R090 S1      
327m3388            PU31  -30         A01X+047994Y+063895X0090Y0240R180 S1      
327m3388            PC349_-1          A01X+050696Y+061435X0198Y0197R090 S1      
327m3388            PC348_-1          A01X+050300Y+061434X0198Y0197R090 S1      
327m3388            PU32  -30         A01X+051324Y+060485X0090Y0240R180 S1      
327m3388            PL37  -1          A01X+046658Y+059376X0650Y1030R270 S1      
327m3388            PC327_-1          A18X+045055Y+066548X0400Y0500R270 S2      
327m3388            PC329_-1          A18X+045121Y+067282X0400Y0500R090 S2      
327m3388            PC331_-1          A18X+044311Y+067282X0400Y0500R090 S2      
327m3388            PC330_-1          A18X+048381Y+064642X0400Y0500R090 S2      
327m3388            PC332_-1          A18X+047581Y+064642X0400Y0500R090 S2      
327m3388            PC335_-1          A18X+046891Y+064642X0400Y0500R090 S2      
327m3388            PC334_-1          A18X+043625Y+067278X0400Y0500R090 S2      
327m3388            PC328_-1          A18X+048325Y+063898X0400Y0500R270 S2      
327m3388            PC350_-1          A18X+051701Y+061222X0400Y0500R090 S2      
327m3388            PC351_-1          A18X+050901Y+061222X0400Y0500R090 S2      
327m3388            PC352_-1          A18X+051635Y+060478X0400Y0500R270 S2      
327m3388            PC353_-1          A18X+050211Y+061222X0400Y0500R090 S2      
317m3388            PC336 -1   MD0400PA00X+043362Y+059426X0600Y0600R090 S3      
317m3388            VIA   -    MD0100PA00X+044511Y+066560X0200Y    R180 S0      
317m3388            VIA   -    MD0100PA00X+044304Y+066733X0200Y    R180 S0      
317m3388            VIA   -    MD0100PA00X+044084Y+066293X0200Y    R180 S0      
317m3388            VIA   -    MD0100PA00X+044294Y+066433X0200Y    R180 S0      
317m3388            VIA   -    MD0100PA00X+044511Y+066270X0200Y    R180 S0      
317m3388            VIA   -    MD0100PA00X+044084Y+066583X0200Y    R180 S0      
317m3388            VIA   -    MD0100PA00X+044084Y+066873X0200Y    R180 S0      
327m3388            PU30  -25_2M      A01X+044935Y+067182X0810Y0910R090 S1      
317m3388            VIA   -    MD0100PA00X+044788Y+066904X0193Y    R180 S0      
317m3388            VIA   -    MD0100PA00X+045274Y+066904X0193Y    R180 S0      
317m3388            VIA   -    MD0100PA00X+045030Y+066904X0193Y    R180 S0      
317m3388            VIA   -    MD0100PA00X+047771Y+063620X0200Y    R180 S0      
317m3388            VIA   -    MD0100PA00X+047344Y+063643X0200Y    R180 S0      
317m3388            VIA   -    MD0100PA00X+047554Y+063783X0200Y    R180 S0      
317m3388            VIA   -    MD0100PA00X+047344Y+063933X0200Y    R180 S0      
317m3388            VIA   -    MD0100PA00X+047564Y+064083X0200Y    R180 S0      
317m3388            VIA   -    MD0100PA00X+047771Y+063910X0200Y    R180 S0      
317m3388            VIA   -    MD0100PA00X+047344Y+064223X0200Y    R180 S0      
317m3388            VIA   -    MD0100PA00X+048290Y+064254X0193Y    R180 S0      
317m3388            VIA   -    MD0100PA00X+048048Y+064254X0193Y    R180 S0      
317m3388            VIA   -    MD0100PA00X+048534Y+064254X0193Y    R180 S0      
327m3388            PU31  -25_2M      A01X+048195Y+064532X0810Y0910R090 S1      
317m3388            VIA   -    MD0100PA00X+051101Y+060500X0200Y    R180 S0      
317m3388            VIA   -    MD0100PA00X+051101Y+060210X0200Y    R180 S0      
317m3388            VIA   -    MD0100PA00X+050884Y+060373X0200Y    R180 S0      
317m3388            VIA   -    MD0100PA00X+050674Y+060523X0200Y    R180 S0      
317m3388            VIA   -    MD0100PA00X+050674Y+060233X0200Y    R180 S0      
317m3388            VIA   -    MD0100PA00X+050894Y+060673X0200Y    R180 S0      
317m3388            VIA   -    MD0100PA00X+050674Y+060813X0200Y    R180 S0      
317m3388            VIA   -    MD0100PA00X+051378Y+060844X0193Y    R180 S0      
317m3388            VIA   -    MD0100PA00X+051864Y+060844X0193Y    R180 S0      
317m3388            VIA   -    MD0100PA00X+051620Y+060844X0193Y    R180 S0      
327m3388            PU32  -25_2M      A01X+051525Y+061122X0810Y0910R090 S1      
317m3388            VIA   -    MD0100PA00X+046533Y+060101X0200Y    R180 S0      
317m3388            VIA   -    MD0100PA00X+047033Y+060101X0200Y    R180 S0      
317m3388            VIA   -    MD0100PA00X+046783Y+060101X0200Y    R180 S0      
317m3388            VIA   -    MD0100PA00X+046283Y+060101X0200Y    R180 S0      
317m3388            VIA   -    MD0100PA00X+046533Y+059851X0200Y    R180 S0      
317m3388            VIA   -    MD0100PA00X+047033Y+059851X0200Y    R180 S0      
317m3388            VIA   -    MD0100PA00X+046783Y+059851X0200Y    R180 S0      
317m3388            VIA   -    MD0100PA00X+046283Y+059851X0200Y    R180 S0      
327m3389            PC585_-1          A01X+155183Y+069546X0198Y0197R090 S1      
327m3389            PC583_-1          A01X+154783Y+069546X0198Y0197R090 S1      
327m3389            PU49  -30         A01X+155813Y+068611X0090Y0240R180 S1      
327m3389            PC586_-1          A01X+158060Y+066185X0198Y0197R090 S1      
327m3389            PC584_-1          A01X+158460Y+066185X0198Y0197R090 S1      
327m3389            PU50  -30         A01X+159090Y+065234X0090Y0240R180 S1      
327m3389            PU51  -30         A01X+162390Y+063334X0090Y0240R180 S1      
327m3389            PC609_-1          A01X+161360Y+064285X0198Y0197R090 S1      
327m3389            PC608_-1          A01X+161760Y+064285X0198Y0197R090 S1      
327m3389            PL65  -1          A01X+152001Y+060934X0650Y1030R180 S1      
327m3389            PC8009-1          A18X+157039Y+066380X0400Y0500R090 S2      
327m3389            PC8010-1          A18X+160450Y+063523X0400Y0500R090 S2      
317m3389            VIA   -    MD0100PA00X+152728Y+061812X0200Y    R180 S0      
317m3389            VIA   -    MD0100PA00X+152478Y+061812X0200Y    R180 S0      
317m3389            VIA   -    MD0100PA00X+152728Y+061562X0200Y    R180 S0      
317m3389            VIA   -    MD0100PA00X+152478Y+061562X0200Y    R180 S0      
317m3389            VIA   -    MD0100PA00X+159096Y+065874X0200Y    R180 S0      
317m3389            VIA   -    MD0100PA00X+159096Y+066174X0200Y    R180 S0      
317m3389            VIA   -    MD0100PA00X+162396Y+063974X0200Y    R180 S0      
317m3389            VIA   -    MD0100PA00X+162396Y+064274X0200Y    R180 S0      
317m3389            VIA   -    MD0100PA00X+155819Y+069250X0200Y    R180 S0      
317m3389            VIA   -    MD0100PA00X+155819Y+069550X0200Y    R180 S0      
327m3389            PC589_-1          A18X+156219Y+069451X0400Y0500R090 S2      
327m3389            PC591_-1          A18X+155419Y+069451X0400Y0500R090 S2      
327m3389            PC587_-1          A18X+156146Y+068616X0400Y0500R270 S2      
327m3389            PC590_-1          A18X+159496Y+066074X0400Y0500R090 S2      
327m3389            PC592_-1          A18X+158696Y+066074X0400Y0500R090 S2      
327m3389            PC595_-1          A18X+158007Y+066076X0400Y0500R090 S2      
327m3389            PC593_-1          A18X+155509Y+067110X0400Y0500     S2      
327m3389            PC588_-1          A18X+159418Y+065234X0400Y0500R270 S2      
327m3389            PC610_-1          A18X+161996Y+064174X0400Y0500R090 S2      
327m3389            PC611_-1          A18X+162718Y+063338X0400Y0500R270 S2      
327m3389            PC613_-1          A18X+162796Y+064174X0400Y0500R090 S2      
327m3389            PC612_-1          A18X+161269Y+063630X0400Y0500R090 S2      
317m3389            PC596 -1   MD0400PA00X+152444Y+064036X0600Y0600R180 S3      
317m3389            VIA   -    MD0100PA00X+155866Y+068970X0193Y    R180 S0      
317m3389            VIA   -    MD0100PA00X+156109Y+068970X0193Y    R180 S0      
317m3389            VIA   -    MD0100PA00X+156352Y+068970X0193Y    R180 S0      
327m3389            PU49  -25_2M      A01X+156014Y+069248X0810Y0910R090 S1      
317m3389            VIA   -    MD0100PA00X+155373Y+068499X0200Y    R180 S0      
317m3389            VIA   -    MD0100PA00X+155366Y+068196X0200Y    R180 S0      
317m3389            VIA   -    MD0100PA00X+155589Y+068336X0200Y    R180 S0      
317m3389            VIA   -    MD0100PA00X+155589Y+068626X0200Y    R180 S0      
317m3389            VIA   -    MD0100PA00X+155603Y+068039X0200Y    R180 S0      
317m3389            VIA   -    MD0100PA00X+155383Y+068799X0200Y    R180 S0      
317m3389            VIA   -    MD0100PA00X+155366Y+067896X0200Y    R180 S0      
317m3389            VIA   -    MD0100PA00X+158866Y+065249X0200Y    R180 S0      
317m3389            VIA   -    MD0100PA00X+158866Y+064959X0200Y    R180 S0      
327m3389            PU50  -25_2M      A01X+159290Y+065872X0810Y0910R090 S1      
317m3389            VIA   -    MD0100PA00X+159386Y+065593X0193Y    R180 S0      
317m3389            VIA   -    MD0100PA00X+159143Y+065593X0193Y    R180 S0      
317m3389            VIA   -    MD0100PA00X+159629Y+065593X0193Y    R180 S0      
317m3389            VIA   -    MD0100PA00X+158440Y+064982X0200Y    R180 S0      
317m3389            VIA   -    MD0100PA00X+158440Y+065272X0200Y    R180 S0      
317m3389            VIA   -    MD0100PA00X+158660Y+065422X0200Y    R180 S0      
317m3389            VIA   -    MD0100PA00X+158650Y+065122X0200Y    R180 S0      
317m3389            VIA   -    MD0100PA00X+158440Y+065562X0200Y    R180 S0      
317m3389            VIA   -    MD0100PA00X+161950Y+063222X0200Y    R180 S0      
317m3389            VIA   -    MD0100PA00X+162166Y+063349X0200Y    R180 S0      
317m3389            VIA   -    MD0100PA00X+161960Y+063522X0200Y    R180 S0      
317m3389            VIA   -    MD0100PA00X+162166Y+063059X0200Y    R180 S0      
317m3389            VIA   -    MD0100PA00X+162443Y+063693X0193Y    R180 S0      
317m3389            VIA   -    MD0100PA00X+162929Y+063693X0193Y    R180 S0      
317m3389            VIA   -    MD0100PA00X+162686Y+063693X0193Y    R180 S0      
327m3389            PU51  -25_2M      A01X+162590Y+063972X0810Y0910R090 S1      
317m3389            VIA   -    MD0100PA00X+161740Y+063372X0200Y    R180 S0      
317m3389            VIA   -    MD0100PA00X+161740Y+063662X0200Y    R180 S0      
317m3389            VIA   -    MD0100PA00X+161740Y+063082X0200Y    R180 S0      
317m3389            VIA   -    MD0100PA00X+152728Y+061309X0200Y    R180 S0      
317m3389            VIA   -    MD0100PA00X+152478Y+061309X0200Y    R180 S0      
317m3389            VIA   -    MD0100PA00X+152728Y+061059X0200Y    R180 S0      
317m3389            VIA   -    MD0100PA00X+152478Y+061059X0200Y    R180 S0      
317m3389            VIA   -    MD0100PA00X+152728Y+060799X0200Y    R180 S0      
317m3389            VIA   -    MD0100PA00X+152728Y+060549X0200Y    R180 S0      
317m3389            VIA   -    MD0100PA00X+152478Y+060799X0200Y    R180 S0      
317m3389            VIA   -    MD0100PA00X+152478Y+060549X0200Y    R180 S0      
317m3390            VIA   -    MD0100PA00X+035163Y+135920X0200Y         S0      
327m3390            PC415_-1          A18X+024802Y+137705X0400Y0500R090 S2      
327m3390            PC411_-1          A18X+025640Y+136881X0400Y0500R270 S2      
327m3390            PC409_-1          A18X+024802Y+136881X0400Y0500R270 S2      
327m3390            PC147_-1          A18X+041280Y+135035X0400Y0500R090 S2      
327m3390            PC144_-1          A18X+041280Y+134211X0400Y0500R270 S2      
327m3390            PC145_-1          A18X+042118Y+134211X0400Y0500R270 S2      
327m3390            PC429_-1          A18X+038022Y+133102X0400Y0500R090 S2      
327m3390            PC379_-1          A18X+034742Y+133082X0400Y0500R090 S2      
327m3390            PC385_-1          A18X+031451Y+133088X0400Y0500R090 S2      
327m3390            PC410_-1          A18X+028162Y+133091X0400Y0500R090 S2      
327m3390            PC426_-1          A18X+038860Y+132278X0400Y0500R270 S2      
327m3390            PC427_-1          A18X+038022Y+132278X0400Y0500R270 S2      
327m3390            PC384_-1          A18X+035580Y+132258X0400Y0500R270 S2      
327m3390            PC381_-1          A18X+034742Y+132258X0400Y0500R270 S2      
327m3390            PC380_-1          A18X+032289Y+132264X0400Y0500R270 S2      
327m3390            PC382_-1          A18X+031451Y+132264X0400Y0500R270 S2      
327m3390            PC412_-1          A18X+029000Y+132266X0400Y0500R270 S2      
327m3390            PC416_-1          A18X+028162Y+132266X0400Y0500R270 S2      
317m3390            VIA   -    MD0100PA00X+030516Y+138689X0200Y         S0      
317m3390            VIA   -    MD0100PA00X+029468Y+138704X0200Y         S0      
317m3390            VIA   -    MD0100PA00X+030516Y+138968X0200Y         S0      
317m3390            VIA   -    MD0100PA00X+029468Y+139028X0200Y         S0      
317m3390            VIA   -    MD0100PA00X+030501Y+138425X0200Y         S0      
317m3390            VIA   -    MD0100PA00X+030520Y+138146X0200Y         S0      
317m3390            VIA   -    MD0100PA00X+029453Y+138440X0200Y         S0      
317m3390            VIA   -    MD0100PA00X+029472Y+138161X0200Y         S0      
317m3390            VIA   -    MD0100PA00X+032371Y+137950X0200Y         S0      
317m3390            VIA   -    MD0100PA00X+033419Y+137890X0200Y         S0      
317m3390            VIA   -    MD0100PA00X+032375Y+137083X0200Y         S0      
317m3390            VIA   -    MD0100PA00X+032356Y+137362X0200Y         S0      
317m3390            VIA   -    MD0100PA00X+032371Y+137626X0200Y         S0      
317m3390            VIA   -    MD0100PA00X+033423Y+137068X0200Y         S0      
317m3390            VIA   -    MD0100PA00X+033404Y+137347X0200Y         S0      
317m3390            VIA   -    MD0100PA00X+033419Y+137611X0200Y         S0      
317m3390            VIA   -    MD0100PA00X+035976Y+135930X0200Y         S0      
317m3390            VIA   -    MD0100PA00X+036226Y+135930X0200Y         S0      
317m3390            VIA   -    MD0100PA00X+036476Y+135930X0200Y         S0      
317m3390            VIA   -    MD0100PA00X+035426Y+135930X0200Y         S0      
317m3390            VIA   -    MD0100PA00X+035676Y+135930X0200Y         S0      
317m3390            VIA   -    MD0100PA00X+036457Y+136208X0200Y         S0      
317m3390            VIA   -    MD0100PA00X+036207Y+136208X0200Y         S0      
317m3390            VIA   -    MD0100PA00X+035927Y+136208X0200Y         S0      
317m3390            VIA   -    MD0100PA00X+035677Y+136208X0200Y         S0      
317m3390            VIA   -    MD0100PA00X+035427Y+136208X0200Y         S0      
317m3390            VIA   -    MD0100PA00X+035177Y+136208X0200Y         S0      
327m3390            PC390 -1          A01X+032899Y+137665X0630Y1380     S1      
327m3390            PC393 -1          A01X+030004Y+138704X0630Y1380     S1      
317m3390            VIA   -    MD0100PA00X+036472Y+136472X0200Y         S0      
317m3390            VIA   -    MD0100PA00X+036222Y+136472X0200Y         S0      
317m3390            VIA   -    MD0100PA00X+035942Y+136472X0200Y         S0      
317m3390            VIA   -    MD0100PA00X+035692Y+136472X0200Y         S0      
317m3390            VIA   -    MD0100PA00X+035442Y+136472X0200Y         S0      
317m3390            VIA   -    MD0100PA00X+035192Y+136472X0200Y         S0      
327m3390            PL42  -1          A01X+035625Y+136997X0650Y1030R090 S1      
327m3390            PU36  -30         A01X+025171Y+137646X0090Y0240     S1      
327m3390            PC405_-1          A01X+026178Y+136720X0198Y0197R270 S1      
327m3390            PC407_-1          A01X+025791Y+136721X0198Y0197R270 S1      
327m3390            PU33  -30         A01X+041649Y+134976X0090Y0240     S1      
327m3390            PC141_-1          A01X+042656Y+134049X0198Y0197R270 S1      
327m3390            PC140_-1          A01X+042269Y+134051X0198Y0197R270 S1      
327m3390            PU38  -30         A01X+038391Y+133043X0090Y0240     S1      
327m3390            PU35  -30         A01X+035111Y+133023X0090Y0240     S1      
327m3390            PC425_-1          A01X+035794Y+133627X0198Y0197     S1      
327m3390            PC375_-1          A01X+032514Y+133607X0198Y0197     S1      
327m3390            PU5   -30         A01X+031821Y+133029X0090Y0240     S1      
327m3390            PC376_-1          A01X+029224Y+133613X0198Y0197     S1      
327m3390            PU37  -30         A01X+028531Y+133032X0090Y0240     S1      
327m3390            PC408_-1          A01X+028754Y+134270X0198Y0197R180 S1      
327m3390            PC424_-1          A01X+039011Y+132118X0198Y0197R270 S1      
327m3390            PC377_-1          A01X+035731Y+132098X0198Y0197R270 S1      
327m3390            PC378_-1          A01X+032456Y+132100X0198Y0197R270 S1      
327m3390            PC406_-1          A01X+029151Y+132086X0198Y0197R270 S1      
317m3390            VIA   -    MD0100PA00X+025394Y+137631X0200Y         S0      
317m3390            VIA   -    MD0100PA00X+025394Y+137921X0200Y         S0      
317m3390            VIA   -    MD0100PA00X+025821Y+137608X0200Y         S0      
317m3390            VIA   -    MD0100PA00X+025601Y+137458X0200Y         S0      
317m3390            VIA   -    MD0100PA00X+025821Y+137898X0200Y         S0      
317m3390            VIA   -    MD0100PA00X+025611Y+137758X0200Y         S0      
317m3390            VIA   -    MD0100PA00X+025821Y+137318X0200Y         S0      
317m3390            VIA   -    MD0100PA00X+024632Y+137287X0193Y         S0      
317m3390            VIA   -    MD0100PA00X+025221Y+136733X0193Y         S0      
317m3390            VIA   -    MD0100PA00X+025221Y+137023X0193Y         S0      
317m3390            VIA   -    MD0100PA00X+025118Y+137287X0193Y         S0      
317m3390            VIA   -    MD0100PA00X+024875Y+137287X0193Y         S0      
327m3390            PU36  -25_2M      A01X+024970Y+137008X0810Y0910R270 S1      
317m3390            VIA   -    MD0100PA00X+041868Y+134927X0200Y         S0      
317m3390            VIA   -    MD0100PA00X+041868Y+135217X0200Y         S0      
317m3390            VIA   -    MD0100PA00X+042120Y+134569X0200Y         S0      
317m3390            VIA   -    MD0100PA00X+042120Y+134859X0200Y         S0      
317m3390            VIA   -    MD0100PA00X+042132Y+135138X0200Y         S0      
317m3390            VIA   -    MD0100PA00X+042132Y+135428X0200Y         S0      
317m3390            VIA   -    MD0100PA00X+041706Y+134342X0193Y         S0      
317m3390            VIA   -    MD0100PA00X+041706Y+134052X0193Y         S0      
317m3390            VIA   -    MD0100PA00X+041110Y+134617X0193Y         S0      
317m3390            VIA   -    MD0100PA00X+041353Y+134617X0193Y         S0      
317m3390            VIA   -    MD0100PA00X+041596Y+134617X0193Y         S0      
327m3390            PU33  -25_2M      A01X+041448Y+134338X0810Y0910R270 S1      
317m3390            VIA   -    MD0100PA00X+038877Y+133455X0200Y         S0      
317m3390            VIA   -    MD0100PA00X+038877Y+133755X0200Y         S0      
317m3390            VIA   -    MD0100PA00X+038661Y+133606X0200Y         S0      
317m3390            VIA   -    MD0100PA00X+038614Y+133028X0200Y         S0      
317m3390            VIA   -    MD0100PA00X+038614Y+133318X0200Y         S0      
317m3390            VIA   -    MD0100PA00X+038831Y+133155X0200Y         S0      
317m3390            VIA   -    MD0100PA00X+035761Y+133275X0200Y         S0      
317m3390            VIA   -    MD0100PA00X+035551Y+133135X0200Y         S0      
317m3390            VIA   -    MD0100PA00X+035334Y+133008X0200Y         S0      
317m3390            VIA   -    MD0100PA00X+035761Y+132985X0200Y         S0      
317m3390            VIA   -    MD0100PA00X+035334Y+133298X0200Y         S0      
317m3390            VIA   -    MD0100PA00X+032471Y+132990X0200Y         S0      
317m3390            VIA   -    MD0100PA00X+032261Y+133140X0200Y         S0      
317m3390            VIA   -    MD0100PA00X+032471Y+133280X0200Y         S0      
317m3390            VIA   -    MD0100PA00X+032044Y+133303X0200Y         S0      
317m3390            VIA   -    MD0100PA00X+032044Y+133013X0200Y         S0      
317m3390            VIA   -    MD0100PA00X+029181Y+132993X0200Y         S0      
317m3390            VIA   -    MD0100PA00X+029181Y+133283X0200Y         S0      
317m3390            VIA   -    MD0100PA00X+028754Y+133306X0200Y         S0      
317m3390            VIA   -    MD0100PA00X+028754Y+133016X0200Y         S0      
317m3390            VIA   -    MD0100PA00X+028971Y+133143X0200Y         S0      
317m3390            VIA   -    MD0100PA00X+038821Y+132855X0200Y         S0      
317m3390            VIA   -    MD0100PA00X+037852Y+132684X0193Y         S0      
317m3390            VIA   -    MD0100PA00X+038095Y+132684X0193Y         S0      
317m3390            VIA   -    MD0100PA00X+038448Y+132409X0193Y         S0      
317m3390            VIA   -    MD0100PA00X+038448Y+132119X0193Y         S0      
317m3390            VIA   -    MD0100PA00X+038338Y+132684X0193Y         S0      
327m3390            PU38  -25_2M      A01X+038190Y+132405X0810Y0910R270 S1      
317m3390            VIA   -    MD0100PA00X+035541Y+132835X0200Y         S0      
317m3390            VIA   -    MD0100PA00X+035761Y+132695X0200Y         S0      
317m3390            VIA   -    MD0100PA00X+034572Y+132664X0193Y         S0      
317m3390            VIA   -    MD0100PA00X+035058Y+132664X0193Y         S0      
317m3390            VIA   -    MD0100PA00X+034815Y+132664X0193Y         S0      
317m3390            VIA   -    MD0100PA00X+035165Y+132384X0193Y         S0      
317m3390            VIA   -    MD0100PA00X+035165Y+132094X0193Y         S0      
327m3390            PU35  -25_2M      A01X+034910Y+132385X0810Y0910R270 S1      
317m3390            VIA   -    MD0100PA00X+032251Y+132840X0200Y         S0      
317m3390            VIA   -    MD0100PA00X+032471Y+132700X0200Y         S0      
317m3390            VIA   -    MD0100PA00X+031881Y+132380X0193Y         S0      
317m3390            VIA   -    MD0100PA00X+031881Y+132090X0193Y         S0      
317m3390            VIA   -    MD0100PA00X+031768Y+132670X0193Y         S0      
317m3390            VIA   -    MD0100PA00X+031525Y+132670X0193Y         S0      
317m3390            VIA   -    MD0100PA00X+031282Y+132670X0193Y         S0      
327m3390            PU5   -25_2M      A01X+031620Y+132391X0810Y0910R270 S1      
317m3390            VIA   -    MD0100PA00X+029181Y+132703X0200Y         S0      
317m3390            VIA   -    MD0100PA00X+028961Y+132843X0200Y         S0      
317m3390            VIA   -    MD0100PA00X+028589Y+132384X0193Y         S0      
317m3390            VIA   -    MD0100PA00X+028589Y+132094X0193Y         S0      
317m3390            VIA   -    MD0100PA00X+027992Y+132673X0193Y         S0      
317m3390            VIA   -    MD0100PA00X+028235Y+132673X0193Y         S0      
317m3390            VIA   -    MD0100PA00X+028478Y+132673X0193Y         S0      
327m3390            PU37  -25_2M      A01X+028330Y+132394X0810Y0910R270 S1      
327m3391            PL12  -1   M      A01X+134507Y+139184X0650Y1030R090 S1      
327m3391            PU11  -30         A01X+139262Y+134974X0090Y0240     S1      
327m3391            PC115_-1          A01X+139882Y+134049X0198Y0197R270 S1      
327m3391            PC114_-1          A01X+136683Y+135572X0198Y0197     S1      
327m3391            PU16  -30         A01X+136004Y+133041X0090Y0240     S1      
327m3391            PU13  -30         A01X+132724Y+133021X0090Y0240     S1      
327m3391            PC134_-1          A01X+133407Y+133626X0198Y0197     S1      
327m3391            PU2   -30         A01X+129434Y+133027X0090Y0240     S1      
327m3391            PC85_1-1          A01X+130127Y+133606X0198Y0197     S1      
327m3391            PU15  -30         A01X+126144Y+133030X0090Y0240     S1      
327m3391            PC116_-1          A01X+126367Y+134269X0198Y0197R180 S1      
327m3391            PC86_2-1          A01X+126837Y+133611X0198Y0197     S1      
327m3391            PC135_-1          A01X+136624Y+132116X0198Y0197R270 S1      
327m3391            PC87_1-1          A01X+133344Y+132096X0198Y0197R270 S1      
327m3391            PC88_2-1          A01X+130069Y+132098X0198Y0197R270 S1      
327m3391            PC118_-1          A01X+126764Y+132084X0198Y0197R270 S1      
327m3391            PU14  -30         A01X+122345Y+137644X0090Y0240     S1      
327m3391            PC115_-1          A01X+123352Y+136718X0198Y0197R270 S1      
327m3391            PC117_-1          A01X+122965Y+136719X0198Y0197R270 S1      
327m3391            PC123_-1          A18X+121976Y+137704X0400Y0500R090 S2      
327m3391            PC125_-1          A18X+121976Y+136879X0400Y0500R270 S2      
327m3391            PC119_-1          A18X+122813Y+136879X0400Y0500R270 S2      
317m3391            PC104 -1   MD0400PA00X+132052Y+137572X0600Y0600R180 S3      
317m3391            PC101 -1   MD0400PA00X+129115Y+137572X0600Y0600R180 S3      
327m3391            PC116_-1          A18X+138893Y+135034X0400Y0500R090 S2      
327m3391            PC118_-1          A18X+139731Y+134209X0400Y0500R270 S2      
327m3391            PC119_-1          A18X+138893Y+134209X0400Y0500R270 S2      
327m3391            PC136_-1          A18X+135635Y+133100X0400Y0500R090 S2      
327m3391            PC95_1-1          A18X+132355Y+133080X0400Y0500R090 S2      
327m3391            PC93_2-1          A18X+129064Y+133086X0400Y0500R090 S2      
327m3391            PC126_-1          A18X+125775Y+133089X0400Y0500R090 S2      
327m3391            PC138_-1          A18X+135635Y+132276X0400Y0500R270 S2      
327m3391            PC139_-1          A18X+136472Y+132276X0400Y0500R270 S2      
327m3391            PC89_1-1          A18X+132355Y+132256X0400Y0500R270 S2      
327m3391            PC91_1-1          A18X+133192Y+132256X0400Y0500R270 S2      
327m3391            PC90_2-1          A18X+129902Y+132262X0400Y0500R270 S2      
327m3391            PC96_2-1          A18X+129064Y+132262X0400Y0500R270 S2      
327m3391            PC124_-1          A18X+126612Y+132265X0400Y0500R270 S2      
327m3391            PC120_-1          A18X+125775Y+132265X0400Y0500R270 S2      
317m3391            VIA   -    MD0100PA00X+135222Y+138979X0200Y    R180 S0      
317m3391            VIA   -    MD0100PA00X+135223Y+138380X0200Y    R180 S0      
317m3391            VIA   -    MD0100PA00X+135223Y+138680X0200Y    R180 S0      
317m3391            VIA   -    MD0100PA00X+136227Y+133606X0200Y         S0      
317m3391            VIA   -    MD0100PA00X+134121Y+138980X0200Y         S0      
317m3391            VIA   -    MD0100PA00X+134621Y+138980X0200Y         S0      
317m3391            VIA   -    MD0100PA00X+134871Y+138980X0200Y         S0      
317m3391            VIA   -    MD0100PA00X+134371Y+138980X0200Y         S0      
317m3391            VIA   -    MD0100PA00X+133756Y+138966X0200Y    R180 S0      
317m3391            VIA   -    MD0100PA00X+134956Y+138667X0200Y    R180 S0      
317m3391            VIA   -    MD0100PA00X+134956Y+138367X0200Y    R180 S0      
317m3391            VIA   -    MD0100PA00X+134356Y+138367X0200Y    R180 S0      
317m3391            VIA   -    MD0100PA00X+134356Y+138667X0200Y    R180 S0      
317m3391            VIA   -    MD0100PA00X+134656Y+138367X0200Y    R180 S0      
317m3391            VIA   -    MD0100PA00X+134656Y+138667X0200Y    R180 S0      
317m3391            VIA   -    MD0100PA00X+133756Y+138367X0200Y    R180 S0      
317m3391            VIA   -    MD0100PA00X+133756Y+138667X0200Y    R180 S0      
317m3391            VIA   -    MD0100PA00X+134056Y+138667X0200Y    R180 S0      
317m3391            VIA   -    MD0100PA00X+134056Y+138367X0200Y    R180 S0      
317m3391            VIA   -    MD0100PA00X+122995Y+137606X0200Y         S0      
317m3391            VIA   -    MD0100PA00X+122995Y+137896X0200Y         S0      
317m3391            VIA   -    MD0100PA00X+122775Y+137456X0200Y         S0      
317m3391            VIA   -    MD0100PA00X+122568Y+137629X0200Y         S0      
317m3391            VIA   -    MD0100PA00X+122785Y+137756X0200Y         S0      
317m3391            VIA   -    MD0100PA00X+122568Y+137919X0200Y         S0      
317m3391            VIA   -    MD0100PA00X+122995Y+137316X0200Y         S0      
317m3391            VIA   -    MD0100PA00X+121806Y+137285X0193Y         S0      
317m3391            VIA   -    MD0100PA00X+122389Y+137009X0200Y         S0      
317m3391            VIA   -    MD0100PA00X+122389Y+136719X0200Y         S0      
317m3391            VIA   -    MD0100PA00X+122049Y+137285X0193Y         S0      
317m3391            VIA   -    MD0100PA00X+122292Y+137285X0193Y         S0      
327m3391            PU14  -25_2M      A01X+122144Y+137006X0810Y0910R270 S1      
317m3391            VIA   -    MD0100PA00X+139702Y+135086X0200Y         S0      
317m3391            VIA   -    MD0100PA00X+139486Y+134959X0200Y         S0      
317m3391            VIA   -    MD0100PA00X+139692Y+134786X0200Y         S0      
317m3391            VIA   -    MD0100PA00X+139912Y+134936X0200Y         S0      
317m3391            VIA   -    MD0100PA00X+139912Y+134646X0200Y         S0      
317m3391            VIA   -    MD0100PA00X+139486Y+135249X0200Y         S0      
317m3391            VIA   -    MD0100PA00X+139912Y+135226X0200Y         S0      
317m3391            VIA   -    MD0100PA00X+138723Y+134615X0193Y         S0      
317m3391            VIA   -    MD0100PA00X+139331Y+134342X0200Y         S0      
317m3391            VIA   -    MD0100PA00X+139331Y+134052X0200Y         S0      
317m3391            VIA   -    MD0100PA00X+138966Y+134615X0193Y         S0      
317m3391            VIA   -    MD0100PA00X+139209Y+134615X0193Y         S0      
327m3391            PU11  -25_2M      A01X+139061Y+134336X0810Y0910R270 S1      
317m3391            VIA   -    MD0100PA00X+136227Y+133316X0200Y         S0      
317m3391            VIA   -    MD0100PA00X+136227Y+133026X0200Y         S0      
317m3391            VIA   -    MD0100PA00X+136444Y+133453X0200Y         S0      
317m3391            VIA   -    MD0100PA00X+136444Y+133153X0200Y         S0      
317m3391            VIA   -    MD0100PA00X+136444Y+133753X0200Y         S0      
317m3391            VIA   -    MD0100PA00X+132947Y+133296X0200Y         S0      
317m3391            VIA   -    MD0100PA00X+132947Y+133006X0200Y         S0      
317m3391            VIA   -    MD0100PA00X+133164Y+133133X0200Y         S0      
317m3391            VIA   -    MD0100PA00X+133374Y+133273X0200Y         S0      
317m3391            VIA   -    MD0100PA00X+133374Y+132983X0200Y         S0      
317m3391            VIA   -    MD0100PA00X+130084Y+133278X0200Y         S0      
317m3391            VIA   -    MD0100PA00X+130084Y+132988X0200Y         S0      
317m3391            VIA   -    MD0100PA00X+129874Y+133138X0200Y         S0      
317m3391            VIA   -    MD0100PA00X+129657Y+133301X0200Y         S0      
317m3391            VIA   -    MD0100PA00X+129657Y+133011X0200Y         S0      
317m3391            VIA   -    MD0100PA00X+126367Y+133304X0200Y         S0      
317m3391            VIA   -    MD0100PA00X+126367Y+133014X0200Y         S0      
317m3391            VIA   -    MD0100PA00X+126584Y+133141X0200Y         S0      
317m3391            VIA   -    MD0100PA00X+126794Y+132991X0200Y         S0      
317m3391            VIA   -    MD0100PA00X+126794Y+133281X0200Y         S0      
317m3391            VIA   -    MD0100PA00X+136434Y+132853X0200Y         S0      
317m3391            VIA   -    MD0100PA00X+135465Y+132682X0193Y         S0      
317m3391            VIA   -    MD0100PA00X+135708Y+132682X0193Y         S0      
317m3391            VIA   -    MD0100PA00X+136072Y+132408X0200Y         S0      
317m3391            VIA   -    MD0100PA00X+136072Y+132118X0200Y         S0      
317m3391            VIA   -    MD0100PA00X+135951Y+132682X0193Y         S0      
327m3391            PU16  -25_2M      A01X+135803Y+132403X0810Y0910R270 S1      
317m3391            VIA   -    MD0100PA00X+133154Y+132833X0200Y         S0      
317m3391            VIA   -    MD0100PA00X+133374Y+132693X0200Y         S0      
317m3391            VIA   -    MD0100PA00X+132788Y+132383X0200Y         S0      
317m3391            VIA   -    MD0100PA00X+132788Y+132093X0200Y         S0      
317m3391            VIA   -    MD0100PA00X+132185Y+132662X0193Y         S0      
317m3391            VIA   -    MD0100PA00X+132428Y+132662X0193Y         S0      
317m3391            VIA   -    MD0100PA00X+132671Y+132662X0193Y         S0      
327m3391            PU13  -25_2M      A01X+132523Y+132383X0810Y0910R270 S1      
317m3391            VIA   -    MD0100PA00X+129864Y+132838X0200Y         S0      
317m3391            VIA   -    MD0100PA00X+130084Y+132698X0200Y         S0      
317m3391            VIA   -    MD0100PA00X+129496Y+132383X0200Y         S0      
317m3391            VIA   -    MD0100PA00X+129496Y+132093X0200Y         S0      
317m3391            VIA   -    MD0100PA00X+128895Y+132668X0193Y         S0      
317m3391            VIA   -    MD0100PA00X+129138Y+132668X0193Y         S0      
317m3391            VIA   -    MD0100PA00X+129381Y+132668X0193Y         S0      
327m3391            PU2   -25_2M      A01X+129233Y+132389X0810Y0910R270 S1      
317m3391            VIA   -    MD0100PA00X+126574Y+132841X0200Y         S0      
317m3391            VIA   -    MD0100PA00X+126794Y+132701X0200Y         S0      
317m3391            VIA   -    MD0100PA00X+126205Y+132378X0200Y         S0      
317m3391            VIA   -    MD0100PA00X+126205Y+132088X0200Y         S0      
317m3391            VIA   -    MD0100PA00X+125848Y+132671X0193Y         S0      
317m3391            VIA   -    MD0100PA00X+126091Y+132671X0193Y         S0      
317m3391            VIA   -    MD0100PA00X+125605Y+132671X0193Y         S0      
327m3391            PU15  -25_2M      A01X+125943Y+132392X0810Y0910R270 S1      
317m3392            VIA   -    MD0100PA00X+035260Y+064605X0200Y    R180 S0      
317m3392            VIA   -    MD0100PA00X+035520Y+064609X0200Y    R180 S0      
317m3392            VIA   -    MD0100PA00X+035010Y+064605X0200Y    R180 S0      
317m3392            VIA   -    MD0100PA00X+034760Y+064605X0200Y    R180 S0      
317m3392            VIA   -    MD0100PA00X+034510Y+064605X0200Y    R180 S0      
317m3392            VIA   -    MD0100PA00X+034260Y+064605X0200Y    R180 S0      
317m3392            VIA   -    MD0100PA00X+035528Y+064353X0200Y    R180 S0      
317m3392            VIA   -    MD0100PA00X+035528Y+064103X0200Y    R180 S0      
317m3392            VIA   -    MD0100PA00X+041471Y+069654X0200Y    R180 S0      
317m3392            VIA   -    MD0100PA00X+041471Y+069944X0200Y    R180 S0      
317m3392            VIA   -    MD0100PA00X+038181Y+071416X0200Y    R180 S0      
317m3392            VIA   -    MD0100PA00X+038181Y+071706X0200Y    R180 S0      
317m3392            VIA   -    MD0100PA00X+034840Y+071416X0200Y    R180 S0      
317m3392            VIA   -    MD0100PA00X+034840Y+071706X0200Y    R180 S0      
317m3392            VIA   -    MD0100PA00X+031591Y+071450X0200Y    R180 S0      
317m3392            VIA   -    MD0100PA00X+031591Y+071740X0200Y    R180 S0      
317m3392            VIA   -    MD0100PA00X+028304Y+069438X0200Y    R180 S0      
317m3392            VIA   -    MD0100PA00X+028304Y+069728X0200Y    R180 S0      
317m3392            VIA   -    MD0100PA00X+025031Y+066018X0200Y    R180 S0      
317m3392            VIA   -    MD0100PA00X+025031Y+066308X0200Y    R180 S0      
317m3392            VIA   -    MD0100PA00X+041271Y+068730X0200Y    R180 S0      
317m3392            VIA   -    MD0100PA00X+041271Y+069020X0200Y    R180 S0      
317m3392            VIA   -    MD0100PA00X+040844Y+069333X0200Y    R180 S0      
317m3392            VIA   -    MD0100PA00X+040844Y+069043X0200Y    R180 S0      
317m3392            VIA   -    MD0100PA00X+041054Y+068893X0200Y    R180 S0      
317m3392            VIA   -    MD0100PA00X+040844Y+068753X0200Y    R180 S0      
317m3392            VIA   -    MD0100PA00X+041064Y+069193X0200Y    R180 S0      
327m3392            PC294_-1          A18X+038525Y+070778X0400Y0500R270 S2      
327m3392            PC296_-1          A18X+038581Y+071522X0400Y0500R090 S2      
327m3392            PC298_-1          A18X+037781Y+071522X0400Y0500R090 S2      
327m3392            PC265_-1          A18X+035260Y+071543X0400Y0500R090 S2      
327m3392            PC267_-1          A18X+035260Y+070719X0400Y0500R270 S2      
327m3392            PC269_-1          A18X+034422Y+071543X0400Y0500R090 S2      
327m3392            PC264_-1          A18X+031865Y+070808X0400Y0500R270 S2      
327m3392            PC266_-1          A18X+031991Y+071562X0400Y0500R090 S2      
327m3392            PC268_-1          A18X+031191Y+071562X0400Y0500R090 S2      
327m3392            PC295_-1          A18X+041805Y+068988X0400Y0500R270 S2      
327m3392            PC299_-1          A18X+041871Y+069772X0400Y0500R090 S2      
327m3392            PC297_-1          A18X+041071Y+069772X0400Y0500R090 S2      
327m3392            PC311_-1          A18X+028704Y+069537X0400Y0500R090 S2      
327m3392            PC312_-1          A18X+027904Y+069537X0400Y0500R090 S2      
327m3392            PC313_-1          A18X+028618Y+068803X0400Y0500R270 S2      
327m3392            PC130_-1          A18X+025431Y+066133X0400Y0500R090 S2      
327m3392            PC132_-1          A18X+024631Y+066133X0400Y0500R090 S2      
327m3392            PC129_-1          A18X+025355Y+065358X0400Y0500R270 S2      
327m3392            PU27  -30         A01X+038194Y+070785X0090Y0240R180 S1      
327m3392            PC292_-1          A01X+037570Y+071739X0198Y0197R090 S1      
327m3392            PU26  -30         A01X+034890Y+070778X0090Y0240R180 S1      
327m3392            PC263_-1          A01X+034271Y+071724X0198Y0197R090 S1      
327m3392            PU4   -30         A01X+031584Y+070805X0090Y0240R180 S1      
327m3392            PC262_-1          A01X+030966Y+071726X0198Y0197R090 S1      
327m3392            PU28  -30         A01X+041494Y+069005X0090Y0240R180 S1      
327m3392            PC293_-1          A01X+040477Y+069306X0198Y0197R090 S1      
327m3392            PC291_-1          A01X+040874Y+069952X0198Y0197R090 S1      
327m3392            PC290_-1          A01X+037487Y+070194X0198Y0197R180 S1      
327m3392            PC261_-1          A01X+034181Y+070220X0198Y0197R180 S1      
327m3392            PC260_-1          A01X+031407Y+069452X0198Y0197     S1      
327m3392            PC310_-1          A01X+027686Y+069740X0198Y0197R090 S1      
327m3392            PU29  -30         A01X+028308Y+068790X0090Y0240R180 S1      
327m3392            PC309_-1          A01X+028228Y+067415X0198Y0197     S1      
327m3392            PC128_-1          A01X+024412Y+066316X0198Y0197R090 S1      
327m3392            PU24  -30         A01X+025034Y+065366X0090Y0240R180 S1      
327m3392            PL30  -1          A01X+034738Y+063604X0650Y1030R270 S1      
327m3392            PC127_-1          A01X+024805Y+064091X0198Y0197     S1      
317m3392            PC272 -1   MD0400PA00X+032673Y+065339X0600Y0600R180 S3      
317m3392            PC273 -1   MD0400PA00X+036373Y+065339X0600Y0600R180 S3      
317m3392            VIA   -    MD0100PA00X+037544Y+071113X0200Y    R180 S0      
317m3392            VIA   -    MD0100PA00X+037764Y+070973X0200Y    R180 S0      
317m3392            VIA   -    MD0100PA00X+037544Y+070533X0200Y    R180 S0      
317m3392            VIA   -    MD0100PA00X+037754Y+070673X0200Y    R180 S0      
317m3392            VIA   -    MD0100PA00X+037544Y+070823X0200Y    R180 S0      
317m3392            VIA   -    MD0100PA00X+037971Y+070510X0200Y    R180 S0      
317m3392            VIA   -    MD0100PA00X+037971Y+070800X0200Y    R180 S0      
327m3392            PU27  -25_2M      A01X+038395Y+071422X0810Y0910R090 S1      
317m3392            VIA   -    MD0100PA00X+038490Y+071144X0193Y    R180 S0      
317m3392            VIA   -    MD0100PA00X+038734Y+071144X0193Y    R180 S0      
317m3392            VIA   -    MD0100PA00X+038248Y+071144X0193Y    R180 S0      
317m3392            VIA   -    MD0100PA00X+034240Y+071106X0200Y    R180 S0      
317m3392            VIA   -    MD0100PA00X+034240Y+070816X0200Y    R180 S0      
317m3392            VIA   -    MD0100PA00X+034240Y+070526X0200Y    R180 S0      
317m3392            VIA   -    MD0100PA00X+034460Y+070966X0200Y    R180 S0      
317m3392            VIA   -    MD0100PA00X+034667Y+070793X0200Y    R180 S0      
317m3392            VIA   -    MD0100PA00X+034450Y+070666X0200Y    R180 S0      
317m3392            VIA   -    MD0100PA00X+034667Y+070503X0200Y    R180 S0      
317m3392            VIA   -    MD0100PA00X+034944Y+071137X0193Y    R180 S0      
317m3392            VIA   -    MD0100PA00X+035430Y+071137X0193Y    R180 S0      
317m3392            VIA   -    MD0100PA00X+035186Y+071137X0193Y    R180 S0      
327m3392            PU26  -25_2M      A01X+035091Y+071416X0810Y0910R090 S1      
317m3392            VIA   -    MD0100PA00X+031361Y+070530X0200Y    R180 S0      
317m3392            VIA   -    MD0100PA00X+031361Y+070820X0200Y    R180 S0      
317m3392            VIA   -    MD0100PA00X+031144Y+070693X0200Y    R180 S0      
317m3392            VIA   -    MD0100PA00X+031044Y+070393X0200Y    R180 S0      
317m3392            VIA   -    MD0100PA00X+031154Y+070993X0200Y    R180 S0      
317m3392            VIA   -    MD0100PA00X+031880Y+071164X0193Y    R180 S0      
317m3392            VIA   -    MD0100PA00X+031638Y+071164X0193Y    R180 S0      
317m3392            VIA   -    MD0100PA00X+032124Y+071164X0193Y    R180 S0      
327m3392            PU4   -25_2M      A01X+031785Y+071442X0810Y0910R090 S1      
317m3392            VIA   -    MD0100PA00X+041790Y+069364X0193Y    R180 S0      
317m3392            VIA   -    MD0100PA00X+041548Y+069364X0193Y    R180 S0      
317m3392            VIA   -    MD0100PA00X+042034Y+069364X0193Y    R180 S0      
327m3392            PU28  -25_2M      A01X+041695Y+069642X0810Y0910R090 S1      
317m3392            VIA   -    MD0100PA00X+031261Y+070230X0200Y    R180 S0      
317m3392            VIA   -    MD0100PA00X+031044Y+070093X0200Y    R180 S0      
317m3392            VIA   -    MD0100PA00X+027878Y+068978X0200Y    R180 S0      
317m3392            VIA   -    MD0100PA00X+028604Y+069149X0193Y    R180 S0      
317m3392            VIA   -    MD0100PA00X+028360Y+069149X0193Y    R180 S0      
317m3392            VIA   -    MD0100PA00X+028846Y+069149X0193Y    R180 S0      
327m3392            PU29  -25_2M      A01X+028508Y+069428X0810Y0910R090 S1      
317m3392            VIA   -    MD0100PA00X+027658Y+069118X0200Y    R180 S0      
317m3392            VIA   -    MD0100PA00X+027658Y+068828X0200Y    R180 S0      
317m3392            VIA   -    MD0100PA00X+028084Y+068515X0200Y    R180 S0      
317m3392            VIA   -    MD0100PA00X+027868Y+068678X0200Y    R180 S0      
317m3392            VIA   -    MD0100PA00X+028084Y+068805X0200Y    R180 S0      
317m3392            VIA   -    MD0100PA00X+027658Y+068538X0200Y    R180 S0      
317m3392            VIA   -    MD0100PA00X+035268Y+064349X0200Y    R180 S0      
317m3392            VIA   -    MD0100PA00X+035018Y+064349X0200Y    R180 S0      
317m3392            VIA   -    MD0100PA00X+034768Y+064349X0200Y    R180 S0      
317m3392            VIA   -    MD0100PA00X+034518Y+064349X0200Y    R180 S0      
317m3392            VIA   -    MD0100PA00X+034268Y+064349X0200Y    R180 S0      
317m3392            VIA   -    MD0100PA00X+024811Y+065091X0200Y    R180 S0      
317m3392            VIA   -    MD0100PA00X+024811Y+065381X0200Y    R180 S0      
317m3392            VIA   -    MD0100PA00X+025088Y+065724X0193Y    R180 S0      
317m3392            VIA   -    MD0100PA00X+025330Y+065724X0193Y    R180 S0      
317m3392            VIA   -    MD0100PA00X+025574Y+065724X0193Y    R180 S0      
327m3392            PU24  -25_2M      A01X+025235Y+066003X0810Y0910R090 S1      
317m3392            VIA   -    MD0100PA00X+024594Y+065254X0200Y    R180 S0      
317m3392            VIA   -    MD0100PA00X+024384Y+065404X0200Y    R180 S0      
317m3392            VIA   -    MD0100PA00X+024384Y+065114X0200Y    R180 S0      
317m3392            VIA   -    MD0100PA00X+024604Y+065554X0200Y    R180 S0      
317m3392            VIA   -    MD0100PA00X+024384Y+065694X0200Y    R180 S0      
317m3392            VIA   -    MD0100PA00X+035268Y+064099X0200Y    R180 S0      
317m3392            VIA   -    MD0100PA00X+035018Y+064099X0200Y    R180 S0      
317m3392            VIA   -    MD0100PA00X+034768Y+064099X0200Y    R180 S0      
317m3392            VIA   -    MD0100PA00X+034518Y+064099X0200Y    R180 S0      
317m3392            VIA   -    MD0100PA00X+034268Y+064099X0200Y    R180 S0      
317m3393            VIA   -    MD0100PA00X+144638Y+064777X0200Y    R180 S0      
317m3393            VIA   -    MD0100PA00X+144638Y+064527X0200Y    R180 S0      
317m3393            VIA   -    MD0100PA00X+144388Y+064777X0200Y    R180 S0      
317m3393            VIA   -    MD0100PA00X+144388Y+064527X0200Y    R180 S0      
317m3393            VIA   -    MD0100PA00X+144393Y+065037X0200Y    R180 S0      
317m3393            VIA   -    MD0100PA00X+144643Y+065037X0200Y    R180 S0      
317m3393            VIA   -    MD0100PA00X+145945Y+065037X0200Y    R180 S0      
317m3393            VIA   -    MD0100PA00X+145655Y+065037X0200Y    R180 S0      
317m3393            VIA   -    MD0100PA00X+145155Y+065037X0200Y    R180 S0      
317m3393            VIA   -    MD0100PA00X+145405Y+065037X0200Y    R180 S0      
317m3393            VIA   -    MD0100PA00X+144905Y+065037X0200Y    R180 S0      
317m3393            VIA   -    MD0100PA00X+152506Y+071744X0200Y    R180 S0      
317m3393            VIA   -    MD0100PA00X+152506Y+071454X0200Y    R180 S0      
317m3393            VIA   -    MD0100PA00X+149226Y+071744X0200Y    R180 S0      
317m3393            VIA   -    MD0100PA00X+149226Y+071454X0200Y    R180 S0      
317m3393            VIA   -    MD0100PA00X+145878Y+071709X0200Y    R180 S0      
317m3393            VIA   -    MD0100PA00X+145878Y+071419X0200Y    R180 S0      
317m3393            VIA   -    MD0100PA00X+142626Y+069785X0200Y    R180 S0      
317m3393            VIA   -    MD0100PA00X+142626Y+069495X0200Y    R180 S0      
317m3393            VIA   -    MD0100PA00X+139366Y+066528X0200Y    R180 S0      
317m3393            VIA   -    MD0100PA00X+139366Y+066238X0200Y    R180 S0      
317m3393            VIA   -    MD0100PA00X+136096Y+063241X0200Y    R180 S0      
317m3393            VIA   -    MD0100PA00X+136096Y+062951X0200Y    R180 S0      
327m3393            PC555_-1          A18X+152833Y+070809X0400Y0500R270 S2      
327m3393            PC557_-1          A18X+152906Y+071645X0400Y0500R090 S2      
327m3393            PC559_-1          A18X+152106Y+071645X0400Y0500R090 S2      
327m3393            PC554_-1          A18X+149562Y+070814X0400Y0500R270 S2      
327m3393            PC556_-1          A18X+148826Y+071645X0400Y0500R090 S2      
327m3393            PC558_-1          A18X+149626Y+071645X0400Y0500R090 S2      
327m3393            PC484_-1          A18X+146319Y+070820X0400Y0500R270 S2      
327m3393            PC488_-1          A18X+146281Y+071570X0400Y0500R090 S2      
327m3393            PC486_-1          A18X+145443Y+071570X0400Y0500R090 S2      
327m3393            PC485_-1          A18X+143026Y+069687X0400Y0500R090 S2      
327m3393            PC487_-1          A18X+142226Y+069687X0400Y0500R090 S2      
327m3393            PC483_-1          A18X+142948Y+068861X0400Y0500R270 S2      
327m3393            PC573_-1          A18X+139766Y+066429X0400Y0500R090 S2      
327m3393            PC572_-1          A18X+138966Y+066429X0400Y0500R090 S2      
327m3393            PC571_-1          A18X+139692Y+065598X0400Y0500R270 S2      
327m3393            PC158_-1          A18X+136496Y+063139X0400Y0500R090 S2      
327m3393            PC159_-1          A18X+135696Y+063139X0400Y0500R090 S2      
327m3393            PC157_-1          A18X+136403Y+062309X0400Y0500R270 S2      
327m3393            PU47  -30         A01X+152500Y+070805X0090Y0240R180 S1      
327m3393            PC553_-1          A01X+151870Y+071756X0198Y0197R090 S1      
327m3393            PU46  -30         A01X+149220Y+070822X0090Y0240R180 S1      
327m3393            PC550_-1          A01X+148590Y+071756X0198Y0197R090 S1      
327m3393            PU43  -30         A01X+145912Y+070805X0090Y0240R180 S1      
327m3393            PC480_-1          A01X+145276Y+071733X0198Y0197R090 S1      
327m3393            PC551_-1          A01X+151817Y+070220X0198Y0197R180 S1      
327m3393            PC552_-1          A01X+148508Y+070220X0198Y0197R180 S1      
327m3393            PC482_-1          A01X+146218Y+069526X0198Y0197     S1      
327m3393            PU6   -30         A01X+142620Y+068847X0090Y0240R180 S1      
327m3393            PC481_-1          A01X+142001Y+069766X0198Y0197R090 S1      
327m3393            PC479_-1          A01X+143068Y+067576X0198Y0197     S1      
327m3393            PC569_-1          A01X+138730Y+066541X0198Y0197R090 S1      
327m3393            PU48  -30         A01X+139360Y+065589X0090Y0240R180 S1      
327m3393            PL53  -1          A01X+145406Y+063950X0650Y1030R270 S1      
327m3393            PC570_-1          A01X+139668Y+064276X0198Y0197     S1      
327m3393            PC154_-1          A01X+135460Y+063251X0198Y0197R090 S1      
327m3393            PC153_-1          A01X+135026Y+063251X0198Y0197R090 S1      
327m3393            PU10  -30         A01X+136090Y+062299X0090Y0240R180 S1      
317m3393            PC491 -1   MD0400PA00X+148768Y+064014X0600Y0600R180 S3      
317m3393            PC492 -1   MD0400PA00X+141569Y+060123X0600Y0600R090 S3      
317m3393            VIA   -    MD0100PA00X+151850Y+071133X0200Y    R180 S0      
317m3393            VIA   -    MD0100PA00X+152070Y+070993X0200Y    R180 S0      
317m3393            VIA   -    MD0100PA00X+151850Y+070843X0200Y    R180 S0      
317m3393            VIA   -    MD0100PA00X+152060Y+070693X0200Y    R180 S0      
317m3393            VIA   -    MD0100PA00X+151850Y+070553X0200Y    R180 S0      
317m3393            VIA   -    MD0100PA00X+152276Y+070530X0200Y    R180 S0      
317m3393            VIA   -    MD0100PA00X+152276Y+070820X0200Y    R180 S0      
327m3393            PU47  -25_2M      A01X+152700Y+071442X0810Y0910R090 S1      
317m3393            VIA   -    MD0100PA00X+152796Y+071164X0193Y    R180 S0      
317m3393            VIA   -    MD0100PA00X+152553Y+071164X0193Y    R180 S0      
317m3393            VIA   -    MD0100PA00X+153039Y+071164X0193Y    R180 S0      
317m3393            VIA   -    MD0100PA00X+148570Y+071133X0200Y    R180 S0      
317m3393            VIA   -    MD0100PA00X+148570Y+070553X0200Y    R180 S0      
317m3393            VIA   -    MD0100PA00X+148570Y+070843X0200Y    R180 S0      
317m3393            VIA   -    MD0100PA00X+148996Y+070820X0200Y    R180 S0      
317m3393            VIA   -    MD0100PA00X+148790Y+070993X0200Y    R180 S0      
317m3393            VIA   -    MD0100PA00X+148780Y+070693X0200Y    R180 S0      
317m3393            VIA   -    MD0100PA00X+148996Y+070530X0200Y    R180 S0      
317m3393            VIA   -    MD0100PA00X+149273Y+071164X0193Y    R180 S0      
317m3393            VIA   -    MD0100PA00X+149516Y+071164X0193Y    R180 S0      
317m3393            VIA   -    MD0100PA00X+149759Y+071164X0193Y    R180 S0      
327m3393            PU46  -25_2M      A01X+149420Y+071459X0810Y0910R090 S1      
317m3393            VIA   -    MD0100PA00X+145482Y+070993X0200Y    R180 S0      
317m3393            VIA   -    MD0100PA00X+145472Y+070393X0200Y    R180 S0      
317m3393            VIA   -    MD0100PA00X+145472Y+070693X0200Y    R180 S0      
317m3393            VIA   -    MD0100PA00X+145688Y+070530X0200Y    R180 S0      
317m3393            VIA   -    MD0100PA00X+145688Y+070820X0200Y    R180 S0      
317m3393            VIA   -    MD0100PA00X+145962Y+071183X0193Y    R180 S0      
317m3393            VIA   -    MD0100PA00X+146448Y+071183X0193Y    R180 S0      
317m3393            VIA   -    MD0100PA00X+146204Y+071183X0193Y    R180 S0      
327m3393            PU43  -25_2M      A01X+146112Y+071442X0810Y0910R090 S1      
317m3393            VIA   -    MD0100PA00X+145262Y+070553X0200Y    R180 S0      
317m3393            VIA   -    MD0100PA00X+145472Y+070093X0200Y    R180 S0      
317m3393            VIA   -    MD0100PA00X+142676Y+069236X0193Y    R180 S0      
317m3393            VIA   -    MD0100PA00X+142919Y+069236X0193Y    R180 S0      
317m3393            VIA   -    MD0100PA00X+143162Y+069236X0193Y    R180 S0      
327m3393            PU6   -25_2M      A01X+142820Y+069485X0810Y0910R090 S1      
317m3393            VIA   -    MD0100PA00X+141970Y+069175X0200Y    R180 S0      
317m3393            VIA   -    MD0100PA00X+141970Y+068885X0200Y    R180 S0      
317m3393            VIA   -    MD0100PA00X+142396Y+068862X0200Y    R180 S0      
317m3393            VIA   -    MD0100PA00X+142190Y+069035X0200Y    R180 S0      
317m3393            VIA   -    MD0100PA00X+141970Y+068595X0200Y    R180 S0      
317m3393            VIA   -    MD0100PA00X+142396Y+068572X0200Y    R180 S0      
317m3393            VIA   -    MD0100PA00X+142180Y+068735X0200Y    R180 S0      
317m3393            VIA   -    MD0100PA00X+138710Y+065917X0200Y    R180 S0      
317m3393            VIA   -    MD0100PA00X+139656Y+065948X0193Y    R180 S0      
317m3393            VIA   -    MD0100PA00X+139899Y+065948X0193Y    R180 S0      
317m3393            VIA   -    MD0100PA00X+139413Y+065948X0193Y    R180 S0      
327m3393            PU48  -25_2M      A01X+139560Y+066227X0810Y0910R090 S1      
317m3393            VIA   -    MD0100PA00X+145940Y+064777X0200Y    R180 S0      
317m3393            VIA   -    MD0100PA00X+145650Y+064777X0200Y    R180 S0      
317m3393            VIA   -    MD0100PA00X+145940Y+064527X0200Y    R180 S0      
317m3393            VIA   -    MD0100PA00X+145650Y+064527X0200Y    R180 S0      
317m3393            VIA   -    MD0100PA00X+145150Y+064777X0200Y    R180 S0      
317m3393            VIA   -    MD0100PA00X+145400Y+064777X0200Y    R180 S0      
317m3393            VIA   -    MD0100PA00X+145400Y+064527X0200Y    R180 S0      
317m3393            VIA   -    MD0100PA00X+145150Y+064527X0200Y    R180 S0      
317m3393            VIA   -    MD0100PA00X+144900Y+064777X0200Y    R180 S0      
317m3393            VIA   -    MD0100PA00X+144900Y+064527X0200Y    R180 S0      
317m3393            VIA   -    MD0100PA00X+139136Y+065314X0200Y    R180 S0      
317m3393            VIA   -    MD0100PA00X+138920Y+065477X0200Y    R180 S0      
317m3393            VIA   -    MD0100PA00X+138710Y+065337X0200Y    R180 S0      
317m3393            VIA   -    MD0100PA00X+139136Y+065604X0200Y    R180 S0      
317m3393            VIA   -    MD0100PA00X+138930Y+065777X0200Y    R180 S0      
317m3393            VIA   -    MD0100PA00X+138710Y+065627X0200Y    R180 S0      
317m3393            VIA   -    MD0100PA00X+135866Y+062024X0200Y    R180 S0      
317m3393            VIA   -    MD0100PA00X+135440Y+062047X0200Y    R180 S0      
317m3393            VIA   -    MD0100PA00X+135650Y+062187X0200Y    R180 S0      
317m3393            VIA   -    MD0100PA00X+135866Y+062314X0200Y    R180 S0      
317m3393            VIA   -    MD0100PA00X+135660Y+062487X0200Y    R180 S0      
317m3393            VIA   -    MD0100PA00X+135440Y+062627X0200Y    R180 S0      
317m3393            VIA   -    MD0100PA00X+135440Y+062337X0200Y    R180 S0      
317m3393            VIA   -    MD0100PA00X+136143Y+062658X0193Y    R180 S0      
317m3393            VIA   -    MD0100PA00X+136386Y+062658X0193Y    R180 S0      
317m3393            VIA   -    MD0100PA00X+136629Y+062658X0193Y    R180 S0      
327m3393            PU10  -25_2M      A01X+136290Y+062937X0810Y0910R090 S1      
327m3394            PL26  -2          A01X+032409Y+059879X0280Y0320R090 S1      
327m3394            PC8003-1          A01X+031796Y+059886X0400Y0500R270 S1      
327m3394            PC152 -1          A01X+030994Y+059883X0400Y0500R270 S1      
327m3394            PC150 -1          A01X+029614Y+059883X0400Y0500R270 S1      
327m3394            PC60  -1          A01X+030304Y+059883X0400Y0500R270 S1      
327m3394            PU3   -10         A01X+028012Y+059855X0120Y0790R090 S1      
327m3394            PC61  -1          A01X+028924Y+059883X0400Y0500R270 S1      
327m3394            PU3   -21         A01X+026989Y+059855X0120Y0790R090 S1      
327m3394            PC22  -1          A01X+026247Y+059823X0198Y0197R270 S1      
327m3394            VIA   -           A01X+031427Y+059304X0300Y    R180 S1      
327m3395            PC8002-1          A01X+132001Y+051968X0400Y0500R180 S1      
327m3395            PC237 -1          A01X+131942Y+056715X0198Y0197R180 S1      
327m3395            PU57  -21         A01X+131974Y+055973X0120Y0790     S1      
327m3395            PU57  -10         A01X+131974Y+054949X0120Y0790     S1      
327m3395            PC227 -1          A01X+132001Y+054038X0400Y0500R180 S1      
327m3395            PL77  -2          A01X+131350Y+051872X0280Y0320R270 S1      
327m3395            PC254 -1          A01X+131377Y+053211X0400Y0500     S1      
327m3395            PC111 -1          A01X+132001Y+053348X0400Y0500R180 S1      
327m3395            PC81  -1          A01X+132001Y+052658X0400Y0500R180 S1      
327m3396            PC7003-1          A18X+073250Y+143015X0400Y0500R180 S2      
327m3396            PC8007-1          A01X+077449Y+140956X0400Y0500R180 S1      
327m3396            PC8006-1          A18X+073250Y+141550X0400Y0500R180 S2      
327m3396            PL56  -1          A01X+072872Y+142362X0420Y0990R180 S1      
327m3396            PU45  -30         A01X+076105Y+139457X0090Y0240     S1      
327m3396            PC509_-1          A01X+073508Y+140041X0198Y0197     S1      
327m3396            PU44  -30         A01X+072827Y+139447X0090Y0240     S1      
327m3396            PC510_-1          A01X+077122Y+138508X0198Y0197R270 S1      
327m3396            PC512_-1          A01X+076734Y+138508X0198Y0197R270 S1      
327m3396            PC511_-1          A01X+073456Y+138498X0198Y0197R270 S1      
317m3396            PC522 -1   MD0400PA00X+075464Y+142689X0600Y0600R180 S3      
317m3396            VIA   -    MD0100PA00X+073242Y+142012X0200Y    R180 S0      
317m3396            VIA   -    MD0100PA00X+073242Y+142312X0200Y    R180 S0      
317m3396            VIA   -    MD0100PA00X+073242Y+142612X0200Y    R180 S0      
317m3396            VIA   -    MD0100PA00X+073542Y+142012X0200Y    R180 S0      
317m3396            VIA   -    MD0100PA00X+073542Y+142312X0200Y    R180 S0      
317m3396            VIA   -    MD0100PA00X+073542Y+142612X0200Y    R180 S0      
327m3396            PC521_-1          A18X+073264Y+140814X0400Y0500R180 S2      
327m3396            PC518_-1          A18X+075792Y+139445X0400Y0500R090 S2      
317m3396            VIA   -    MD0100PA00X+076328Y+139442X0200Y         S0      
317m3396            VIA   -    MD0100PA00X+076328Y+139732X0200Y         S0      
317m3396            VIA   -    MD0100PA00X+076545Y+139569X0200Y         S0      
317m3396            VIA   -    MD0100PA00X+076535Y+139269X0200Y         S0      
317m3396            VIA   -    MD0100PA00X+076755Y+139419X0200Y         S0      
317m3396            VIA   -    MD0100PA00X+076755Y+139709X0200Y         S0      
317m3396            VIA   -    MD0100PA00X+076755Y+139129X0200Y         S0      
317m3396            VIA   -    MD0100PA00X+073477Y+139119X0200Y         S0      
317m3396            VIA   -    MD0100PA00X+073050Y+139432X0200Y         S0      
317m3396            VIA   -    MD0100PA00X+073050Y+139722X0200Y         S0      
317m3396            VIA   -    MD0100PA00X+073267Y+139559X0200Y         S0      
317m3396            VIA   -    MD0100PA00X+073257Y+139259X0200Y         S0      
317m3396            VIA   -    MD0100PA00X+073477Y+139409X0200Y         S0      
317m3396            VIA   -    MD0100PA00X+073477Y+139699X0200Y         S0      
327m3396            PC517_-1          A18X+072490Y+139435X0400Y0500R090 S2      
327m3396            PC27  -1          A18X+077191Y+138618X0400Y0500R270 S2      
327m3396            PC516_-1          A18X+075698Y+138633X0400Y0500R270 S2      
327m3396            PC514_-1          A18X+076510Y+138633X0400Y0500R270 S2      
317m3396            VIA   -    MD0100PA00X+076098Y+138805X0200Y         S0      
317m3396            VIA   -    MD0100PA00X+076098Y+138515X0200Y         S0      
317m3396            VIA   -    MD0100PA00X+075566Y+139098X0193Y         S0      
317m3396            VIA   -    MD0100PA00X+076052Y+139098X0193Y         S0      
317m3396            VIA   -    MD0100PA00X+075809Y+139098X0193Y         S0      
327m3396            PU45  -25_2M      A01X+075904Y+138819X0810Y0910R270 S1      
327m3396            PC515_-1          A18X+073231Y+138623X0400Y0500R270 S2      
327m3396            PC513_-1          A18X+072420Y+138623X0400Y0500R270 S2      
317m3396            VIA   -    MD0100PA00X+072288Y+139088X0193Y         S0      
317m3396            VIA   -    MD0100PA00X+072820Y+138513X0200Y         S0      
317m3396            VIA   -    MD0100PA00X+072820Y+138803X0200Y         S0      
317m3396            VIA   -    MD0100PA00X+072531Y+139088X0193Y         S0      
317m3396            VIA   -    MD0100PA00X+072774Y+139088X0193Y         S0      
327m3396            PU44  -25_2M      A01X+072626Y+138809X0810Y0910R270 S1      
327m3397            PC7002-1          A18X+172311Y+142473X0400Y0500R090 S2      
327m3397            PC8005-1          A18X+168026Y+141169X0400Y0500R180 S2      
327m3397            PC8004-1          A18X+172650Y+140250X0400Y0500     S2      
327m3397            PL24  -1          A01X+172115Y+141971X0420Y0990     S1      
327m3397            PC219_-1          A01X+168026Y+141169X0400Y0500     S1      
327m3397            PU23  -30         A01X+170878Y+139386X0090Y0240     S1      
327m3397            VIA   -           A01X+171882Y+140056X0300Y         S1      
327m3397            PC207_-1          A01X+168281Y+139970X0198Y0197     S1      
327m3397            PU22  -30         A01X+167600Y+139376X0090Y0240     S1      
327m3397            PC210_-1          A01X+171507Y+138436X0198Y0197R270 S1      
327m3397            PC208_-1          A01X+171895Y+138436X0198Y0197R270 S1      
327m3397            PC209_-1          A01X+168229Y+138426X0198Y0197R270 S1      
317m3397            VIA   -    MD0100PA00X+171445Y+142321X0200Y         S0      
317m3397            VIA   -    MD0100PA00X+171445Y+142021X0200Y         S0      
317m3397            VIA   -    MD0100PA00X+171745Y+142021X0200Y         S0      
317m3397            VIA   -    MD0100PA00X+171745Y+142321X0200Y         S0      
317m3397            PC220 -1   MD0400PA00X+170084Y+142452X0600Y0600R180 S3      
317m3397            VIA   -    MD0100PA00X+171445Y+141721X0200Y         S0      
317m3397            VIA   -    MD0100PA00X+171745Y+141721X0200Y         S0      
317m3397            VIA   -    MD0100PA00X+171528Y+139348X0200Y         S0      
317m3397            VIA   -    MD0100PA00X+171318Y+139498X0200Y         S0      
317m3397            VIA   -    MD0100PA00X+171102Y+139660X0200Y         S0      
317m3397            VIA   -    MD0100PA00X+171102Y+139370X0200Y         S0      
317m3397            VIA   -    MD0100PA00X+171528Y+139058X0200Y         S0      
317m3397            VIA   -    MD0100PA00X+171308Y+139198X0200Y         S0      
317m3397            VIA   -    MD0100PA00X+171528Y+139638X0200Y         S0      
327m3397            PC216_-1          A18X+170565Y+139374X0400Y0500R090 S2      
317m3397            VIA   -    MD0100PA00X+168250Y+139338X0200Y         S0      
317m3397            VIA   -    MD0100PA00X+167823Y+139650X0200Y         S0      
317m3397            VIA   -    MD0100PA00X+167823Y+139360X0200Y         S0      
317m3397            VIA   -    MD0100PA00X+168040Y+139488X0200Y         S0      
317m3397            VIA   -    MD0100PA00X+168250Y+139628X0200Y         S0      
317m3397            VIA   -    MD0100PA00X+168030Y+139188X0200Y         S0      
317m3397            VIA   -    MD0100PA00X+168250Y+139048X0200Y         S0      
327m3397            PC215_-1          A18X+167263Y+139364X0400Y0500R090 S2      
327m3397            PC212_-1          A18X+171271Y+138562X0400Y0500R270 S2      
327m3397            PC218_-1          A18X+171984Y+138577X0400Y0500R270 S2      
317m3397            VIA   -    MD0100PA00X+170582Y+139027X0193Y         S0      
317m3397            VIA   -    MD0100PA00X+170339Y+139027X0193Y         S0      
317m3397            VIA   -    MD0100PA00X+170871Y+138734X0200Y         S0      
317m3397            VIA   -    MD0100PA00X+170871Y+138444X0200Y         S0      
317m3397            VIA   -    MD0100PA00X+170825Y+139027X0193Y         S0      
327m3397            PU23  -25_2M      A01X+170677Y+138748X0810Y0910R270 S1      
327m3397            PC214_-1          A18X+170471Y+138562X0400Y0500R270 S2      
327m3397            PC211_-1          A18X+167993Y+138552X0400Y0500R270 S2      
327m3397            PC213_-1          A18X+167193Y+138552X0400Y0500R270 S2      
317m3397            VIA   -    MD0100PA00X+167593Y+138724X0200Y         S0      
317m3397            VIA   -    MD0100PA00X+167593Y+138434X0200Y         S0      
317m3397            VIA   -    MD0100PA00X+167061Y+139017X0193Y         S0      
317m3397            VIA   -    MD0100PA00X+167304Y+139017X0193Y         S0      
317m3397            VIA   -    MD0100PA00X+167547Y+139017X0193Y         S0      
327m3397            PU22  -25_2M      A01X+167399Y+138738X0810Y0910R270 S1      
327m3398            VIA   -    M      A01X+138380Y+169524X0300Y    R180 S1      
327m3398            R4560 -2          A01X+138860Y+169524X0198Y0197R180 S1      
327m3398            Q146  -5          A01X+138636Y+169038X0170Y0200R180 S1      
327m3398            Q146  -6   M      A01X+138380Y+169038X0170Y0200R180 S1      
327m3399            R4563 -2          A18X+079273Y+047934X0198Y0197R180 S2      
317m3399            VIA   -    MD0100PA00X+079733Y+047934X0200Y    R180 S0      
317m3399            VIA   -    MD0100PA00X+140050Y+045838X0200Y         S0      
317m3399            VIA   -    MD0100PA00X+170511Y+145177X0200Y         S0      
317m3399            VIA   -    MD0100PA00X+154755Y+152007X0200Y         S0      
317m3399            VIA   -    M      A01X+139074Y+166494X0200Y         S2      
017m3399            VIA   -    M      A18X+139074Y+166494X0260Y         S2      
017m3399                  -    MD0100PA00X+139074Y+166494                       
327m3399            R4561 -2   M      A01X+138892Y+167439X0198Y0197R180 S1      
327m3399            C18   -1   M      A01X+138892Y+167039X0198Y0197     S1      
327m3399            Q146  -3          A01X+138892Y+168290X0170Y0200R180 S1      
317SWB_HSC_PWRGD    VIA   -    M      A01X+138507Y+166491X0200Y         S2      
017SWB_HSC_PWRGD    VIA   -    M      A18X+138507Y+166491X0260Y         S2      
017SWB_HSC_PWRGD          -    MD0100PA00X+138507Y+166491                       
317SWB_HSC_PWRGD    J107  -A7   D0142PA00X+135295Y+173421X0302Y    R180 S3      
327SWB_HSC_PWRGD    Q146  -2          A01X+138636Y+168290X0170Y0200R180 S1      
327SWB_HSC_PWRGD    R4559 -1   M      A01X+138507Y+167039X0198Y0197R180 S1      
327SWB_HSC_PWRGD    R4562 -2   M      A01X+138507Y+167439X0198Y0197     S1      
327m3400            VIA   -    M      A01X+139242Y+170804X0300Y         S1      
327m3400            U316  -6          A01X+139018Y+171644X0160Y0200R180 S1      
327m3400            R4555 -1   M      A01X+138762Y+170804X0198Y0197R180 S1      
327m3400            R4550 -1          A01X+138762Y+170004X0198Y0197R180 S1      
327m3400            R4549 -2   M      A01X+138762Y+170404X0198Y0197     S1      
317SWB_HSC_EN_BUF   VIA   -    M      A01X+138204Y+170004X0200Y    R270 S2      
017SWB_HSC_EN_BUF   VIA   -    M      A18X+138204Y+170004X0260Y    R270 S2      
017SWB_HSC_EN_BUF         -    MD0100PA00X+138204Y+170004                       
317SWB_HSC_EN_BUF   J107  -N8   D0142PA00X+136083Y+167201X0302Y    R180 S3      
327SWB_HSC_EN_BUF   R4550 -2          A01X+138447Y+170004X0198Y0197R180 S1      
317SWB_HSC_EN       VIA   -    MD0100PA00X+154547Y+152212X0200Y         S0      
317SWB_HSC_EN       VIA   -    MD0100PA00X+085829Y+046705X0200Y         S0      
317SWB_HSC_EN       VIA   -    MD0100PA00X+140650Y+045836X0200Y         S0      
327SWB_HSC_EN       R4558 -2          A18X+077823Y+047134X0198Y0197R180 S2      
317SWB_HSC_EN       VIA   -    MD0100PA00X+170228Y+144980X0200Y         S0      
317SWB_HSC_EN       VIA   -    M      A01X+139018Y+173312X0200Y         S2      
017SWB_HSC_EN       VIA   -    M      A18X+139018Y+173312X0260Y         S2      
017SWB_HSC_EN             -    MD0100PA00X+139018Y+173312                       
327SWB_HSC_EN       U316  -1          A01X+139018Y+172392X0160Y0200R180 S1      
327SWB_HSC_EN       R4548 -1   M      A01X+139018Y+172832X0198Y0197R180 S1      
327SWB_HSC_EN       R4547 -2          A01X+138538Y+173312X0198Y0197     S1      
327m3401            VIA   -    M      A01X+010255Y+141595X0300Y         S1      
327m3401            R8238 -2          A01X+009908Y+141250X0198Y0197     S1      
327m3401            PU34  -23         A01X+010868Y+142641X0070Y0260R270 S1      
327m3402            C308  -1          A01X+009008Y+141250X0198Y0197R180 S1      
317m3402            VIA   -    M      A01X+015648Y+144773X0200Y         S2      
017m3402            VIA   -    M      A18X+015648Y+144773X0260Y         S2      
017m3402                  -    MD0100PA00X+015648Y+144773                       
327m3402            U26   -DG73       A01X+031357Y+115776X0177Y    R180 S1      
327m3402            R8238 -1          A01X+009592Y+141250X0198Y0197     S1      
327m3402            R8220 -2          A18X+009008Y+141250X0198Y0197R180 S2      
327m3402            R8219 -1          A18X+009592Y+141250X0198Y0197R180 S2      
317m3402            VIA   -    MD0100PA00X+009307Y+141250X0200Y         S0      
327m3403            VIA   -    M      A01X+010238Y+140938X0300Y         S1      
327m3403            PR239 -2          A01X+009908Y+140800X0198Y0197     S1      
327m3403            PU34  -24         A01X+010868Y+142484X0070Y0260R270 S1      
327m3404            PR217 -1          A01X+009008Y+140800X0198Y0197R180 S1      
327m3404            PR239 -1          A01X+009592Y+140800X0198Y0197     S1      
327m3404            PR218 -2          A18X+009008Y+140800X0198Y0197R180 S2      
317m3404            VIA   -    MD0100PA00X+009300Y+140800X0200Y         S0      
327m3405            PR8012-1          A01X+009592Y+142150X0198Y0197     S1      
317m3405            VIA   -    M      A01X+015430Y+145310X0200Y         S2      
017m3405            VIA   -    M      A18X+015430Y+145310X0260Y         S2      
017m3405                  -    MD0100PA00X+015430Y+145310                       
317m3405            VIA   -    MD0100PA00X+035141Y+121005X0200Y         S0      
327m3405            PR237 -1          A18X+035727Y+121656X0198Y0197R090 S2      
327m3405            C309  -1          A01X+009008Y+142150X0198Y0197R180 S1      
327m3405            R8222 -2          A18X+009008Y+142150X0198Y0197R180 S2      
317m3405            VIA   -    MD0100PA00X+009300Y+142150X0200Y         S0      
327m3406            U26   -DH72       A01X+031542Y+116095X0177Y    R180 S1      
327m3406            PR237 -2          A18X+035727Y+121341X0198Y0197R090 S2      
317m3406            VIA   -    M      A01X+035727Y+120899X0200Y    R180 S2      
017m3406            VIA   -    M      A18X+035727Y+120899X0260Y    R180 S2      
017m3406                  -    MD0100PA00X+035727Y+120899                       
327m3407            PR8011-1          A01X+009592Y+141700X0198Y0197     S1      
327m3407            VIA   -    M      A01X+016211Y+145002X0300Y         S1      
327m3407            C310  -1          A01X+009008Y+141700X0198Y0197R180 S1      
327m3407            R8225 -2          A18X+009008Y+141700X0198Y0197R180 S2      
317m3407            VIA   -    MD0100PA00X+009300Y+141700X0200Y         S0      
317m3407            VIA   -    MD0100PA00X+034994Y+121456X0200Y    R180 S0      
327m3407            PR236 -1          A18X+036127Y+121656X0198Y0197R090 S2      
317m3407            VIA   -    MD0100PA00X+015467Y+145002X0200Y         S0      
327m3408            U26   -DJ72       A01X+031728Y+116414X0177Y    R180 S1      
317m3408            VIA   -    M      A01X+036192Y+120689X0200Y    R180 S2      
017m3408            VIA   -    M      A18X+036192Y+120689X0260Y    R180 S2      
017m3408                  -    MD0100PA00X+036192Y+120689                       
327m3408            PR236 -2          A18X+036127Y+121341X0198Y0197R090 S2      
327m3409            PU12  -23         A01X+120968Y+141291X0070Y0260R270 S1      
327m3409            R61   -2          A01X+120008Y+140100X0198Y0197     S1      
317m3410            VIA   -    MD0100PA00X+119400Y+140100X0200Y         S0      
317m3410            VIA   -    M      A01X+130080Y+142180X0200Y         S2      
017m3410            VIA   -    M      A18X+130080Y+142180X0260Y         S2      
017m3410                  -    MD0100PA00X+130080Y+142180                       
327m3410            R8043 -2          A18X+119108Y+140100X0198Y0197R180 S2      
327m3410            C303  -1          A01X+119108Y+140100X0198Y0197R180 S1      
327m3410            R8042 -1          A18X+119692Y+140100X0198Y0197R180 S2      
327m3410            R61   -1          A01X+119692Y+140100X0198Y0197     S1      
317m3410            VIA   -    MD0100PA00X+131878Y+121957X0200Y         S0      
327m3410            U25   -DG73       A01X+128972Y+115776X0177Y    R180 S1      
327m3411            VIA   -    M      A01X+120327Y+139914X0300Y         S1      
327m3411            PR62  -2          A01X+120008Y+139650X0198Y0197     S1      
327m3411            PU12  -24         A01X+120968Y+141134X0070Y0260R270 S1      
317m3412            VIA   -    M      A01X+119430Y+139650X0200Y         S2      
017m3412            VIA   -    M      A18X+119430Y+139650X0260Y         S2      
017m3412                  -    MD0100PA00X+119430Y+139650                       
327m3412            PR41  -2          A18X+119108Y+139650X0198Y0197R180 S2      
327m3412            PR40  -1          A01X+119108Y+139650X0198Y0197R180 S1      
327m3412            PR62  -1          A01X+119692Y+139650X0198Y0197     S1      
327m3413            PR8008-1          A01X+119692Y+141000X0198Y0197     S1      
317m3413            VIA   -    MD0100PA00X+119393Y+141000X0200Y         S0      
317m3413            VIA   -    M      A01X+129570Y+142180X0200Y         S2      
017m3413            VIA   -    M      A18X+129570Y+142180X0260Y         S2      
017m3413                  -    MD0100PA00X+129570Y+142180                       
327m3413            R8045 -2          A18X+119108Y+141000X0198Y0197R180 S2      
327m3413            C304  -1          A01X+119108Y+141000X0198Y0197R180 S1      
327m3413            PR60  -1          A18X+133681Y+122856X0198Y0197     S2      
327m3414            VIA   -    M      A18X+132951Y+122856X0260Y         S2      
317m3414            VIA   -    MD0100PA00X+132214Y+121736X0200Y    R180 S0      
327m3414            PR60  -2          A18X+133366Y+122856X0198Y0197     S2      
327m3414            U25   -DH72       A01X+129157Y+116094X0177Y    R180 S1      
317m3415            VIA   -    MD0100PA00X+119437Y+140550X0200Y         S0      
327m3415            PR8007-1          A01X+119692Y+140550X0198Y0197     S1      
317m3415            VIA   -    M      A01X+130190Y+142770X0200Y         S2      
017m3415            VIA   -    M      A18X+130190Y+142770X0260Y         S2      
017m3415                  -    MD0100PA00X+130190Y+142770                       
327m3415            R8048 -2          A18X+119108Y+140550X0198Y0197R180 S2      
327m3415            C305  -1          A01X+119108Y+140550X0198Y0197R180 S1      
327m3415            PR59  -1          A18X+134597Y+122431X0198Y0197     S2      
327m3416            VIA   -    M      A18X+133730Y+122502X0260Y         S2      
327m3416            PR59  -2          A18X+134282Y+122431X0198Y0197     S2      
327m3416            U25   -DJ72       A01X+129342Y+116413X0177Y    R180 S1      
317m3416            VIA   -    MD0100PA00X+132490Y+121642X0200Y    R180 S0      
327m3417            VIA   -    M      A18X+036047Y+058173X0260Y    R180 S2      
327m3417            R8171 -2          A18X+035673Y+058642X0198Y0197R180 S2      
327m3417            PU25  -23         A18X+036534Y+057700X0070Y0260R270 S2      
327m3418            C295  -1   M      A01X+034873Y+058642X0198Y0197R180 S1      
327m3418            U26   -B21        A01X+050298Y+087748X0177Y    R180 S1      
327m3418            R154  -2          A01X+035598Y+058642X0198Y0197R180 S1      
327m3418            VIA   -    M      A01X+033775Y+058475X0300Y    R180 S1      
327m3418            R8153 -1          A18X+034873Y+058642X0198Y0197     S2      
327m3418            R8171 -1          A18X+035358Y+058642X0198Y0197R180 S2      
317m3418            VIA   -    MD0100PA00X+035116Y+058642X0200Y    R180 S0      
327m3419            PU25  -24         A18X+036534Y+057858X0070Y0260R270 S2      
327m3419            VIA   -    M      A18X+036310Y+058596X0260Y    R270 S2      
327m3419            PR172 -2          A18X+035673Y+059042X0198Y0197R180 S2      
317m3420            VIA   -    M      A01X+035116Y+059042X0300Y    R180 S1      
017m3420            VIA   -    M      A18X+035116Y+059042X0200Y    R180 S1      
017m3420                  -    MD0100PA00X+035116Y+059042                       
327m3420            PR151 -2          A01X+035598Y+059042X0198Y0197R180 S1      
327m3420            PR172 -1          A18X+035358Y+059042X0198Y0197R180 S2      
327m3420            PR150 -1          A18X+034873Y+059134X0198Y0197     S2      
327m3421            PR8010-1          A18X+034542Y+057850X0198Y0197R180 S2      
327m3421            VIA   -    M      A01X+057522Y+075976X0300Y         S1      
327m3421            PR170 -1          A01X+057522Y+076444X0198Y0197R090 S1      
317m3421            VIA   -    MD0100PA00X+033842Y+057450X0200Y         S0      
327m3421            C296  -1          A18X+033958Y+057850X0198Y0197     S2      
327m3421            R8156 -2          A01X+035358Y+057842X0198Y0197R180 S1      
317m3421            VIA   -    MD0100PA00X+034250Y+057850X0200Y         S0      
327m3422            U26   -A22        A01X+049743Y+087429X0177Y    R180 S1      
327m3422            VIA   -    M      A01X+057522Y+077226X0300Y    R180 S1      
327m3422            PR170 -2          A01X+057522Y+076759X0198Y0197R090 S1      
327m3423            PR8009-1          A18X+034542Y+058250X0198Y0197R180 S2      
327m3423            C297  -1          A18X+033958Y+058250X0198Y0197     S2      
327m3423            R8160 -2          A01X+035358Y+058242X0198Y0197R180 S1      
317m3423            VIA   -    MD0100PA00X+034250Y+058250X0200Y         S0      
327m3423            VIA   -    M      A01X+057022Y+075976X0300Y         S1      
327m3423            PR169 -1          A01X+057022Y+076444X0198Y0197R090 S1      
317m3423            VIA   -    MD0100PA00X+034150Y+057450X0200Y         S0      
327m3424            U26   -A23        A01X+049373Y+087429X0177Y    R180 S1      
327m3424            VIA   -    M      A01X+057022Y+077226X0300Y    R180 S1      
327m3424            PR169 -2          A01X+057022Y+076759X0198Y0197R090 S1      
327m3425            R8304 -2          A18X+146983Y+057698X0198Y0197R180 S2      
327m3425            PU42  -23         A18X+147844Y+056756X0070Y0260R270 S2      
327m3425            VIA   -    M      A18X+147294Y+057834X0260Y    R180 S2      
317m3426            VIA   -    MD0080PA00X+148096Y+087643X0160Y    R180 S0      
327m3426            U25   -B21        A01X+147913Y+087748X0177Y    R180 S1      
327m3426            VIA   -    M      A18X+144071Y+084140X0260Y    R180 S2      
317m3426            VIA   -    MD0100PA00X+119846Y+066814X0200Y         S0      
327m3426            R8286 -1          A01X+146183Y+057698X0198Y0197R180 S1      
327m3426            R8287 -2          A01X+146668Y+057698X0198Y0197R180 S1      
327m3426            R8304 -1          A18X+146668Y+057698X0198Y0197R180 S2      
327m3426            C298  -1          A18X+146183Y+057698X0198Y0197     S2      
317m3426            VIA   -    MD0100PA00X+146426Y+057698X0200Y    R180 S0      
327m3427            PU42  -24         A18X+147844Y+056914X0070Y0260R270 S2      
327m3427            PR305 -2          A18X+146983Y+058098X0198Y0197R180 S2      
327m3427            VIA   -    M      A18X+147725Y+057575X0260Y    R180 S2      
317m3428            VIA   -    MD0100PA00X+146426Y+058098X0200Y    R180 S0      
327m3428            PR284 -2          A01X+146668Y+058098X0198Y0197R180 S1      
327m3428            PR305 -1          A18X+146668Y+058098X0198Y0197R180 S2      
327m3428            PR283 -1   M      A18X+146183Y+058098X0198Y0197     S2      
327m3428            VIA   -           A18X+146183Y+058427X0260Y    R180 S2      
327m3429            PR8006-1          A18X+146668Y+056898X0198Y0197R180 S2      
327m3429            C299  -1          A18X+146183Y+056898X0198Y0197     S2      
327m3429            PR303 -1          A18X+144973Y+084365X0198Y0197R180 S2      
317m3429            VIA   -    M      A01X+120433Y+066814X0200Y         S2      
017m3429            VIA   -    M      A18X+120433Y+066814X0260Y         S2      
017m3429                  -    MD0100PA00X+120433Y+066814                       
327m3429            R8289 -2          A01X+146668Y+056898X0198Y0197R180 S1      
317m3429            VIA   -    MD0100PA00X+146426Y+056898X0200Y    R180 S0      
317m3430            VIA   -    MD0080PA00X+147541Y+087324X0160Y    R180 S0      
327m3430            U25   -A22        A01X+147358Y+087429X0177Y    R180 S1      
327m3430            VIA   -    M      A18X+145635Y+084832X0260Y    R180 S2      
327m3430            PR303 -2          A18X+145288Y+084365X0198Y0197R180 S2      
327m3431            PR8005-1          A18X+146668Y+057298X0198Y0197R180 S2      
327m3431            VIA   -    M      A18X+122108Y+066812X0260Y         S2      
317m3431            VIA   -    MD0100PA00X+120980Y+066812X0200Y         S0      
327m3431            C302  -1          A18X+146183Y+057298X0198Y0197     S2      
327m3431            PR302 -1          A18X+144371Y+084765X0198Y0197R180 S2      
327m3431            R8293 -2          A01X+146668Y+057298X0198Y0197R180 S1      
317m3431            VIA   -    MD0100PA00X+146426Y+057298X0200Y    R180 S0      
317m3432            VIA   -    MD0080PA00X+147171Y+087324X0160Y    R180 S0      
327m3432            U25   -A23        A01X+146987Y+087429X0177Y    R180 S1      
327m3432            VIA   -    M      A18X+145135Y+084832X0260Y    R180 S2      
327m3432            PR302 -2          A18X+144686Y+084765X0198Y0197R180 S2      
317SPI_CPU1_R_CLK   VIA   -    MD0080PA00X+048195Y+116518X0160Y         S0      
327SPI_CPU1_R_CLK   U26   -DJ27       A01X+048011Y+116414X0177Y    R180 S1      
327SPI_CPU1_R_CLK   VIA   -    M      A18X+056360Y+126812X0260Y    R270 S2      
327SPI_CPU1_R_CLK   R738  -2          A18X+057015Y+126812X0198Y0197     S2      
327SPI_CPU1_CLK     VIA   -    M      A18X+057848Y+126895X0260Y    R090 S2      
327SPI_CPU1_CLK     R738  -1          A18X+057330Y+126812X0198Y0197     S2      
327SPI_CPU1_CLK     R754  -2          A18X+060577Y+127285X0198Y0197R270 S2      
327SPI_CPU1_CLK     R730  -2   M      A18X+060177Y+127285X0198Y0197R270 S2      
327m3433            R475  -1          A01X+157828Y+127545X0198Y0197R180 S1      
317m3433            VIA   -    MD0100PA00X+158058Y+127094X0200Y    R180 S0      
327m3433            R659  -2          A01X+103968Y+053407X0198Y0197R180 S1      
317m3433            VIA   -    M      A01X+103602Y+053499X0200Y    R180 S2      
017m3433            VIA   -    M      A18X+103602Y+053499X0260Y    R180 S2      
017m3433                  -    MD0100PA00X+103602Y+053499                       
327m3433            U53   -6          A01X+103068Y+052738X0140Y0630R090 S1      
327m3434            U25   -DJ25       A01X+146365Y+116413X0177Y    R180 S1      
327m3434            VIA   -    M      A01X+152288Y+126850X0300Y    R180 S1      
327m3434            R475  -2          A01X+157513Y+127545X0198Y0197R180 S1      
327SPI_CPU0_R_D3    R467  -2          A01X+158210Y+129299X0198Y0197R180 S1      
327SPI_CPU0_R_D3    U25   -DG29       A01X+144885Y+115776X0177Y    R180 S1      
327SPI_CPU0_R_D3    VIA   -    M      A01X+151305Y+128642X0300Y    R180 S1      
327SPI_CPU0_R_D2    U25   -DJ28       A01X+145255Y+116413X0177Y    R180 S1      
327SPI_CPU0_R_D2    VIA   -    M      A01X+152135Y+128114X0300Y    R180 S1      
327SPI_CPU0_R_D2    R466  -2          A01X+157483Y+128896X0198Y0197R180 S1      
317SPI_CPU0_R_D1    VIA   -    MD0080PA00X+147659Y+115880X0160Y         S0      
327SPI_CPU0_R_D1    U25   -DG22       A01X+147476Y+115776X0177Y    R180 S1      
327SPI_CPU0_R_D1    R465  -2          A01X+157072Y+127138X0198Y0197R180 S1      
317SPI_CPU0_R_D1    VIA   -    M      A01X+156774Y+127141X0200Y    R180 S2      
017SPI_CPU0_R_D1    VIA   -    M      A18X+156774Y+127141X0260Y    R180 S2      
017SPI_CPU0_R_D1          -    MD0100PA00X+156774Y+127141                       
317SPI_CPU0_R_D0    VIA   -    MD0080PA00X+145624Y+115561X0160Y         S0      
327SPI_CPU0_R_D0    R464  -2          A01X+155797Y+130261X0198Y0197R180 S1      
317SPI_CPU0_R_D0    VIA   -    M      A01X+155522Y+130276X0200Y         S2      
017SPI_CPU0_R_D0    VIA   -    M      A18X+155522Y+130276X0260Y         S2      
017SPI_CPU0_R_D0          -    MD0100PA00X+155522Y+130276                       
327SPI_CPU0_R_D0    U25   -DF28       A01X+145440Y+115457X0177Y    R180 S1      
317m3435            VIA   -    MD0080PA00X+146179Y+115880X0160Y         S0      
327m3435            U25   -DG26       A01X+145995Y+115776X0177Y    R180 S1      
327m3435            VIA   -    M      A18X+146001Y+119675X0260Y    R180 S2      
327m3435            R460  -2          A18X+154740Y+128994X0198Y0197     S2      
317m3436            VIA   -    MD0080PA00X+144884Y+115561X0160Y         S0      
327m3436            R459  -2          A01X+157568Y+130305X0198Y0197R090 S1      
317m3436            VIA   -    M      A01X+157242Y+130316X0200Y         S2      
017m3436            VIA   -    M      A18X+157242Y+130316X0260Y         S2      
017m3436                  -    MD0100PA00X+157242Y+130316                       
327m3436            U25   -DF30       A01X+144700Y+115457X0177Y    R180 S1      
327SPI_CPU0_R_CLK   U25   -DJ27       A01X+145625Y+116413X0177Y    R180 S1      
327SPI_CPU0_R_CLK   VIA   -    M      A01X+152904Y+128013X0300Y    R180 S1      
327SPI_CPU0_R_CLK   R461  -2          A01X+158210Y+127899X0198Y0197R180 S1      
327m3437            J41   -OB12       A01X+072623Y+006516X0150Y0570R180 S1      
317m3437            VIA   -    MD0100PA00X+072577Y+006974X0200Y         S0      
317m3437            VIA   -    M      A01X+099406Y+053107X0200Y    R180 S2      
017m3437            VIA   -    M      A18X+099406Y+053107X0260Y    R180 S2      
017m3437                  -    MD0100PA00X+099406Y+053107                       
327m3437            R1547 -2          A01X+099163Y+053107X0198Y0197     S1      
327m3437            R608  -2          A01X+099648Y+053107X0198Y0197R180 S1      
327m3438            J41   -B16        A01X+066877Y+006516X0150Y0570R180 S1      
327m3438            R607  -2          A01X+101221Y+054507X0198Y0197R180 S1      
327m3438            R129  -2          A01X+100701Y+054507X0198Y0197R090 S1      
317m3438            VIA   -    MD0100PA00X+100961Y+054507X0200Y         S0      
317m3438            VIA   -    M      A01X+066620Y+008486X0200Y         S2      
017m3438            VIA   -    M      A18X+066620Y+008486X0260Y         S2      
017m3438                  -    MD0100PA00X+066620Y+008486                       
327m3439            J41   -B15        A01X+067113Y+006516X0150Y0570R180 S1      
327m3439            R606  -2          A01X+101221Y+055007X0198Y0197R180 S1      
327m3439            R128  -2          A01X+100701Y+055007X0198Y0197R270 S1      
317m3439            VIA   -    MD0100PA00X+100961Y+055007X0200Y         S0      
317m3439            VIA   -    M      A01X+066794Y+008014X0200Y         S2      
017m3439            VIA   -    M      A18X+066794Y+008014X0260Y         S2      
017m3439                  -    MD0100PA00X+066794Y+008014                       
327m3440            J41   -B14        A01X+067349Y+006516X0150Y0570R180 S1      
327m3440            R127  -2          A01X+102458Y+056600X0198Y0197     S1      
327m3440            R605  -2          A01X+102496Y+056051X0198Y0197R090 S1      
317m3440            VIA   -    MD0100PA00X+102400Y+056300X0200Y         S0      
317m3440            VIA   -    M      A01X+065823Y+008845X0200Y         S2      
017m3440            VIA   -    M      A18X+065823Y+008845X0260Y         S2      
017m3440                  -    MD0100PA00X+065823Y+008845                       
327m3441            J41   -B13        A01X+067585Y+006516X0150Y0570R180 S1      
317m3441            VIA   -    MD0100PA00X+101600Y+056311X0200Y         S0      
317m3441            VIA   -    M      A01X+067404Y+007452X0200Y         S2      
017m3441            VIA   -    M      A18X+067404Y+007452X0260Y         S2      
017m3441                  -    MD0100PA00X+067404Y+007452                       
327m3441            R604  -2          A01X+101996Y+056051X0198Y0197R090 S1      
327m3441            R21   -2   M      A01X+101608Y+056050X0198Y0197     S1      
317m3442            VIA   -    M      A01X+099406Y+052607X0200Y    R180 S2      
017m3442            VIA   -    M      A18X+099406Y+052607X0260Y    R180 S2      
017m3442                  -    MD0100PA00X+099406Y+052607                       
327m3442            R1655 -2          A01X+099163Y+052607X0198Y0197     S1      
327m3442            R600  -2          A01X+099648Y+052607X0198Y0197R180 S1      
327m3443            J41   -B12        A01X+067822Y+006516X0150Y0570R180 S1      
317m3443            VIA   -    M      A01X+099406Y+051601X0200Y    R180 S2      
017m3443            VIA   -    M      A18X+099406Y+051601X0260Y    R180 S2      
017m3443                  -    MD0100PA00X+099406Y+051601                       
327m3443            R610  -2          A01X+099163Y+051601X0198Y0197     S1      
327m3443            R603  -2          A01X+099648Y+051601X0198Y0197R180 S1      
317m3443            VIA   -    MD0100PA00X+067551Y+008817X0200Y         S0      
327m3444            J41   -B11        A01X+068058Y+006516X0150Y0570R180 S1      
317m3444            VIA   -    MD0100PA00X+068058Y+007923X0200Y         S0      
317m3444            VIA   -    M      A01X+099406Y+052101X0200Y    R180 S2      
017m3444            VIA   -    M      A18X+099406Y+052101X0260Y    R180 S2      
017m3444                  -    MD0100PA00X+099406Y+052101                       
327m3444            R20   -2          A01X+099163Y+052101X0198Y0197     S1      
327m3444            R602  -2          A01X+099648Y+052101X0198Y0197R180 S1      
327m3445            U53   -11         A01X+100863Y+052738X0140Y0630R090 S1      
317m3445            VIA   -    M      A01X+100206Y+053107X0200Y    R180 S2      
017m3445            VIA   -    M      A18X+100206Y+053107X0260Y    R180 S2      
017m3445                  -    MD0100PA00X+100206Y+053107                       
327m3445            R608  -1          A01X+099963Y+053107X0198Y0197R180 S1      
317m3446            VIA   -    M      A01X+101796Y+054507X0200Y         S2      
017m3446            VIA   -    M      A18X+101796Y+054507X0260Y         S2      
017m3446                  -    MD0100PA00X+101796Y+054507                       
327m3446            R607  -1          A01X+101536Y+054507X0198Y0197R180 S1      
327m3446            U54   -10         A01X+102496Y+054507X0070Y0280R270 S1      
327m3447            VIA   -    M      A01X+101887Y+054986X0300Y         S1      
327m3447            R606  -1          A01X+101536Y+055007X0198Y0197R180 S1      
327m3447            U54   -9          A01X+102496Y+054665X0070Y0280R270 S1      
317m3448            VIA   -    M      A01X+102416Y+055476X0200Y         S2      
017m3448            VIA   -    M      A18X+102416Y+055476X0260Y         S2      
017m3448                  -    MD0100PA00X+102416Y+055476                       
327m3448            R605  -1          A01X+102496Y+055736X0198Y0197R090 S1      
327m3448            U54   -7          A01X+102496Y+054980X0070Y0280R270 S1      
317m3449            VIA   -    M      A01X+101916Y+055476X0200Y         S2      
017m3449            VIA   -    M      A18X+101916Y+055476X0260Y         S2      
017m3449                  -    MD0100PA00X+101916Y+055476                       
327m3449            R604  -1          A01X+101996Y+055736X0198Y0197R090 S1      
327m3449            U54   -8          A01X+102496Y+054822X0070Y0280R270 S1      
317m3450            VIA   -    M      A01X+100206Y+052607X0200Y    R180 S2      
017m3450            VIA   -    M      A18X+100206Y+052607X0260Y    R180 S2      
017m3450                  -    MD0100PA00X+100206Y+052607                       
327m3450            R600  -1          A01X+099963Y+052607X0198Y0197R180 S1      
327m3450            U53   -12         A01X+100863Y+052482X0140Y0630R090 S1      
317m3451            VIA   -    M      A01X+100206Y+051601X0200Y    R180 S2      
017m3451            VIA   -    M      A18X+100206Y+051601X0260Y    R180 S2      
017m3451                  -    MD0100PA00X+100206Y+051601                       
327m3451            R603  -1          A01X+099963Y+051601X0198Y0197R180 S1      
327m3451            U53   -14         A01X+100863Y+051970X0140Y0630R090 S1      
317m3452            VIA   -    M      A01X+100206Y+052101X0200Y    R180 S2      
017m3452            VIA   -    M      A18X+100206Y+052101X0260Y    R180 S2      
017m3452                  -    MD0100PA00X+100206Y+052101                       
327m3452            R602  -1          A01X+099963Y+052101X0198Y0197R180 S1      
327m3452            U53   -13         A01X+100863Y+052226X0140Y0630R090 S1      
327SPI_CPU0_D3      R8005 -1          A01X+104558Y+053800X0198Y0197R180 S1      
317SPI_CPU0_D3      VIA   -    MD0100PA00X+158617Y+129548X0200Y    R180 S0      
317SPI_CPU0_D3      VIA   -    M      A01X+104399Y+054098X0200Y         S2      
017SPI_CPU0_D3      VIA   -    M      A18X+104399Y+054098X0260Y         S2      
017SPI_CPU0_D3            -    MD0100PA00X+104399Y+054098                       
327SPI_CPU0_D3      R1529 -2          A01X+104168Y+054457X0198Y0197R180 S1      
327SPI_CPU0_D3      R467  -1          A01X+158525Y+129299X0198Y0197R180 S1      
327SPI_CPU0_D2      R8006 -1          A01X+104491Y+055364X0198Y0197R180 S1      
317SPI_CPU0_D2      VIA   -    MD0100PA00X+158052Y+128990X0200Y    R180 S0      
317SPI_CPU0_D2      VIA   -    M      A01X+103941Y+054772X0200Y         S2      
017SPI_CPU0_D2      VIA   -    M      A18X+103941Y+054772X0260Y         S2      
017SPI_CPU0_D2            -    MD0100PA00X+103941Y+054772                       
327SPI_CPU0_D2      R1530 -2   M      A01X+104168Y+054957X0198Y0197R180 S1      
327SPI_CPU0_D2      R466  -1          A01X+157798Y+128896X0198Y0197R180 S1      
327SPI_CPU0_D1      R8008 -1          A01X+103000Y+056058X0198Y0197R270 S1      
317SPI_CPU0_D1      VIA   -    M      A01X+102850Y+056300X0200Y         S2      
017SPI_CPU0_D1      VIA   -    M      A18X+102850Y+056300X0260Y         S2      
017SPI_CPU0_D1            -    MD0100PA00X+102850Y+056300                       
327SPI_CPU0_D1      R1531 -2          A01X+102842Y+056600X0198Y0197R180 S1      
317SPI_CPU0_D1      VIA   -    MD0100PA00X+157708Y+127094X0200Y    R180 S0      
327SPI_CPU0_D1      R465  -1          A01X+157387Y+127138X0198Y0197R180 S1      
327SPI_CPU0_D0      R8007 -1          A01X+103550Y+056058X0198Y0197R270 S1      
317SPI_CPU0_D0      VIA   -    MD0100PA00X+157417Y+128330X0200Y    R180 S0      
317SPI_CPU0_D0      VIA   -    M      A01X+104263Y+055684X0200Y         S2      
017SPI_CPU0_D0      VIA   -    M      A18X+104263Y+055684X0260Y         S2      
017SPI_CPU0_D0            -    MD0100PA00X+104263Y+055684                       
327SPI_CPU0_D0      R1532 -2   M      A01X+103900Y+056058X0198Y0197R090 S1      
327SPI_CPU0_D0      R464  -1          A01X+156112Y+130261X0198Y0197R180 S1      
317SPI_CPU0_CS1_N   VIA   -    M      A01X+103725Y+052607X0200Y    R180 S2      
017SPI_CPU0_CS1_N   VIA   -    M      A18X+103725Y+052607X0260Y    R180 S2      
017SPI_CPU0_CS1_N         -    MD0100PA00X+103725Y+052607                       
327SPI_CPU0_CS1_N   R601  -2          A01X+103968Y+052607X0198Y0197R180 S1      
327SPI_CPU0_CS1_N   U53   -5          A01X+103068Y+052482X0140Y0630R090 S1      
317SPI_CPU0_CS1_N   VIA   -    MD0100PA00X+155652Y+129223X0200Y         S0      
327SPI_CPU0_CS1_N   R460  -1          A18X+155055Y+128994X0198Y0197     S2      
327SPI_CPU0_CS0_N   R459  -1          A01X+157568Y+129990X0198Y0197R090 S1      
317SPI_CPU0_CS0_N   VIA   -    MD0100PA00X+157456Y+129641X0200Y    R180 S0      
327SPI_CPU0_CS0_N   U53   -3          A01X+103068Y+051970X0140Y0630R090 S1      
317SPI_CPU0_CS0_N   VIA   -    M      A01X+103671Y+051488X0200Y    R180 S2      
017SPI_CPU0_CS0_N   VIA   -    M      A18X+103671Y+051488X0260Y    R180 S2      
017SPI_CPU0_CS0_N         -    MD0100PA00X+103671Y+051488                       
327SPI_CPU0_CS0_N   R811  -2          A01X+103968Y+051601X0198Y0197R180 S1      
327SPI_CPU0_CLK     R461  -1          A01X+158525Y+127899X0198Y0197R180 S1      
327SPI_CPU0_CLK     R743  -2   M      A01X+158860Y+127899X0198Y0197R180 S1      
317SPI_CPU0_CLK     VIA   -    MD0100PA00X+159636Y+128630X0200Y    R180 S0      
327SPI_CPU0_CLK     R6098 -2          A01X+103968Y+052107X0198Y0197R180 S1      
317SPI_CPU0_CLK     VIA   -    M      A01X+103725Y+052101X0200Y    R180 S2      
017SPI_CPU0_CLK     VIA   -    M      A18X+103725Y+052101X0260Y    R180 S2      
017SPI_CPU0_CLK           -    MD0100PA00X+103725Y+052101                       
327SPI_CPU0_CLK     U53   -4          A01X+103068Y+052226X0140Y0630R090 S1      
327SMERR_LED_N      D6    -C          A01X+134935Y+006665X0320Y0320R090 S1      
327SMERR_LED_N      Q11   -3          A01X+135175Y+008282X0170Y0200     S1      
327SMERR_LED_N      VIA   -    M      A01X+134388Y+007045X0300Y    R270 S1      
327SMERR_LED        R947  -2          A01X+136011Y+009248X0198Y0197R270 S1      
327SMERR_LED        VIA   -    M      A01X+136011Y+008768X0300Y         S1      
327SMERR_LED        Q11   -5          A01X+135431Y+007534X0170Y0200     S1      
327SMERR_LED        Q11   -6   M      A01X+135687Y+007534X0170Y0200     S1      
327m3453            R3712 -1          A01X+106884Y+048766X0198Y0197R180 S1      
327m3453            R4270 -2          A01X+107464Y+048778X0198Y0197R180 S1      
317m3453            VIA   -    M      A01X+107171Y+048878X0200Y         S2      
017m3453            VIA   -    M      A18X+107171Y+048878X0260Y         S2      
017m3453                  -    MD0100PA00X+107171Y+048878                       
317m3453            VIA   -    MD0100PA00X+069247Y+003595X0200Y         S0      
327m3453            R2422 -1          A18X+069247Y+003838X0198Y0197R270 S2      
317m3454            VIA   -    MD0100PA00X+069789Y+003595X0200Y         S0      
327m3454            R2421 -1          A18X+069789Y+003838X0198Y0197R270 S2      
327m3454            R4269 -2          A01X+107464Y+048378X0198Y0197R180 S1      
327m3454            R3711 -1          A01X+106884Y+048366X0198Y0197R180 S1      
317m3454            VIA   -    M      A01X+107171Y+048366X0200Y         S2      
017m3454            VIA   -    M      A18X+107171Y+048366X0260Y         S2      
017m3454                  -    MD0100PA00X+107171Y+048366                       
317m3455            VIA   -    M      A01X+004774Y+158488X0200Y         S2      
017m3455            VIA   -    M      A18X+004774Y+158488X0260Y         S2      
017m3455                  -    MD0100PA00X+004774Y+158488                       
327m3455            R6859 -1          A18X+005220Y+158598X0198Y0197R180 S2      
317m3455            VIA   -    MD0100PA00X+005100Y+133920X0200Y         S0      
317m3455            VIA   -    MD0100PA00X+008404Y+060223X0200Y         S0      
317m3455            VIA   -    MD0100PA00X+008450Y+144850X0200Y         S0      
327m3455            R1494 -1          A01X+008692Y+144850X0198Y0197     S1      
317m3455            VIA   -    MD0100PA00X+036865Y+055042X0200Y         S0      
327m3455            R309  -2   M      A18X+036622Y+054800X0198Y0197     S2      
327m3455            R8176 -1          A18X+036216Y+055034X0198Y0197R270 S2      
317m3456            VIA   -    M      A01X+004797Y+158998X0200Y         S2      
017m3456            VIA   -    M      A18X+004797Y+158998X0260Y         S2      
017m3456                  -    MD0100PA00X+004797Y+158998                       
317m3456            VIA   -    MD0100PA00X+035057Y+054188X0200Y         S0      
327m3456            R308  -2          A18X+036622Y+054400X0198Y0197     S2      
327m3456            R175  -1   M      A18X+036216Y+054334X0198Y0197R270 S2      
327m3456            R6858 -1          A18X+005220Y+158998X0198Y0197R180 S2      
317m3456            VIA   -    MD0100PA00X+008450Y+144450X0200Y         S0      
327m3456            R1321 -1          A01X+008692Y+144450X0198Y0197     S1      
317m3456            VIA   -    MD0100PA00X+005370Y+134230X0200Y         S0      
317m3456            VIA   -    MD0100PA00X+008406Y+059937X0200Y         S0      
327m3457            J41   -A6         A01X+069239Y+005354X0150Y0570R180 S1      
327m3457            R2422 -2          A18X+069247Y+004152X0198Y0197R270 S2      
317m3457            VIA   -    M      A01X+069239Y+004694X0200Y         S2      
017m3457            VIA   -    M      A18X+069239Y+004694X0260Y         S2      
017m3457                  -    MD0100PA00X+069239Y+004694                       
327m3458            R309  -1          A18X+036938Y+054800X0198Y0197     S2      
317m3458            VIA   -    MD0100PA00X+038270Y+054643X0200Y         S0      
317m3458            VIA   -    MD0100PA00X+087059Y+064242X0200Y         S0      
327m3458            R1498 -1   M      A01X+099596Y+047918X0198Y0197R180 S1      
317m3458            VIA   -    M      A01X+098812Y+048519X0200Y         S2      
017m3458            VIA   -    M      A18X+098812Y+048519X0260Y         S2      
017m3458                  -    MD0100PA00X+098812Y+048519                       
327m3458            R3714 -2          A01X+101119Y+048016X0198Y0197R180 S1      
327m3458            R3724 -2   M      A01X+100391Y+048468X0198Y0197     S1      
327m3459            J41   -A5         A01X+069475Y+005354X0150Y0570R180 S1      
327m3459            R2421 -2          A18X+069789Y+004152X0198Y0197R270 S2      
317m3459            VIA   -    M      A01X+069768Y+004713X0200Y         S2      
017m3459            VIA   -    M      A18X+069768Y+004713X0260Y         S2      
017m3459                  -    MD0100PA00X+069768Y+004713                       
327m3460            R308  -1          A18X+036938Y+054400X0198Y0197     S2      
317m3460            VIA   -    MD0100PA00X+037911Y+054487X0200Y         S0      
317m3460            VIA   -    MD0100PA00X+086459Y+064242X0200Y         S0      
317m3460            VIA   -    M      A01X+099127Y+047021X0200Y         S2      
017m3460            VIA   -    M      A18X+099127Y+047021X0260Y         S2      
017m3460                  -    MD0100PA00X+099127Y+047021                       
327m3460            R1497 -1   M      A01X+099596Y+047368X0198Y0197R180 S1      
327m3460            R3723 -2   M      A01X+100391Y+047918X0198Y0197     S1      
327m3460            R3713 -2          A01X+101119Y+047616X0198Y0197R180 S1      
317m3461            VIA   -    M      A01X+069221Y+162004X0200Y         S2      
017m3461            VIA   -    M      A18X+069221Y+162004X0260Y         S2      
017m3461                  -    MD0100PA00X+069221Y+162004                       
317m3461            VIA   -    MD0100PA00X+070902Y+160910X0200Y         S0      
317m3461            VIA   -    MD0100PA00X+092450Y+130200X0200Y         S0      
327m3461            R6785 -2          A18X+092158Y+130200X0198Y0197R180 S2      
317m3461            VIA   -    MD0100PA00X+074598Y+150105X0200Y         S0      
327m3461            R348  -1   M      A01X+070257Y+161666X0198Y0197     S1      
317m3461            VIA   -    MD0100PA00X+090030Y+083122X0200Y         S0      
317m3461            VIA   -    MD0100PA00X+080612Y+033010X0200Y         S0      
317m3461            VIA   -    MD0100PA00X+065101Y+006082X0200Y         S0      
327m3461            R2996 -2          A18X+065101Y+006474X0198Y0197R180 S2      
327m3461            R1714 -1          A18X+071409Y+160362X0198Y0197R090 S2      
317m3462            VIA   -    MD0100PA00X+092450Y+130600X0200Y         S0      
327m3462            R6784 -2          A18X+092158Y+130600X0198Y0197R180 S2      
317m3462            VIA   -    MD0100PA00X+074611Y+150412X0200Y         S0      
327m3462            R347  -1   M      A01X+070230Y+162306X0198Y0197R180 S1      
317m3462            VIA   -    MD0100PA00X+090030Y+082825X0200Y         S0      
317m3462            VIA   -    MD0100PA00X+080862Y+033010X0200Y         S0      
317m3462            VIA   -    MD0100PA00X+066093Y+006071X0200Y         S0      
327m3462            R2995 -2          A18X+065874Y+005851X0198Y0197R270 S2      
317m3462            VIA   -    MD0100PA00X+068990Y+162178X0200Y         S0      
327m3462            R3909 -1          A18X+071769Y+160480X0198Y0197R090 S2      
317m3462            VIA   -    M      A01X+071372Y+161024X0200Y         S2      
017m3462            VIA   -    M      A18X+071372Y+161024X0260Y         S2      
017m3462                  -    MD0100PA00X+071372Y+161024                       
327m3463            R1714 -2          A18X+071409Y+160047X0198Y0197R090 S2      
317m3463            VIA   -    M      A01X+071437Y+159468X0200Y    R270 S2      
017m3463            VIA   -    M      A18X+071437Y+159468X0260Y    R270 S2      
017m3463                  -    MD0100PA00X+071437Y+159468                       
327m3463            PU289 -12         A01X+072058Y+159117X0090Y0150     S1      
327m3464            R3909 -2          A18X+071769Y+160165X0198Y0197R090 S2      
317m3464            VIA   -    M      A01X+071889Y+159715X0200Y    R270 S2      
017m3464            VIA   -    M      A18X+071889Y+159715X0260Y    R270 S2      
017m3464                  -    MD0100PA00X+071889Y+159715                       
327m3464            PU289 -11         A01X+072236Y+159117X0090Y0150     S1      
327m3465            J41   -A26        A01X+064515Y+005354X0150Y0570R180 S1      
327m3465            R2424 -2          A18X+064522Y+005218X0198Y0197R090 S2      
317m3465            VIA   -    M      A01X+064604Y+004154X0200Y         S2      
017m3465            VIA   -    M      A18X+064604Y+004154X0260Y         S2      
017m3465                  -    MD0100PA00X+064604Y+004154                       
327m3466            J41   -A25        A01X+064751Y+005354X0150Y0570R180 S1      
327m3466            R2423 -2          A18X+064922Y+005218X0198Y0197R090 S2      
317m3466            VIA   -    M      A01X+064799Y+004761X0200Y         S2      
017m3466            VIA   -    M      A18X+064799Y+004761X0260Y         S2      
017m3466                  -    MD0100PA00X+064799Y+004761                       
317m3467            VIA   -    MD0100PA00X+101822Y+024364X0200Y    R180 S0      
327m3467            R2968 -2          A01X+109887Y+045936X0198Y0197R180 S1      
327m3467            R1090 -2   M      A01X+109351Y+045710X0198Y0197     S1      
317m3467            VIA   -    M      A01X+061880Y+016536X0200Y         S2      
017m3467            VIA   -    M      A18X+061880Y+016536X0260Y         S2      
017m3467                  -    MD0100PA00X+061880Y+016536                       
327m3467            U98   -5          A01X+061280Y+016786X0140Y0590R270 S1      
317m3468            VIA   -    M      A01X+061880Y+017042X0200Y         S2      
017m3468            VIA   -    M      A18X+061880Y+017042X0260Y         S2      
017m3468                  -    MD0100PA00X+061880Y+017042                       
327m3468            U98   -6          A01X+061280Y+017042X0140Y0590R270 S1      
317m3468            VIA   -    MD0100PA00X+102422Y+024364X0200Y    R180 S0      
327m3468            R2967 -2          A01X+109887Y+045536X0198Y0197R180 S1      
327m3468            R1089 -2   M      A01X+109351Y+045160X0198Y0197     S1      
317m3469            VIA   -    MD0100PA00X+083522Y+016386X0200Y         S0      
327m3469            U279  -6          A01X+084256Y+017348X0170Y0460R270 S1      
327m3469            R3527 -2          A01X+109887Y+045136X0198Y0197R180 S1      
317m3469            VIA   -    M      A01X+108484Y+044352X0200Y         S2      
017m3469            VIA   -    M      A18X+108484Y+044352X0260Y         S2      
017m3469                  -    MD0100PA00X+108484Y+044352                       
327m3469            R3536 -2   M      A01X+109351Y+044610X0198Y0197     S1      
317m3470            VIA   -    MD0100PA00X+083822Y+016386X0200Y         S0      
327m3470            U279  -7          A01X+084256Y+017092X0170Y0460R270 S1      
327m3470            R3526 -2          A01X+109887Y+044736X0198Y0197R180 S1      
317m3470            VIA   -    M      A01X+108484Y+043823X0200Y         S2      
017m3470            VIA   -    M      A18X+108484Y+043823X0260Y         S2      
017m3470                  -    MD0100PA00X+108484Y+043823                       
327m3470            R3535 -2   M      A01X+109351Y+044060X0198Y0197     S1      
317m3471            VIA   -    M      A01X+063585Y+139338X0200Y         S2      
017m3471            VIA   -    M      A18X+063585Y+139338X0260Y         S2      
017m3471                  -    MD0100PA00X+063585Y+139338                       
327m3471            R1496 -2          A18X+007842Y+144850X0198Y0197     S2      
317m3471            VIA   -    MD0100PA00X+007376Y+144850X0200Y         S0      
327m3471            R350  -1          A01X+063500Y+140142X0198Y0197R090 S1      
327m3471            R8382 -1          A01X+063410Y+139003X0198Y0197R270 S1      
317m3472            VIA   -    M      A01X+063052Y+139255X0200Y         S2      
017m3472            VIA   -    M      A18X+063052Y+139255X0260Y         S2      
017m3472                  -    MD0100PA00X+063052Y+139255                       
327m3472            R1495 -2          A18X+007842Y+144450X0198Y0197     S2      
317m3472            VIA   -    MD0100PA00X+007382Y+144594X0200Y         S0      
327m3472            R349  -1          A01X+063000Y+140142X0198Y0197R090 S1      
327m3472            R8381 -1          A01X+063020Y+139003X0198Y0197R270 S1      
327m3473            VIA   -    M      A18X+008829Y+144664X0260Y         S2      
327m3473            R1496 -1          A18X+008158Y+144850X0198Y0197     S2      
317m3473            VIA   -    MD0100PA00X+009300Y+144850X0200Y         S0      
327m3473            R1494 -2          A01X+009008Y+144850X0198Y0197     S1      
327m3473            R8249 -1          A01X+009592Y+144850X0198Y0197     S1      
317m3474            VIA   -    M      A01X+009300Y+144450X0200Y         S2      
017m3474            VIA   -    M      A18X+009300Y+144450X0260Y         S2      
017m3474                  -    MD0100PA00X+009300Y+144450                       
327m3474            R1495 -1          A18X+008158Y+144450X0198Y0197     S2      
327m3474            R8248 -1          A01X+009592Y+144450X0198Y0197     S1      
327m3474            R1321 -2          A01X+009008Y+144450X0198Y0197     S1      
327m3475            VIA   -    M      A01X+068025Y+046771X0300Y         S1      
327m3475            U18   -B13        A01X+070048Y+045769X0160Y    R090 S1      
327m3475            R211  -2          A01X+067558Y+046586X0198Y0197     S1      
327m3476            VIA   -    M      A01X+068345Y+046381X0300Y         S1      
327m3476            U18   -A13        A01X+069733Y+045769X0160Y    R090 S1      
327m3476            R210  -2          A01X+067558Y+046186X0198Y0197     S1      
317m3477            VIA   -    M      A01X+093696Y+094290X0200Y         S2      
017m3477            VIA   -    M      A18X+093696Y+094290X0260Y         S2      
017m3477                  -    MD0100PA00X+093696Y+094290                       
327m3477            U6    -7          A18X+093866Y+093650X0100Y0210R180 S2      
317m3477            VIA   -    MD0100PA00X+092950Y+091650X0200Y         S0      
327m3477            R148  -1          A18X+092950Y+091992X0198Y0197R270 S2      
317m3477            VIA   -    MD0100PA00X+094250Y+091634X0200Y         S0      
327m3477            R144  -1          A18X+094250Y+091992X0198Y0197R270 S2      
317m3477            VIA   -    MD0100PA00X+096092Y+090650X0200Y         S0      
327m3477            R1154 -2          A18X+096150Y+089958X0198Y0197R270 S2      
327m3477            R406  -2   M      A18X+096092Y+090350X0198Y0197     S2      
317m3478            VIA   -    M      A01X+094263Y+094316X0200Y         S2      
017m3478            VIA   -    M      A18X+094263Y+094316X0260Y         S2      
017m3478                  -    MD0100PA00X+094263Y+094316                       
327m3478            R368  -2   M      A18X+095708Y+090350X0198Y0197R180 S2      
327m3478            R1153 -2          A18X+095650Y+089958X0198Y0197R270 S2      
317m3478            VIA   -    MD0100PA00X+095708Y+090650X0200Y         S0      
317m3478            VIA   -    MD0100PA00X+095050Y+091615X0200Y         S0      
327m3478            R145  -1          A18X+095050Y+091992X0198Y0197R270 S2      
327m3478            R358  -1          A18X+093450Y+091992X0198Y0197R270 S2      
317m3478            VIA   -    MD0100PA00X+093450Y+091650X0200Y         S0      
327m3478            U6    -8          A18X+094063Y+093650X0100Y0210R180 S2      
327m3479            U96   -3          A18X+096028Y+088706X0170Y0460     S2      
327m3479            R1154 -1          A18X+096150Y+089642X0198Y0197R270 S2      
327m3479            VIA   -    M      A18X+096150Y+089300X0260Y         S2      
327m3480            U96   -2          A18X+095772Y+088706X0170Y0460     S2      
327m3480            R1153 -1          A18X+095650Y+089642X0198Y0197R270 S2      
327m3480            VIA   -    M      A18X+095650Y+089300X0260Y         S2      
327m3481            R257  -2          A18X+092396Y+083960X0180Y0200R180 S2      
327m3481            R281  -2   M      A18X+092396Y+083960X0180Y0200     S2      
327m3481            R323  -1          A18X+090750Y+095608X0180Y0200R270 S2      
327m3481            R326  -1   M      A18X+090750Y+095608X0180Y0200R090 S2      
317m3481            VIA   -    M      A01X+092778Y+084342X0200Y         S2      
017m3481            VIA   -    M      A18X+092778Y+084342X0260Y         S2      
017m3481                  -    MD0100PA00X+092778Y+084342                       
317m3481            VIA   -    MD0100PA00X+091000Y+095750X0200Y         S0      
327m3482            R256  -2          A18X+092408Y+084719X0180Y0200R180 S2      
327m3482            R274  -2   M      A18X+092408Y+084719X0180Y0200     S2      
327m3482            R324  -1          A18X+091250Y+095608X0180Y0200R270 S2      
327m3482            R325  -1   M      A18X+091250Y+095608X0180Y0200R090 S2      
317m3482            VIA   -    M      A01X+092023Y+084335X0200Y         S2      
017m3482            VIA   -    M      A18X+092023Y+084335X0260Y         S2      
017m3482                  -    MD0100PA00X+092023Y+084335                       
317m3482            VIA   -    MD0100PA00X+091000Y+095450X0200Y         S0      
317m3483            VIA   -    M      A01X+094300Y+086282X0200Y         S2      
017m3483            VIA   -    M      A18X+094300Y+086282X0260Y         S2      
017m3483                  -    MD0100PA00X+094300Y+086282                       
327m3483            R790  -2          A18X+094508Y+089450X0198Y0197R180 S2      
317m3483            VIA   -    MD0100PA00X+094508Y+089150X0200Y         S0      
327m3483            R1152 -1          A18X+094300Y+085858X0198Y0197R090 S2      
327m3483            U5    -6          A18X+094120Y+086979X0170Y0460     S2      
317m3484            VIA   -    M      A01X+093800Y+086262X0200Y         S2      
017m3484            VIA   -    M      A18X+093800Y+086262X0260Y         S2      
017m3484                  -    MD0100PA00X+093800Y+086262                       
327m3484            R789  -2          A18X+093492Y+089450X0198Y0197     S2      
317m3484            VIA   -    MD0100PA00X+093492Y+089142X0200Y         S0      
327m3484            R1151 -1          A18X+093800Y+085858X0198Y0197R090 S2      
327m3484            U5    -7          A18X+093864Y+086979X0170Y0460     S2      
327m3485            U18   -A12        A01X+069733Y+045454X0160Y    R090 S1      
327m3485            VIA   -    M      A01X+068345Y+045593X0300Y         S1      
327m3485            R56   -2          A01X+067558Y+045386X0198Y0197     S1      
327m3486            VIA   -    M      A01X+068025Y+045981X0300Y         S1      
327m3486            U18   -B12        A01X+070048Y+045454X0160Y    R090 S1      
327m3486            R51   -2          A01X+067558Y+045786X0198Y0197     S1      
327m3487            J41   -A41        A01X+059629Y+005354X0150Y0570R180 S1      
327m3487            R2418 -2          A18X+059010Y+005261X0198Y0197R090 S2      
317m3487            VIA   -    M      A01X+059194Y+004631X0200Y         S2      
017m3487            VIA   -    M      A18X+059194Y+004631X0260Y         S2      
017m3487                  -    MD0100PA00X+059194Y+004631                       
327m3488            J41   -A40        A01X+059865Y+005354X0150Y0570R180 S1      
327m3488            R2417 -2          A18X+059440Y+005261X0198Y0197R090 S2      
317m3488            VIA   -    M      A01X+059796Y+004805X0200Y         S2      
017m3488            VIA   -    M      A18X+059796Y+004805X0260Y         S2      
017m3488                  -    MD0100PA00X+059796Y+004805                       
317m3489            VIA   -    M      A01X+061880Y+017553X0200Y         S2      
017m3489            VIA   -    M      A18X+061880Y+017553X0260Y         S2      
017m3489                  -    MD0100PA00X+061880Y+017553                       
327m3489            U98   -8   M      A01X+061280Y+017553X0140Y0590R270 S1      
327m3489            U98   -7          A01X+061280Y+017298X0140Y0590R270 S1      
327m3489            R2476 -1          A01X+062531Y+017553X0198Y0197R090 S1      
327m3489            R1700 -2   M      A01X+062131Y+017553X0198Y0197R270 S1      
327m3490            R2114 -1          A01X+101526Y+028731X0198Y0197     S1      
327m3490            U134  -4          A01X+100517Y+029052X0170Y0240R270 S1      
327m3490            VIA   -    M      A01X+101016Y+028849X0300Y         S1      
327m3491            U279  -5          A01X+084256Y+017633X0240Y0460R270 S1      
327m3491            R3531 -2   M      A01X+083130Y+017636X0198Y0197     S1      
327m3491            VIA   -    M      A01X+083130Y+017163X0300Y    R180 S1      
327m3491            R3529 -2          A01X+083130Y+016686X0198Y0197     S1      
327m3492            R3531 -1          A01X+082814Y+017636X0198Y0197     S1      
317m3492            VIA   -    MD0100PA00X+082264Y+016547X0200Y         S0      
317m3492            VIA   -    M      A01X+102311Y+028731X0200Y         S2      
017m3492            VIA   -    M      A18X+102311Y+028731X0260Y         S2      
017m3492                  -    MD0100PA00X+102311Y+028731                       
327m3492            R2114 -2          A01X+101841Y+028731X0198Y0197     S1      
327m3492            R2125 -2          A01X+102783Y+028731X0198Y0197R180 S1      
327m3493            J41   -A39        A01X+060101Y+005354X0150Y0570R180 S1      
327m3493            R2416 -2          A18X+060235Y+005261X0198Y0197R090 S2      
317m3493            VIA   -    M      A01X+059928Y+004248X0200Y         S2      
017m3493            VIA   -    M      A18X+059928Y+004248X0260Y         S2      
017m3493                  -    MD0100PA00X+059928Y+004248                       
327m3494            J41   -A38        A01X+060337Y+005354X0150Y0570R180 S1      
327m3494            R2415 -2          A18X+060633Y+005261X0198Y0197R090 S2      
317m3494            VIA   -    M      A01X+060306Y+004802X0200Y         S2      
017m3494            VIA   -    M      A18X+060306Y+004802X0260Y         S2      
017m3494                  -    MD0100PA00X+060306Y+004802                       
327m3495            J41   -A32        A01X+061755Y+005354X0150Y0570R180 S1      
327m3495            R2414 -2          A18X+061028Y+005261X0198Y0197R090 S2      
317m3495            VIA   -    M      A01X+061559Y+004561X0200Y         S2      
017m3495            VIA   -    M      A18X+061559Y+004561X0260Y         S2      
017m3495                  -    MD0100PA00X+061559Y+004561                       
327m3496            J41   -A31        A01X+061991Y+005354X0150Y0570R180 S1      
317m3496            VIA   -    M      A01X+061956Y+004919X0200Y         S2      
017m3496            VIA   -    M      A18X+061956Y+004919X0260Y         S2      
017m3496                  -    MD0100PA00X+061956Y+004919                       
327m3496            R2413 -2          A18X+061484Y+005261X0198Y0197R090 S2      
327m3497            J41   -A24        A01X+064987Y+005354X0150Y0570R180 S1      
317m3497            VIA   -    M      A01X+065104Y+004154X0200Y         S2      
017m3497            VIA   -    M      A18X+065104Y+004154X0260Y         S2      
017m3497                  -    MD0100PA00X+065104Y+004154                       
327m3497            R2205 -2          A18X+064315Y+003706X0198Y0197R270 S2      
327m3497            R55   -1   M      A18X+064767Y+003706X0198Y0197R090 S2      
327m3498            J41   -A23        A01X+065223Y+005354X0150Y0570R180 S1      
317m3498            VIA   -    M      A01X+065458Y+004545X0200Y         S2      
017m3498            VIA   -    M      A18X+065458Y+004545X0260Y         S2      
017m3498                  -    MD0100PA00X+065458Y+004545                       
327m3498            R2204 -2          A18X+065629Y+003706X0198Y0197R270 S2      
327m3498            R65   -1   M      A18X+065191Y+003706X0198Y0197R090 S2      
327m3499            J41   -A12        A01X+067822Y+005354X0150Y0570R180 S1      
327m3499            R3858 -2          A18X+067096Y+003332X0198Y0197R270 S2      
317m3499            VIA   -    M      A01X+067465Y+003819X0200Y         S2      
017m3499            VIA   -    M      A18X+067465Y+003819X0260Y         S2      
017m3499                  -    MD0100PA00X+067465Y+003819                       
317m3500            VIA   -    MD0100PA00X+066651Y+003275X0200Y         S0      
327m3500            R3858 -1   M      A18X+067096Y+003017X0198Y0197R270 S2      
327m3500            R3243 -1          A18X+067496Y+003017X0198Y0197R270 S2      
317m3500            VIA   -    M      A01X+056395Y+014864X0200Y         S2      
017m3500            VIA   -    M      A18X+056395Y+014864X0260Y         S2      
017m3500                  -    MD0100PA00X+056395Y+014864                       
327m3500            U235  -3          A01X+057230Y+015208X0170Y0460R090 S1      
327m3501            J41   -A11        A01X+068058Y+005354X0150Y0570R180 S1      
327m3501            R2425 -2          A18X+068584Y+003330X0198Y0197R270 S2      
317m3501            VIA   -    M      A01X+068086Y+003819X0200Y         S2      
017m3501            VIA   -    M      A18X+068086Y+003819X0260Y         S2      
017m3501                  -    MD0100PA00X+068086Y+003819                       
317m3502            VIA   -    MD0100PA00X+069048Y+003268X0200Y         S0      
327m3502            R3242 -1          A18X+068062Y+003017X0198Y0197R270 S2      
327m3502            R2425 -1   M      A18X+068584Y+003014X0198Y0197R270 S2      
317m3502            VIA   -    M      A01X+056395Y+015364X0200Y         S2      
017m3502            VIA   -    M      A18X+056395Y+015364X0260Y         S2      
017m3502                  -    MD0100PA00X+056395Y+015364                       
327m3502            U235  -2          A01X+057230Y+015464X0170Y0460R090 S1      
327m3503            U235  -6          A01X+058942Y+015208X0170Y0460R090 S1      
317m3503            VIA   -    M      A01X+059777Y+014864X0200Y         S2      
017m3503            VIA   -    M      A18X+059777Y+014864X0260Y         S2      
017m3503                  -    MD0100PA00X+059777Y+014864                       
327m3503            R3229 -2          A01X+060019Y+014564X0198Y0197R180 S1      
327m3503            R3520 -2   M      A01X+060019Y+014964X0198Y0197R180 S1      
327m3504            R3228 -2          A01X+060270Y+015764X0198Y0197R180 S1      
327m3504            R3519 -2   M      A01X+060019Y+015364X0198Y0197R180 S1      
327m3504            U235  -7          A01X+058942Y+015464X0170Y0460R090 S1      
317m3504            VIA   -    M      A01X+059777Y+015364X0200Y         S2      
017m3504            VIA   -    M      A18X+059777Y+015364X0260Y         S2      
017m3504                  -    MD0100PA00X+059777Y+015364                       
317m3505            VIA   -    M      A01X+025111Y+001262X0200Y    R090 S2      
017m3505            VIA   -    M      A18X+025111Y+001262X0260Y    R090 S2      
017m3505                  -    MD0100PA00X+025111Y+001262                       
327m3505            J35   -A8         A01X+024278Y+003276X0150Y0570R180 S1      
317m3505            VIA   -    MD0100PA00X+024651Y+002036X0200Y         S0      
317m3505            VIA   -    MD0100PA00X+060585Y+014564X0200Y    R090 S0      
327m3505            R3229 -1          A01X+060334Y+014564X0198Y0197R180 S1      
327m3506            J35   -A7         A01X+024515Y+003276X0150Y0570R180 S1      
317m3506            VIA   -    M      A01X+024636Y+002686X0200Y         S2      
017m3506            VIA   -    M      A18X+024636Y+002686X0260Y         S2      
017m3506                  -    MD0100PA00X+024636Y+002686                       
317m3506            VIA   -    MD0100PA00X+025511Y+001662X0200Y         S0      
317m3506            VIA   -    MD0100PA00X+060585Y+015513X0200Y         S0      
327m3506            R3228 -1          A01X+060585Y+015764X0198Y0197R180 S1      
327m3507            J41   -A2         A01X+070184Y+005354X0150Y0570R180 S1      
327m3507            R3239 -2          A18X+072001Y+007865X0198Y0197R090 S2      
317m3507            VIA   -    M      A01X+071942Y+007404X0200Y         S2      
017m3507            VIA   -    M      A18X+071942Y+007404X0260Y         S2      
017m3507                  -    MD0100PA00X+071942Y+007404                       
317m3508            VIA   -    M      A01X+072002Y+008695X0200Y         S2      
017m3508            VIA   -    M      A18X+072002Y+008695X0260Y         S2      
017m3508                  -    MD0100PA00X+072002Y+008695                       
327m3508            R3241 -1          A18X+071867Y+009156X0198Y0197R270 S2      
327m3508            R3239 -1          A18X+072001Y+008180X0198Y0197R090 S2      
317m3508            VIA   -    MD0100PA00X+106623Y+016508X0200Y         S0      
327m3508            U236  -3          A01X+159454Y+029818X0170Y0460R090 S1      
327m3509            J41   -A1         A01X+070420Y+005354X0150Y0570R180 S1      
327m3509            R3238 -2          A18X+072400Y+007865X0198Y0197R090 S2      
317m3509            VIA   -    M      A01X+071942Y+006874X0200Y         S2      
017m3509            VIA   -    M      A18X+071942Y+006874X0260Y         S2      
017m3509                  -    MD0100PA00X+071942Y+006874                       
317m3510            VIA   -    M      A01X+072502Y+008695X0200Y         S2      
017m3510            VIA   -    M      A18X+072502Y+008695X0260Y         S2      
017m3510                  -    MD0100PA00X+072502Y+008695                       
327m3510            R3240 -1          A18X+072267Y+009156X0198Y0197R270 S2      
327m3510            R3238 -1          A18X+072400Y+008180X0198Y0197R090 S2      
317m3510            VIA   -    MD0100PA00X+106623Y+016758X0200Y         S0      
327m3510            U236  -2          A01X+159454Y+030074X0170Y0460R090 S1      
317m3511            VIA   -    M      A01X+161991Y+029374X0200Y         S2      
017m3511            VIA   -    M      A18X+161991Y+029374X0260Y         S2      
017m3511                  -    MD0100PA00X+161991Y+029374                       
327m3511            U236  -6          A01X+161166Y+029818X0170Y0460R090 S1      
327m3511            R3501 -2   M      A01X+162233Y+029474X0198Y0197R180 S1      
327m3511            R48   -2          A01X+162233Y+029074X0198Y0197R180 S1      
327m3512            R47   -2          A01X+162233Y+030274X0198Y0197R180 S1      
317m3512            VIA   -    M      A01X+161991Y+029874X0200Y         S2      
017m3512            VIA   -    M      A18X+161991Y+029874X0260Y         S2      
017m3512                  -    MD0100PA00X+161991Y+029874                       
327m3512            U236  -7          A01X+161166Y+030074X0170Y0460R090 S1      
327m3512            R3500 -2   M      A01X+162233Y+029874X0198Y0197R180 S1      
317m3513            VIA   -    M      A01X+171706Y+002591X0200Y         S2      
017m3513            VIA   -    M      A18X+171706Y+002591X0260Y         S2      
017m3513                  -    MD0100PA00X+171706Y+002591                       
327m3513            J38   -A8         A01X+171719Y+003276X0150Y0570R180 S1      
327m3513            R48   -1          A01X+162548Y+029074X0198Y0197R180 S1      
317m3513            VIA   -    MD0100PA00X+162791Y+029074X0200Y    R090 S0      
317m3514            VIA   -    M      A01X+172208Y+002591X0200Y         S2      
017m3514            VIA   -    M      A18X+172208Y+002591X0260Y         S2      
017m3514                  -    MD0100PA00X+172208Y+002591                       
327m3514            J38   -A7         A01X+171956Y+003276X0150Y0570R180 S1      
327m3514            R47   -1          A01X+162548Y+030274X0198Y0197R180 S1      
317m3514            VIA   -    MD0100PA00X+162791Y+030274X0200Y    R090 S0      
327m3515            R2410 -1          A01X+057758Y+016436X0198Y0197R180 S1      
327m3515            R1702 -2   M      A01X+058678Y+016436X0198Y0197     S1      
327m3515            U98   -4          A01X+059520Y+016786X0140Y0590R270 S1      
317m3515            VIA   -    M      A01X+058920Y+016436X0200Y         S2      
017m3515            VIA   -    M      A18X+058920Y+016436X0260Y         S2      
017m3515                  -    MD0100PA00X+058920Y+016436                       
317m3516            VIA   -    MD0100PA00X+065370Y+017996X0200Y         S0      
327m3516            J59   -42         A01X+066755Y+018130X0110Y0630R270 S1      
327m3516            R2410 -2          A01X+057443Y+016436X0198Y0197R180 S1      
317m3516            VIA   -    M      A01X+057200Y+016436X0200Y         S2      
017m3516            VIA   -    M      A18X+057200Y+016436X0260Y         S2      
017m3516                  -    MD0100PA00X+057200Y+016436                       
327m3517            R2411 -1          A01X+057758Y+016942X0198Y0197R180 S1      
327m3517            R1703 -2   M      A01X+058678Y+016942X0198Y0197     S1      
317m3517            VIA   -    M      A01X+058920Y+016942X0200Y    R180 S2      
017m3517            VIA   -    M      A18X+058920Y+016942X0260Y    R180 S2      
017m3517                  -    MD0100PA00X+058920Y+016942                       
327m3517            U98   -3          A01X+059520Y+017042X0140Y0590R270 S1      
327m3518            J59   -40         A01X+066755Y+018327X0110Y0630R270 S1      
317m3518            VIA   -    M      A01X+064987Y+018194X0200Y         S2      
017m3518            VIA   -    M      A18X+064987Y+018194X0260Y         S2      
017m3518                  -    MD0100PA00X+064987Y+018194                       
327m3518            R2411 -2          A01X+057443Y+016942X0198Y0197R180 S1      
317m3518            VIA   -    MD0100PA00X+057200Y+016942X0200Y         S0      
327m3519            U247  -9          A01X+005235Y+052033X0100Y0220     S1      
327m3519            VIA   -    M      A01X+005366Y+051264X0300Y    R180 S1      
327m3519            R3341 -2          A01X+005290Y+050766X0198Y0197R090 S1      
327m3520            U247  -8          A01X+005038Y+052033X0100Y0220     S1      
327m3520            R3340 -2          A01X+004850Y+050785X0198Y0197R090 S1      
327m3520            VIA   -    M      A01X+004790Y+051258X0300Y    R180 S1      
327m3521            J41   -A4         A01X+069711Y+005354X0150Y0570R180 S1      
327m3521            R2420 -2          A18X+071204Y+007865X0198Y0197R090 S2      
317m3521            VIA   -    M      A01X+071272Y+006854X0200Y         S2      
017m3521            VIA   -    M      A18X+071272Y+006854X0260Y         S2      
017m3521                  -    MD0100PA00X+071272Y+006854                       
327m3522            J41   -A3         A01X+069948Y+005354X0150Y0570R180 S1      
327m3522            R2419 -2          A18X+071603Y+007865X0198Y0197R090 S2      
317m3522            VIA   -    M      A01X+071410Y+007369X0200Y         S2      
017m3522            VIA   -    M      A18X+071410Y+007369X0260Y         S2      
017m3522                  -    MD0100PA00X+071410Y+007369                       
327m3523            J41   -A30        A01X+062227Y+005354X0150Y0570R180 S1      
327m3523            R3114 -1          A18X+062201Y+006917X0198Y0197R270 S2      
327m3523            R331  -1   M      A18X+062221Y+006517X0198Y0197R180 S2      
317m3523            VIA   -    M      A01X+062221Y+006057X0200Y         S2      
017m3523            VIA   -    M      A18X+062221Y+006057X0260Y         S2      
017m3523                  -    MD0100PA00X+062221Y+006057                       
327m3524            J41   -A29        A01X+062463Y+005354X0150Y0570R180 S1      
317m3524            VIA   -    M      A01X+062463Y+004810X0200Y         S2      
017m3524            VIA   -    M      A18X+062463Y+004810X0260Y         S2      
017m3524                  -    MD0100PA00X+062463Y+004810                       
327m3524            R3113 -1   M      A18X+062402Y+005168X0198Y0197R180 S2      
327m3524            R330  -1          A18X+061897Y+005568X0198Y0197R180 S2      
327m3525            U279  -3          A01X+085969Y+017348X0170Y0460R270 S1      
327m3525            R3534 -1          A01X+087914Y+017686X0198Y0197     S1      
327m3525            VIA   -    M      A01X+086645Y+017386X0300Y    R180 S1      
327m3525            R3532 -2   M      A01X+087114Y+017686X0198Y0197R180 S1      
327m3526            R3534 -2          A01X+088230Y+017686X0198Y0197     S1      
317m3526            VIA   -    MD0100PA00X+088752Y+017686X0200Y         S0      
317m3526            VIA   -    M      A01X+091739Y+018411X0200Y         S2      
017m3526            VIA   -    M      A18X+091739Y+018411X0260Y         S2      
017m3526                  -    MD0100PA00X+091739Y+018411                       
327m3526            J90   -A8         A01X+091339Y+018411X0150Y0500R090 S1      
327m3527            U279  -2          A01X+085969Y+017092X0170Y0460R270 S1      
327m3527            VIA   -    M      A01X+086645Y+016886X0300Y    R180 S1      
327m3527            R3530 -2   M      A01X+087114Y+017136X0198Y0197R180 S1      
327m3527            R3533 -1          A01X+087914Y+017136X0198Y0197     S1      
327m3528            J90   -A7         A01X+091339Y+018175X0150Y0500R090 S1      
317m3528            VIA   -    MD0100PA00X+088752Y+017136X0200Y         S0      
317m3528            VIA   -    M      A01X+092213Y+018249X0200Y         S2      
017m3528            VIA   -    M      A18X+092213Y+018249X0260Y         S2      
017m3528                  -    MD0100PA00X+092213Y+018249                       
327m3528            R3533 -2          A01X+088230Y+017136X0198Y0197     S1      
327m3529            PU34  -13         A01X+010868Y+144216X0070Y0260R270 S1      
327m3529            R8249 -2          A01X+009908Y+144850X0198Y0197     S1      
327m3530            VIA   -    M      A01X+120466Y+144750X0300Y         S1      
327m3530            R8072 -2          A01X+120008Y+144750X0198Y0197     S1      
327m3530            PU12  -13         A01X+120968Y+142866X0070Y0260R270 S1      
327SMB_CPU_5_SDA    R213  -2          A01X+155025Y+128219X0198Y0197     S1      
317SMB_CPU_5_SDA    VIA   -    MD0100PA00X+155355Y+128499X0200Y         S0      
327SMB_CPU_5_SDA    R633  -2          A18X+076052Y+055131X0198Y0197R090 S2      
327SMB_CPU_5_SDA    R1453 -1          A01X+076050Y+054344X0198Y0197R270 S1      
317SMB_CPU_5_SDA    VIA   -    MD0100PA00X+075957Y+054587X0200Y         S0      
317SMB_CPU_5_SDA    VIA   -    M      A01X+138146Y+051105X0200Y         S2      
017SMB_CPU_5_SDA    VIA   -    M      A18X+138146Y+051105X0260Y         S2      
017SMB_CPU_5_SDA          -    MD0100PA00X+138146Y+051105                       
327SMB_CPU_5_SCL    R212  -2          A01X+155025Y+128619X0198Y0197     S1      
317SMB_CPU_5_SCL    VIA   -    MD0100PA00X+155323Y+128881X0200Y         S0      
327SMB_CPU_5_SCL    R632  -2          A18X+074848Y+055144X0198Y0197R090 S2      
327SMB_CPU_5_SCL    R1447 -1          A01X+074850Y+054344X0198Y0197R270 S1      
317SMB_CPU_5_SCL    VIA   -    MD0100PA00X+074850Y+054586X0200Y         S0      
317SMB_CPU_5_SCL    VIA   -    M      A01X+137386Y+051105X0200Y         S2      
017SMB_CPU_5_SCL    VIA   -    M      A18X+137386Y+051105X0260Y         S2      
017SMB_CPU_5_SCL          -    MD0100PA00X+137386Y+051105                       
327m3531            U25   -DJ20       A01X+148216Y+116413X0177Y    R180 S1      
327m3531            VIA   -    M      A01X+153234Y+126572X0300Y    R180 S1      
327m3531            R213  -1          A01X+154710Y+128219X0198Y0197     S1      
327m3532            U25   -DJ21       A01X+147846Y+116413X0177Y    R180 S1      
327m3532            VIA   -    M      A01X+153730Y+127468X0300Y    R180 S1      
327m3532            R212  -1          A01X+154710Y+128619X0198Y0197     S1      
327m3533            R1453 -2          A01X+076050Y+054029X0198Y0197R270 S1      
327m3533            U18   -M19        A01X+073198Y+047659X0160Y    R090 S1      
317m3533            VIA   -    MD0100PA00X+073351Y+047812X0180Y    R090 S0      
317m3533            VIA   -    M      A01X+076066Y+053786X0200Y         S2      
017m3533            VIA   -    M      A18X+076066Y+053786X0260Y         S2      
017m3533                  -    MD0100PA00X+076066Y+053786                       
327m3534            R1447 -2          A01X+074850Y+054029X0198Y0197R270 S1      
317m3534            VIA   -    M      A01X+074800Y+053786X0200Y         S2      
017m3534            VIA   -    M      A18X+074800Y+053786X0260Y         S2      
017m3534                  -    MD0100PA00X+074800Y+053786                       
327m3534            U18   -M20        A01X+073198Y+047974X0160Y    R090 S1      
317m3534            VIA   -    MD0100PA00X+073351Y+048127X0180Y    R090 S0      
317m3535            VIA   -    MD0080PA00X+053073Y+088281X0160Y    R180 S0      
327m3535            R369  -2          A18X+092550Y+091358X0198Y0197R270 S2      
327m3535            R1162 -2          A18X+092550Y+091992X0198Y0197R090 S2      
317m3535            VIA   -    MD0100PA00X+092550Y+091650X0200Y         S0      
327m3535            U26   -D14        A01X+052889Y+088386X0177Y    R180 S1      
317m3535            VIA   -    M      A01X+083158Y+090515X0200Y         S2      
017m3535            VIA   -    M      A18X+083158Y+090515X0260Y         S2      
017m3535                  -    MD0100PA00X+083158Y+090515                       
317m3536            VIA   -    MD0080PA00X+053073Y+087644X0160Y    R180 S0      
327m3536            R366  -2          A18X+093850Y+091358X0198Y0197R270 S2      
327m3536            R1161 -2          A18X+093850Y+091992X0198Y0197R090 S2      
317m3536            VIA   -    MD0100PA00X+093850Y+091650X0200Y         S0      
327m3536            U26   -B14        A01X+052889Y+087748X0177Y    R180 S1      
317m3536            VIA   -    M      A01X+083150Y+089729X0200Y         S2      
017m3536            VIA   -    M      A18X+083150Y+089729X0260Y         S2      
017m3536                  -    MD0100PA00X+083150Y+089729                       
327m3537            U6    -4          A18X+093669Y+093146X0120Y0210R180 S2      
327m3537            R1162 -1          A18X+092550Y+092308X0198Y0197R090 S2      
327m3537            R148  -2   M      A18X+092950Y+092308X0198Y0197R270 S2      
327m3537            VIA   -    M      A18X+092950Y+092650X0260Y         S2      
327m3538            U6    -3          A18X+093866Y+093146X0100Y0210R180 S2      
327m3538            VIA   -    M      A18X+093450Y+092650X0260Y         S2      
327m3538            R1161 -1          A18X+093850Y+092308X0198Y0197R090 S2      
327m3538            R358  -2   M      A18X+093450Y+092308X0198Y0197R270 S2      
317m3539            VIA   -    MD0080PA00X+150687Y+088281X0160Y    R180 S0      
317m3539            VIA   -    M      A01X+095147Y+081640X0200Y         S2      
017m3539            VIA   -    M      A18X+095147Y+081640X0260Y         S2      
017m3539                  -    MD0100PA00X+095147Y+081640                       
317m3539            VIA   -    MD0100PA00X+094650Y+091599X0200Y         S0      
327m3539            R1160 -2          A18X+094650Y+091992X0198Y0197R090 S2      
327m3539            R370  -2          A18X+094650Y+091358X0198Y0197R270 S2      
327m3539            U25   -D14        A01X+150503Y+088386X0177Y    R180 S1      
317m3539            VIA   -    MD0100PA00X+093434Y+066853X0200Y         S0      
317m3540            VIA   -    MD0080PA00X+150687Y+087643X0160Y    R180 S0      
317m3540            VIA   -    M      A01X+094864Y+081119X0200Y         S2      
017m3540            VIA   -    M      A18X+094864Y+081119X0260Y         S2      
017m3540                  -    MD0100PA00X+094864Y+081119                       
317m3540            VIA   -    MD0100PA00X+095450Y+091599X0200Y         S0      
327m3540            R1159 -2          A18X+095450Y+091992X0198Y0197R090 S2      
327m3540            R367  -2          A18X+095450Y+091358X0198Y0197R270 S2      
327m3540            U25   -B14        A01X+150503Y+087748X0177Y    R180 S1      
317m3540            VIA   -    MD0100PA00X+093454Y+066465X0200Y         S0      
327m3541            R1158 -1          A18X+092350Y+094492X0180Y0200R090 S2      
317m3541            VIA   -    M      A01X+092350Y+094150X0200Y         S2      
017m3541            VIA   -    M      A18X+092350Y+094150X0260Y         S2      
017m3541                  -    MD0100PA00X+092350Y+094150                       
327m3541            U213  -8          A18X+090704Y+092401X0100Y0220R180 S2      
327m3541            R147  -2          A18X+090100Y+091558X0198Y0197R270 S2      
317m3541            VIA   -    MD0100PA00X+090500Y+091850X0200Y         S0      
327m3541            R5004 -1   M      A18X+090500Y+091558X0198Y0197R090 S2      
327m3542            R1157 -1          A18X+092850Y+094492X0180Y0200R090 S2      
317m3542            VIA   -    M      A01X+092850Y+094150X0200Y         S2      
017m3542            VIA   -    M      A18X+092850Y+094150X0260Y         S2      
017m3542                  -    MD0100PA00X+092850Y+094150                       
317m3542            VIA   -    MD0100PA00X+091700Y+091850X0200Y         S0      
327m3542            U213  -6          A18X+091098Y+092401X0100Y0220R180 S2      
327m3542            R146  -2          A18X+091700Y+091558X0198Y0197R270 S2      
327m3543            R493  -2          A01X+069500Y+058066X0198Y0197R090 S1      
327m3543            R590  -2   M      A01X+069900Y+058066X0198Y0197R090 S1      
317m3543            VIA   -    M      A01X+069900Y+058308X0200Y         S2      
017m3543            VIA   -    M      A18X+069900Y+058308X0260Y         S2      
017m3543                  -    MD0100PA00X+069900Y+058308                       
327m3543            U27   -6          A01X+070025Y+058893X0170Y0460     S1      
327m3544            R70   -2          A01X+070806Y+058066X0198Y0197R090 S1      
317m3544            VIA   -    M      A01X+070406Y+058308X0200Y         S2      
017m3544            VIA   -    M      A18X+070406Y+058308X0260Y         S2      
017m3544                  -    MD0100PA00X+070406Y+058308                       
327m3544            U27   -7          A01X+070281Y+058893X0170Y0460     S1      
327m3544            R499  -2   M      A01X+070406Y+058066X0198Y0197R090 S1      
327m3545            U18   -F11        A01X+071308Y+045139X0160Y    R090 S1      
317m3545            VIA   -    MD0100PA00X+071154Y+044985X0180Y    R090 S0      
317m3545            VIA   -    M      A01X+069500Y+057508X0200Y         S2      
017m3545            VIA   -    M      A18X+069500Y+057508X0260Y         S2      
017m3545                  -    MD0100PA00X+069500Y+057508                       
327m3545            R493  -1          A01X+069500Y+057751X0198Y0197R090 S1      
327m3546            U18   -G11        A01X+071623Y+045139X0160Y    R090 S1      
317m3546            VIA   -    MD0100PA00X+071469Y+044985X0180Y    R090 S0      
317m3546            VIA   -    M      A01X+070806Y+057508X0200Y         S2      
017m3546            VIA   -    M      A18X+070806Y+057508X0260Y         S2      
017m3546                  -    MD0100PA00X+070806Y+057508                       
327m3546            R70   -1          A01X+070806Y+057751X0198Y0197R090 S1      
327SMB_CPU0_4_SDA   R431  -2          A18X+159483Y+126043X0198Y0197R270 S2      
317SMB_CPU0_4_SDA   VIA   -    MD0100PA00X+159340Y+127146X0200Y    R180 S0      
317SMB_CPU0_4_SDA   VIA   -    MD0100PA00X+086557Y+080854X0200Y         S0      
317SMB_CPU0_4_SDA   VIA   -    M      A01X+069693Y+061321X0200Y         S2      
017SMB_CPU0_4_SDA   VIA   -    M      A18X+069693Y+061321X0260Y         S2      
017SMB_CPU0_4_SDA         -    MD0100PA00X+069693Y+061321                       
327SMB_CPU0_4_SDA   U27   -3          A01X+070025Y+060606X0170Y0460     S1      
327SMB_CPU0_4_SDA   R498  -2   M      A01X+069864Y+061854X0198Y0197R270 S1      
327SMB_CPU0_4_SCL   R430  -2          A18X+159083Y+126043X0198Y0197R270 S2      
317SMB_CPU0_4_SCL   VIA   -    MD0100PA00X+159083Y+127138X0200Y    R180 S0      
317SMB_CPU0_4_SCL   VIA   -    MD0100PA00X+086557Y+080604X0200Y         S0      
317SMB_CPU0_4_SCL   VIA   -    M      A01X+070281Y+061326X0200Y         S2      
017SMB_CPU0_4_SCL   VIA   -    M      A18X+070281Y+061326X0260Y         S2      
017SMB_CPU0_4_SCL         -    MD0100PA00X+070281Y+061326                       
327SMB_CPU0_4_SCL   U27   -2          A01X+070281Y+060606X0170Y0460     S1      
327SMB_CPU0_4_SCL   R495  -2   M      A01X+070264Y+061854X0198Y0197R270 S1      
317m3547            VIA   -    MD0080PA00X+151545Y+116199X0160Y         S0      
327m3547            U25   -DH12       A01X+151361Y+116094X0177Y    R180 S1      
327m3547            VIA   -    M      A18X+159583Y+125268X0260Y         S2      
327m3547            R431  -1          A18X+159483Y+125728X0198Y0197R270 S2      
317m3548            VIA   -    MD0080PA00X+151360Y+115880X0160Y         S0      
327m3548            U25   -DG12       A01X+151176Y+115776X0177Y    R180 S1      
327m3548            VIA   -    M      A18X+159324Y+124418X0260Y         S2      
327m3548            R430  -1          A18X+159083Y+125728X0198Y0197R270 S2      
327SMB_CPU0_3_SDA   VIA   -    M      A18X+153585Y+080114X0260Y    R180 S2      
327SMB_CPU0_3_SDA   R6084 -2          A18X+154030Y+080118X0198Y0197     S2      
327SMB_CPU0_3_SDA   R30   -2          A18X+153125Y+080149X0198Y0197R180 S2      
327SMB_CPU0_3_SCL   VIA   -    M      A18X+153585Y+079614X0260Y    R180 S2      
327SMB_CPU0_3_SCL   R29   -2          A18X+153125Y+079769X0198Y0197R180 S2      
327SMB_CPU0_3_SCL   R6083 -2          A18X+154030Y+079718X0198Y0197     S2      
327m3549            U25   -B4         A01X+154204Y+087748X0177Y    R180 S1      
317m3549            VIA   -    MD0100PA00X+151743Y+081147X0200Y    R180 S0      
327m3549            VIA   -    M      A18X+152318Y+080099X0260Y    R180 S2      
327m3549            R30   -1          A18X+152810Y+080149X0198Y0197R180 S2      
327m3550            U25   -A4         A01X+154019Y+087429X0177Y    R180 S1      
327m3550            VIA   -    M      A18X+151868Y+079819X0260Y    R180 S2      
327m3550            R29   -1          A18X+152810Y+079769X0198Y0197R180 S2      
317m3550            VIA   -    MD0100PA00X+151254Y+081292X0200Y    R180 S0      
327SMB_CPU0_2_SDA   VIA   -    M      A18X+123518Y+078881X0260Y         S2      
327SMB_CPU0_2_SDA   R6082 -2          A18X+122593Y+078046X0198Y0197R270 S2      
327SMB_CPU0_2_SDA   R28   -2          A18X+123518Y+079341X0198Y0197R090 S2      
327SMB_CPU0_2_SCL   VIA   -    M      A18X+122993Y+078506X0260Y    R180 S2      
327SMB_CPU0_2_SCL   R27   -2          A18X+124018Y+079341X0198Y0197R090 S2      
327SMB_CPU0_2_SCL   R6081 -2          A18X+122993Y+078046X0198Y0197R270 S2      
317m3551            VIA   -    MD0080PA00X+128855Y+087643X0160Y    R180 S0      
327m3551            U25   -B72        A01X+129039Y+087748X0177Y    R180 S1      
327m3551            VIA   -    M      A18X+123518Y+080116X0260Y    R180 S2      
327m3551            R28   -1          A18X+123518Y+079656X0198Y0197R090 S2      
317m3552            VIA   -    MD0080PA00X+129040Y+087962X0160Y    R180 S0      
327m3552            U25   -C72        A01X+129224Y+088067X0177Y    R180 S1      
327m3552            VIA   -    M      A18X+124018Y+080116X0260Y    R180 S2      
327m3552            R27   -1          A18X+124018Y+079656X0198Y0197R090 S2      
327m3553            VIA   -    M      A01X+010216Y+144450X0160Y0041R180 S1      
327m3553            PU34  -14         A01X+010868Y+144059X0070Y0260R270 S1      
327m3553            R8248 -2          A01X+009908Y+144450X0198Y0197     S1      
327m3554            VIA   -    M      A01X+120449Y+144250X0300Y         S1      
327m3554            R8071 -2          A01X+120008Y+144250X0198Y0197     S1      
327m3554            PU12  -14         A01X+120968Y+142709X0070Y0260R270 S1      
317m3555            VIA   -    M      A01X+066770Y+170504X0200Y         S2      
017m3555            VIA   -    M      A18X+066770Y+170504X0260Y         S2      
017m3555                  -    MD0100PA00X+066770Y+170504                       
327m3555            R2672 -2          A01X+066558Y+170818X0198Y0197     S1      
317m3555            J109  -A7   D0142PA00X+060925Y+173421X0302Y    R180 S3      
317m3556            VIA   -    M      A01X+065984Y+169840X0300Y         S1      
017m3556            VIA   -    M      A18X+065984Y+169840X0200Y         S1      
017m3556                  -    MD0100PA00X+065984Y+169840                       
327m3556            R2671 -2          A01X+065638Y+169840X0198Y0197     S1      
317m3556            J109  -A5   D0142PA00X+059350Y+173421X0302Y    R180 S3      
327m3557            R1158 -2          A18X+092350Y+094808X0180Y0200R090 S2      
327m3557            R338  -2   M      A18X+092350Y+094808X0180Y0200R270 S2      
317m3557            VIA   -    M      A01X+088752Y+144462X0200Y         S2      
017m3557            VIA   -    M      A18X+088752Y+144462X0260Y         S2      
017m3557                  -    MD0100PA00X+088752Y+144462                       
317m3557            VIA   -    MD0100PA00X+037922Y+121953X0200Y         S0      
327m3557            U26   -DH71       A01X+031913Y+116095X0177Y    R180 S1      
327m3557            R359  -2          A18X+091950Y+094808X0198Y0197R270 S2      
317m3557            VIA   -    MD0100PA00X+092600Y+094650X0200Y         S0      
327m3558            R1157 -2          A18X+092850Y+094808X0180Y0200R090 S2      
327m3558            R337  -2   M      A18X+092850Y+094808X0180Y0200R270 S2      
317m3558            VIA   -    M      A01X+088199Y+144961X0200Y         S2      
017m3558            VIA   -    M      A18X+088199Y+144961X0260Y         S2      
017m3558                  -    MD0100PA00X+088199Y+144961                       
327m3558            R362  -2          A18X+093250Y+094808X0198Y0197R270 S2      
317m3558            VIA   -    MD0100PA00X+092600Y+094950X0200Y         S0      
317m3558            VIA   -    MD0100PA00X+038072Y+122191X0200Y         S0      
327m3558            U26   -DJ71       A01X+032098Y+116414X0177Y    R180 S1      
327m3559            VIA   -    M      A18X+095050Y+092650X0260Y         S2      
327m3559            R145  -2   M      A18X+095050Y+092308X0198Y0197R270 S2      
327m3559            R1159 -1          A18X+095450Y+092308X0198Y0197R090 S2      
327m3559            U6    -1          A18X+094260Y+093146X0120Y0210R180 S2      
327m3560            R1155 -2          A18X+093392Y+097750X0180Y0200R180 S2      
327m3560            R328  -2   M      A18X+093392Y+097750X0180Y0200     S2      
327m3560            VIA   -    M      A18X+094721Y+097932X0260Y         S2      
327m3560            R360  -2          A18X+093392Y+097350X0198Y0197     S2      
317m3560            VIA   -    MD0100PA00X+132317Y+120900X0200Y         S0      
327m3560            U25   -DH71       A01X+129527Y+116094X0177Y    R180 S1      
327m3561            R1156 -2          A18X+093392Y+098250X0180Y0200R180 S2      
327m3561            R327  -2   M      A18X+093392Y+098250X0180Y0200     S2      
327m3561            VIA   -    M      A18X+095586Y+098382X0260Y         S2      
327m3561            R363  -2          A18X+093392Y+098650X0198Y0197     S2      
317m3561            VIA   -    MD0100PA00X+132514Y+121065X0200Y         S0      
327m3561            U25   -DJ71       A01X+129712Y+116413X0177Y    R180 S1      
327m3562            R1155 -1          A18X+093708Y+097750X0180Y0200R180 S2      
317m3562            VIA   -    M      A01X+090392Y+094850X0200Y         S2      
017m3562            VIA   -    M      A18X+090392Y+094850X0260Y         S2      
017m3562                  -    MD0100PA00X+090392Y+094850                       
327m3562            R143  -2   M      A18X+090392Y+094500X0198Y0197     S2      
327m3562            U213  -1          A18X+090704Y+093484X0100Y0220R180 S2      
317m3562            VIA   -    MD0100PA00X+094000Y+097750X0200Y         S0      
327m3563            R1156 -1          A18X+093708Y+098250X0180Y0200R180 S2      
317m3563            VIA   -    M      A01X+091558Y+094850X0200Y         S2      
017m3563            VIA   -    M      A18X+091558Y+094850X0260Y         S2      
017m3563                  -    MD0100PA00X+091558Y+094850                       
317m3563            VIA   -    MD0100PA00X+094000Y+098250X0200Y         S0      
327m3563            U213  -4          A18X+091295Y+093484X0100Y0220R180 S2      
327m3563            R142  -2   M      A18X+091558Y+094500X0198Y0197R180 S2      
317m3564            VIA   -    M      A01X+062788Y+005712X0200Y         S2      
017m3564            VIA   -    M      A18X+062788Y+005712X0260Y         S2      
017m3564                  -    MD0100PA00X+062788Y+005712                       
327m3564            R4152 -2          A18X+063107Y+006604X0198Y0197     S2      
317m3564            VIA   -    MD0100PA00X+066200Y+046586X0200Y    R270 S0      
327m3564            R211  -1          A01X+067242Y+046586X0198Y0197     S1      
327m3565            R4151 -2          A18X+064122Y+006604X0198Y0197R180 S2      
317m3565            VIA   -    M      A01X+064065Y+005827X0200Y         S2      
017m3565            VIA   -    M      A18X+064065Y+005827X0260Y         S2      
017m3565                  -    MD0100PA00X+064065Y+005827                       
317m3565            VIA   -    MD0100PA00X+066600Y+046186X0200Y    R270 S0      
327m3565            R210  -1          A01X+067242Y+046186X0198Y0197     S1      
317m3566            VIA   -    MD0100PA00X+016327Y+144159X0200Y         S0      
317m3566            VIA   -    MD0100PA00X+086337Y+083072X0200Y         S0      
317m3566            VIA   -    MD0100PA00X+073446Y+034671X0200Y         S0      
327m3566            R2414 -1          A18X+061028Y+005576X0198Y0197R090 S2      
327m3566            R3004 -1          A18X+061032Y+006477X0198Y0197R270 S2      
317m3566            VIA   -    MD0100PA00X+061158Y+006028X0200Y         S0      
317m3566            VIA   -    M      A01X+008200Y+172433X0200Y         S2      
017m3566            VIA   -    M      A18X+008200Y+172433X0260Y         S2      
017m3566                  -    MD0100PA00X+008200Y+172433                       
327m3566            R3108 -1          A01X+008518Y+172433X0198Y0197     S1      
317m3567            VIA   -    MD0100PA00X+086337Y+083347X0200Y         S0      
317m3567            VIA   -    MD0100PA00X+016121Y+144354X0200Y         S0      
327m3567            R2413 -1          A18X+061484Y+005576X0198Y0197R090 S2      
317m3567            VIA   -    MD0100PA00X+061682Y+006028X0200Y         S0      
327m3567            R2999 -1          A18X+061682Y+006477X0198Y0197R270 S2      
317m3567            VIA   -    MD0100PA00X+073877Y+034672X0200Y         S0      
317m3567            VIA   -    M      A01X+014648Y+172564X0200Y         S2      
017m3567            VIA   -    M      A18X+014648Y+172564X0260Y         S2      
017m3567                  -    MD0100PA00X+014648Y+172564                       
327m3567            R3107 -1          A01X+014284Y+172624X0198Y0197R180 S1      
317m3568            J112  -S3   D0142PA00X+024665Y+164917X0302Y    R180 S3      
317m3568            VIA   -    M      A01X+008200Y+171633X0200Y         S2      
017m3568            VIA   -    M      A18X+008200Y+171633X0260Y         S2      
017m3568                  -    MD0100PA00X+008200Y+171633                       
327m3568            R2991 -2          A01X+008518Y+171633X0198Y0197R180 S1      
317m3569            J112  -R3   D0142PA00X+024665Y+165390X0302Y    R180 S3      
317m3569            VIA   -    M      A01X+014600Y+171824X0200Y         S2      
017m3569            VIA   -    M      A18X+014600Y+171824X0260Y         S2      
017m3569                  -    MD0100PA00X+014600Y+171824                       
327m3569            R2990 -2          A01X+014284Y+171824X0198Y0197     S1      
327m3570            J41   -A28        A01X+064042Y+005354X0150Y0570R180 S1      
327m3570            R4509 -2          A18X+063422Y+005889X0198Y0197R090 S2      
317m3570            VIA   -    M      A01X+063988Y+004919X0200Y         S2      
017m3570            VIA   -    M      A18X+063988Y+004919X0260Y         S2      
017m3570                  -    MD0100PA00X+063988Y+004919                       
317m3571            VIA   -    M      A01X+062664Y+007136X0200Y         S2      
017m3571            VIA   -    M      A18X+062664Y+007136X0260Y         S2      
017m3571                  -    MD0100PA00X+062664Y+007136                       
327m3571            R4150 -2          A18X+063107Y+007004X0198Y0197     S2      
327m3571            R56   -1          A01X+067242Y+045386X0198Y0197     S1      
317m3571            VIA   -    MD0100PA00X+067000Y+045384X0200Y    R270 S0      
327m3572            R4509 -1          A18X+063422Y+006204X0198Y0197R090 S2      
327m3572            R4150 -1   M      A18X+063422Y+007004X0198Y0197     S2      
327m3572            R4152 -1   M      A18X+063422Y+006604X0198Y0197     S2      
327m3572            VIA   -    M      A18X+063210Y+008054X0260Y         S2      
327m3572            R6037 -1          A18X+062750Y+008054X0198Y0197R090 S2      
327m3573            J41   -A27        A01X+064278Y+005354X0150Y0570R180 S1      
327m3573            R4508 -2          A18X+064130Y+005375X0198Y0197R180 S2      
317m3573            VIA   -    M      A01X+064216Y+004470X0200Y         S2      
017m3573            VIA   -    M      A18X+064216Y+004470X0260Y         S2      
017m3573                  -    MD0100PA00X+064216Y+004470                       
317m3574            VIA   -    M      A01X+064261Y+009412X0200Y         S2      
017m3574            VIA   -    M      A18X+064261Y+009412X0260Y         S2      
017m3574                  -    MD0100PA00X+064261Y+009412                       
327m3574            R4149 -2          A18X+064122Y+007004X0198Y0197R180 S2      
317m3574            VIA   -    MD0100PA00X+066600Y+045786X0200Y    R270 S0      
327m3574            R51   -1          A01X+067242Y+045786X0198Y0197     S1      
327m3575            R4508 -1          A18X+063815Y+005375X0198Y0197R180 S2      
327m3575            R4149 -1   M      A18X+063807Y+007004X0198Y0197R180 S2      
327m3575            R4151 -1   M      A18X+063807Y+006604X0198Y0197R180 S2      
327m3575            VIA   -    M      A18X+063607Y+007634X0260Y    R180 S2      
327m3575            R6036 -1          A18X+064067Y+008054X0198Y0197R090 S2      
317m3576            VIA   -    MD0100PA00X+015870Y+143941X0200Y         S0      
317m3576            VIA   -    MD0100PA00X+086334Y+082471X0200Y         S0      
317m3576            VIA   -    MD0100PA00X+072643Y+034638X0200Y         S0      
327m3576            R2416 -1          A18X+060235Y+005576X0198Y0197R090 S2      
327m3576            R3227 -1          A18X+060233Y+006477X0198Y0197R270 S2      
317m3576            VIA   -    MD0100PA00X+060107Y+006030X0200Y         S0      
317m3576            VIA   -    M      A01X+014300Y+170101X0200Y         S2      
017m3576            VIA   -    M      A18X+014300Y+170101X0260Y         S2      
017m3576                  -    MD0100PA00X+014300Y+170101                       
327m3576            R3110 -1          A01X+014000Y+170101X0198Y0197R180 S1      
317m3577            VIA   -    MD0100PA00X+086337Y+082746X0200Y         S0      
317m3577            VIA   -    MD0100PA00X+016068Y+144105X0200Y         S0      
317m3577            VIA   -    MD0100PA00X+072921Y+034638X0200Y         S0      
327m3577            R2415 -1          A18X+060633Y+005576X0198Y0197R090 S2      
327m3577            R3226 -1          A18X+060626Y+006477X0198Y0197R270 S2      
317m3577            VIA   -    MD0100PA00X+060626Y+006030X0200Y         S0      
327m3577            R3109 -1          A01X+008534Y+169851X0198Y0197     S1      
317m3577            VIA   -    M      A01X+008250Y+169851X0200Y         S2      
017m3577            VIA   -    M      A18X+008250Y+169851X0260Y         S2      
017m3577                  -    MD0100PA00X+008250Y+169851                       
317m3578            J112  -R4   D0142PA00X+025453Y+165311X0302Y    R180 S3      
327m3578            R2898 -2          A01X+013989Y+170917X0198Y0197     S1      
317m3578            VIA   -    M      A01X+014300Y+170917X0200Y         S2      
017m3578            VIA   -    M      A18X+014300Y+170917X0260Y         S2      
017m3578                  -    MD0100PA00X+014300Y+170917                       
317m3579            J112  -Q4   D0142PA00X+025453Y+165783X0302Y    R180 S3      
327m3579            R2897 -2          A01X+008534Y+170651X0198Y0197R180 S1      
317m3579            VIA   -    M      A01X+008250Y+170651X0200Y         S2      
017m3579            VIA   -    M      A18X+008250Y+170651X0260Y         S2      
017m3579                  -    MD0100PA00X+008250Y+170651                       
317m3580            VIA   -    MD0100PA00X+069580Y+043096X0180Y    R090 S2      
327m3580            R6027 -1          A18X+067050Y+038479X0198Y0197R270 S2      
327m3580            R6025 -1          A01X+067280Y+037494X0198Y0197R270 S1      
317m3580            VIA   -    MD0100PA00X+067280Y+038236X0200Y         S0      
317m3580            VIA   -    MD0100PA00X+067000Y+042589X0200Y    R090 S0      
327m3580            U18   -A5         A01X+069733Y+043249X0160Y    R090 S1      
317m3581            VIA   -    M      A01X+068080Y+038028X0200Y         S2      
017m3581            VIA   -    M      A18X+068080Y+038028X0260Y         S2      
017m3581                  -    MD0100PA00X+068080Y+038028                       
327m3581            R6023 -2          A18X+067950Y+038479X0198Y0197R090 S2      
327m3581            R6015 -1          A01X+068080Y+037494X0198Y0197R270 S1      
327m3581            U18   -B5         A01X+070048Y+043249X0160Y    R090 S1      
317m3581            VIA   -    MD0100PA00X+069895Y+043096X0180Y    R090 S0      
317m3582            VIA   -    MD0100PA00X+070524Y+043726X0180Y    R090 S2      
327m3582            R6019 -2          A18X+067550Y+039644X0198Y0197R270 S2      
317m3582            VIA   -    MD0100PA00X+067550Y+039886X0200Y         S0      
327m3582            R6011 -1          A01X+067550Y+039644X0198Y0197R270 S1      
327m3582            U18   -D7         A01X+070678Y+043879X0160Y    R090 S1      
327m3583            VIA   -    M      A18X+070518Y+044938X0260Y         S2      
327m3583            U18   -G8         A01X+071623Y+044194X0160Y    R090 S1      
317m3583            VIA   -    MD0100PA00X+071469Y+044040X0180Y    R090 S0      
327m3583            R58   -1          A18X+067572Y+044720X0198Y0197     S2      
317m3584            VIA   -    M      A01X+059181Y+009742X0200Y         S2      
017m3584            VIA   -    M      A18X+059181Y+009742X0260Y         S2      
017m3584                  -    MD0100PA00X+059181Y+009742                       
327m3584            R6024 -2          A01X+059051Y+010350X0198Y0197R270 S1      
327m3584            R6026 -1          A01X+059050Y+009325X0198Y0197R270 S1      
317m3584            VIA   -    MD0100PA00X+066600Y+044236X0200Y    R270 S0      
327m3584            R58   -2          A18X+067258Y+044720X0198Y0197     S2      
317m3585            VIA   -    M      A01X+067994Y+040093X0200Y         S2      
017m3585            VIA   -    M      A18X+067994Y+040093X0260Y         S2      
017m3585                  -    MD0100PA00X+067994Y+040093                       
327m3585            R6012 -1          A01X+067950Y+039644X0198Y0197R270 S1      
327m3585            R6020 -2          A18X+067950Y+039644X0198Y0197R270 S2      
317m3585            VIA   -    MD0100PA00X+069895Y+042781X0180Y    R090 S0      
327m3585            U18   -B4         A01X+070048Y+042934X0160Y    R090 S1      
327m3586            U18   -E7         A01X+070993Y+043879X0160Y    R090 S1      
317m3586            VIA   -    MD0100PA00X+070840Y+043726X0180Y    R090 S0      
317m3586            VIA   -    M      A01X+068479Y+040227X0200Y         S2      
017m3586            VIA   -    M      A18X+068479Y+040227X0260Y         S2      
017m3586                  -    MD0100PA00X+068479Y+040227                       
327m3586            R6016 -2          A18X+068350Y+039644X0198Y0197R270 S2      
327m3586            R6008 -1          A01X+068350Y+039644X0198Y0197R270 S1      
327m3587            U18   -C6         A01X+070363Y+043564X0160Y    R090 S1      
317m3587            VIA   -    MD0100PA00X+070210Y+043411X0180Y    R090 S0      
327m3587            VIA   -    M      A18X+068318Y+043386X0260Y    R090 S2      
327m3587            R168  -1          A18X+067558Y+043386X0198Y0197     S2      
327m3588            VIA   -    M      A01X+068027Y+043431X0300Y    R090 S1      
327m3588            U18   -A4         A01X+069733Y+042934X0160Y    R090 S1      
327m3588            R167  -1          A01X+067558Y+042986X0198Y0197R180 S1      
317m3589            VIA   -    MD0100PA00X+067000Y+043384X0200Y    R270 S0      
327m3589            R168  -2          A18X+067242Y+043386X0198Y0197     S2      
317m3589            VIA   -    M      A01X+059930Y+010075X0200Y         S2      
017m3589            VIA   -    M      A18X+059930Y+010075X0260Y         S2      
017m3589                  -    MD0100PA00X+059930Y+010075                       
327m3589            R6022 -2          A01X+060233Y+010350X0198Y0197R270 S1      
327m3589            R6014 -1          A01X+060228Y+009325X0198Y0197R270 S1      
317m3590            VIA   -    M      A01X+061818Y+010079X0200Y         S2      
017m3590            VIA   -    M      A18X+061818Y+010079X0260Y         S2      
017m3590                  -    MD0100PA00X+061818Y+010079                       
327m3590            R6018 -2          A01X+061826Y+010350X0198Y0197R270 S1      
327m3590            R6010 -1          A01X+061818Y+009325X0198Y0197R270 S1      
317m3590            VIA   -    MD0100PA00X+067000Y+042986X0200Y         S0      
327m3590            R167  -2          A01X+067242Y+042986X0198Y0197R180 S1      
327m3591            R3173 -1          A18X+030002Y+004594X0198Y0197R090 S2      
327m3591            J35   -OB3        A01X+030261Y+004437X0150Y0570R180 S1      
317m3591            VIA   -    M      A01X+030371Y+005086X0200Y         S2      
017m3591            VIA   -    M      A18X+030371Y+005086X0260Y         S2      
017m3591                  -    MD0100PA00X+030371Y+005086                       
317m3591            VIA   -    MD0100PA00X+069157Y+046521X0200Y    R090 S0      
327m3591            U18   -A14        A01X+069733Y+046084X0160Y    R090 S1      
327m3592            R3175 -1          A18X+029172Y+003742X0198Y0197     S2      
327m3592            J35   -OB5        A01X+029788Y+004437X0150Y0570R180 S1      
317m3592            VIA   -    M      A01X+029854Y+005109X0200Y         S2      
017m3592            VIA   -    M      A18X+029854Y+005109X0260Y         S2      
017m3592                  -    MD0100PA00X+029854Y+005109                       
317m3592            VIA   -    MD0100PA00X+070210Y+046237X0180Y    R090 S0      
327m3592            U18   -C14        A01X+070363Y+046084X0160Y    R090 S1      
327m3593            U18   -B14        A01X+070048Y+046084X0160Y    R090 S1      
317m3593            VIA   -    MD0100PA00X+068761Y+047185X0200Y    R090 S0      
327m3593            VIA   -    M      A18X+029531Y+004323X0260Y         S2      
327m3593            R3174 -1          A18X+029557Y+003742X0198Y0197R180 S2      
327m3593            J35   -OB4        A01X+030024Y+004437X0150Y0570R180 S1      
317m3593            VIA   -    MD0100PA00X+030131Y+005248X0200Y         S0      
317m3594            VIA   -    M      A01X+029634Y+005586X0200Y         S2      
017m3594            VIA   -    M      A18X+029634Y+005586X0260Y         S2      
017m3594                  -    MD0100PA00X+029634Y+005586                       
327m3594            R3176 -1          A18X+029072Y+004594X0198Y0197R090 S2      
327m3594            J35   -OB6        A01X+029552Y+004437X0150Y0570R180 S1      
317m3594            VIA   -    MD0100PA00X+070524Y+046237X0180Y    R090 S0      
327m3594            U18   -D14        A01X+070678Y+046084X0160Y    R090 S1      
327m3595            R8420 -1          A18X+178199Y+004333X0198Y0197R090 S2      
327m3595            J38   -OB3        A01X+177702Y+004437X0150Y0570R180 S1      
317m3595            VIA   -    MD0100PA00X+178030Y+005440X0200Y         S0      
317m3595            VIA   -    M      A01X+066600Y+042984X0200Y         S2      
017m3595            VIA   -    M      A18X+066600Y+042984X0260Y         S2      
017m3595                  -    MD0100PA00X+066600Y+042984                       
327m3595            U18   -D8         A01X+070678Y+044194X0160Y    R090 S1      
317m3595            VIA   -    MD0100PA00X+070524Y+044040X0180Y    R090 S0      
317m3596            VIA   -    M      A01X+065762Y+043782X0200Y         S2      
017m3596            VIA   -    M      A18X+065762Y+043782X0260Y         S2      
017m3596                  -    MD0100PA00X+065762Y+043782                       
317m3596            VIA   -    MD0100PA00X+176920Y+005430X0200Y         S0      
327m3596            J38   -OB5        A01X+177229Y+004437X0150Y0570R180 S1      
327m3596            R8422 -1          A18X+177355Y+004328X0198Y0197R090 S2      
327m3596            U18   -A8         A01X+069733Y+044194X0160Y    R090 S1      
317m3597            VIA   -    M      A01X+177383Y+004900X0200Y         S2      
017m3597            VIA   -    M      A18X+177383Y+004900X0260Y         S2      
017m3597                  -    MD0100PA00X+177383Y+004900                       
327m3597            R8421 -1          A18X+177775Y+004344X0198Y0197R090 S2      
327m3597            J38   -OB4        A01X+177465Y+004437X0150Y0570R180 S1      
317m3597            VIA   -    MD0100PA00X+067000Y+043784X0200Y    R270 S0      
327m3597            U18   -B8         A01X+070048Y+044194X0160Y    R090 S1      
327m3598            R8423 -1          A18X+176990Y+004328X0198Y0197R090 S2      
327m3598            J38   -OB6        A01X+176993Y+004437X0150Y0570R180 S1      
317m3598            VIA   -    MD0100PA00X+176924Y+005079X0200Y         S0      
327m3598            VIA   -    M      A18X+068018Y+044586X0260Y    R090 S2      
327m3598            U18   -C9         A01X+070363Y+044509X0160Y    R090 S1      
317m3598            VIA   -    MD0100PA00X+070210Y+044356X0180Y    R090 S0      
317m3598            VIA   -    MD0100PA00X+066200Y+043784X0200Y    R270 S0      
327SCM_USB_OC_R_N   R588  -1          A01X+075250Y+052429X0198Y0197R090 S1      
327SCM_USB_OC_R_N   U18   -R19        A01X+074143Y+047659X0160Y    R090 S1      
317SCM_USB_OC_R_N   VIA   -    M      A01X+075395Y+052180X0200Y    R180 S2      
017SCM_USB_OC_R_N   VIA   -    M      A18X+075395Y+052180X0260Y    R180 S2      
017SCM_USB_OC_R_N         -    MD0100PA00X+075395Y+052180                       
317SCM_USB_OC_R_N   VIA   -    MD0100PA00X+074296Y+047812X0180Y    R090 S0      
317SCM_USB_OC_N     VIA   -    MD0100PA00X+159490Y+078011X0200Y         S0      
317SCM_USB_OC_N     VIA   -    MD0100PA00X+084900Y+064500X0200Y         S0      
327SCM_USB_OC_N     R588  -2          A01X+075250Y+052744X0198Y0197R090 S1      
317SCM_USB_OC_N     VIA   -    MD0100PA00X+075250Y+052986X0200Y         S0      
317SCM_USB_OC_N     VIA   -    MD0100PA00X+077945Y+063250X0200Y         S0      
327SCM_USB_OC_N     VIA   -    M      A18X+159536Y+079241X0260Y    R180 S2      
327SCM_USB_OC_N     U3    -2          A18X+158918Y+079725X0220Y0530R090 S2      
327SCM_USB_OC_N     R654  -1   M      A18X+159536Y+079721X0198Y0197R270 S2      
327m3599            VIA   -    M      A18X+157218Y+079255X0260Y    R180 S2      
327m3599            R589  -1          A18X+156767Y+079255X0198Y0197     S2      
327m3599            U3    -4          A18X+157953Y+079351X0220Y0530R090 S2      
317m3600            VIA   -    MD0080PA00X+147171Y+088600X0160Y    R180 S0      
327m3600            U25   -E23        A01X+146987Y+088705X0177Y    R180 S1      
327m3600            VIA   -    M      A18X+156455Y+080115X0260Y    R180 S2      
327m3600            R589  -2          A18X+156452Y+079255X0198Y0197     S2      
327m3600            R454  -2   M      A18X+156452Y+079655X0198Y0197     S2      
327m3601            R6093 -1          A18X+064753Y+047388X0198Y0197     S2      
327m3601            R63   -1          A18X+065642Y+046986X0198Y0197R180 S2      
327m3601            R6092 -1   M      A18X+064749Y+046983X0198Y0197     S2      
327m3601            VIA   -    M      A18X+065194Y+046958X0260Y         S2      
327SCM_SYS_PWROK    R63   -2          A18X+065958Y+046986X0198Y0197R180 S2      
327SCM_SYS_PWROK    VIA   -    M      A18X+068318Y+046986X0260Y    R090 S2      
327SCM_SYS_PWROK    U18   -A15        A01X+069733Y+046399X0160Y    R090 S1      
317SCM_SYS_PWROK    VIA   -    MD0100PA00X+069580Y+046552X0180Y    R090 S0      
317m3602            VIA   -    MD0100PA00X+058239Y+046470X0200Y         S0      
327m3602            U18   -E12        A01X+070993Y+045454X0160Y    R090 S1      
317m3602            VIA   -    MD0100PA00X+070840Y+045607X0180Y    R090 S2      
327m3602            R64   -1          A01X+065958Y+045386X0198Y0197R180 S1      
317m3602            VIA   -    MD0100PA00X+066600Y+045384X0200Y    R270 S0      
317m3602            VIA   -    MD0100PA00X+056800Y+005899X0200Y         S0      
327m3602            R1815 -1          A18X+056420Y+005576X0198Y0197R090 S2      
327SCM_SPARE_1      VIA   -    M      A18X+067965Y+046586X0260Y         S2      
317SCM_SPARE_1      VIA   -    MD0100PA00X+071154Y+046237X0180Y    R090 S0      
327SCM_SPARE_1      U18   -F14        A01X+071308Y+046084X0160Y    R090 S1      
327SCM_SPARE_1      R890  -2          A18X+065958Y+046586X0198Y0197R180 S2      
327SCM_SPARE_1      R891  -1   M      A18X+067558Y+046586X0198Y0197     S2      
327SCM_SPARE_0      U18   -G14        A01X+071623Y+046084X0160Y    R090 S1      
317SCM_SPARE_0      VIA   -    MD0100PA00X+071469Y+046237X0180Y    R090 S0      
327SCM_SPARE_0      VIA   -    M      A18X+068018Y+045886X0260Y    R090 S2      
327SCM_SPARE_0      R888  -2          A18X+065958Y+045786X0198Y0197R180 S2      
327SCM_SPARE_0      R889  -1   M      A18X+067558Y+045786X0198Y0197     S2      
317m3603            VIA   -    MD0100PA00X+070210Y+045922X0180Y    R090 S0      
327m3603            U18   -C13        A01X+070363Y+045769X0160Y    R090 S1      
317m3603            VIA   -    M      A01X+065404Y+009604X0200Y         S2      
017m3603            VIA   -    M      A18X+065404Y+009604X0260Y         S2      
017m3603                  -    MD0100PA00X+065404Y+009604                       
317m3603            VIA   -    MD0100PA00X+054992Y+003105X0200Y         S0      
327m3603            R1798 -1   M      A18X+054992Y+003409X0198Y0197R270 S2      
327m3603            R6035 -1          A18X+054272Y+003400X0198Y0197R270 S2      
327m3603            R6034 -2   M      A18X+054635Y+003401X0198Y0197R090 S2      
327m3604            U160  -9          A01X+045193Y+022225X0240Y0540R270 S1      
327m3604            U212  -9          A01X+052998Y+022493X0240Y0540R270 S1      
317m3604            VIA   -    MD0100PA00X+062888Y+012706X0200Y         S0      
327m3604            R1343 -2   M      A01X+125315Y+009047X0198Y0197R090 S1      
327m3604            U99   -4          A01X+124656Y+009047X0220Y0530R270 S1      
317m3604            VIA   -    MD0100PA00X+125566Y+009047X0200Y    R090 S0      
317m3604            VIA   -    MD0100PA00X+066600Y+042586X0200Y    R270 S0      
327m3604            R50   -2          A01X+067242Y+042586X0198Y0197R180 S1      
317m3604            VIA   -    MD0100PA00X+064128Y+018756X0200Y         S0      
317m3604            VIA   -    M      A01X+053428Y+022493X0200Y    R180 S2      
017m3604            VIA   -    M      A18X+053428Y+022493X0260Y    R180 S2      
017m3604                  -    MD0100PA00X+053428Y+022493                       
317m3604            VIA   -    MD0100PA00X+046444Y+021825X0200Y         S0      
327m3604            R1730 -2   M      A01X+046193Y+021825X0198Y0197R090 S1      
327m3604            R1729 -1   M      A01X+045793Y+021825X0198Y0197R270 S1      
327m3605            R49   -2          A01X+065642Y+042586X0198Y0197R180 S1      
317m3605            VIA   -    MD0100PA00X+065754Y+042269X0200Y    R270 S0      
317m3605            VIA   -    MD0100PA00X+054896Y+021844X0200Y         S0      
327m3605            R1659 -2   M      A01X+054656Y+021844X0198Y0197     S1      
327m3605            R1658 -1   M      A01X+054656Y+022244X0198Y0197R180 S1      
327m3605            R6102 -1          A01X+054656Y+022644X0198Y0197R180 S1      
317m3605            VIA   -    M      A01X+047137Y+022276X0200Y         S2      
017m3605            VIA   -    M      A18X+047137Y+022276X0260Y         S2      
017m3605                  -    MD0100PA00X+047137Y+022276                       
327m3605            R6101 -1          A01X+046897Y+022276X0198Y0197R180 S1      
327m3606            U18   -A3         A01X+069733Y+042619X0160Y    R090 S1      
327m3606            VIA   -    M      A01X+068340Y+043036X0300Y    R090 S1      
327m3606            R50   -1          A01X+067558Y+042586X0198Y0197R180 S1      
327m3607            R49   -1          A01X+065958Y+042586X0198Y0197R180 S1      
327m3607            VIA   -    M      A01X+066373Y+042282X0160Y0041     S1      
327m3607            U18   -B3         A01X+070048Y+042619X0160Y    R090 S1      
327SCM_IRQ_R_N      R71   -1          A01X+059658Y+044550X0198Y0197R180 S1      
327SCM_IRQ_R_N      VIA   -    M      A01X+060000Y+044600X0300Y    R180 S1      
327SCM_IRQ_R_N      U92   -4          A01X+060449Y+043221X0220Y0530R270 S1      
327SCM_IRQ_N        R1338 -2   M      A01X+059342Y+044950X0198Y0197R180 S1      
327SCM_IRQ_N        R71   -2          A01X+059342Y+044550X0198Y0197R180 S1      
317SCM_IRQ_N        VIA   -    M      A01X+053446Y+042856X0200Y         S2      
017SCM_IRQ_N        VIA   -    M      A18X+053446Y+042856X0260Y         S2      
017SCM_IRQ_N              -    MD0100PA00X+053446Y+042856                       
317SCM_IRQ_N        VIA   -    MD0100PA00X+053512Y+003134X0200Y         S0      
327SCM_IRQ_N        R321  -1          A18X+053512Y+003396X0198Y0197R270 S2      
327m3608            VIA   -    M      A01X+074850Y+050301X0300Y         S1      
327m3608            U18   -T20        A01X+074458Y+047974X0160Y    R090 S1      
317m3608            VIA   -    MD0100PA00X+074611Y+048127X0180Y    R090 S0      
327m3608            R174  -1          A01X+074850Y+050779X0198Y0197R090 S1      
317m3608            VIA   -    MD0100PA00X+074838Y+049524X0200Y    R090 S0      
317SCM_IRQ_1V8_N    VIA   -    M      A01X+058880Y+043595X0200Y    R090 S2      
017SCM_IRQ_1V8_N    VIA   -    M      A18X+058880Y+043595X0260Y    R090 S2      
017SCM_IRQ_1V8_N          -    MD0100PA00X+058880Y+043595                       
327SCM_IRQ_1V8_N    U92   -2          A01X+059485Y+043595X0220Y0530R270 S1      
327SCM_IRQ_1V8_N    R996  -2          A01X+058620Y+043595X0198Y0197     S1      
317SCM_IRQ_1V8_N    VIA   -    MD0100PA00X+065557Y+057260X0200Y         S0      
317SCM_IRQ_1V8_N    VIA   -    MD0100PA00X+075173Y+055771X0200Y         S0      
327SCM_IRQ_1V8_N    R174  -2          A01X+074850Y+051094X0198Y0197R090 S1      
317SCM_IRQ_1V8_N    VIA   -    MD0100PA00X+074850Y+051336X0200Y    R180 S0      
317m3609            VIA   -    M      A01X+072289Y+162249X0200Y         S2      
017m3609            VIA   -    M      A18X+072289Y+162249X0260Y         S2      
017m3609                  -    MD0100PA00X+072289Y+162249                       
327m3609            R2848 -2          A01X+072472Y+162694X0198Y0197R270 S1      
327m3609            U195  -3   M      A18X+069088Y+163420X0160Y0200R270 S2      
327m3609            R2909 -2   M      A18X+068054Y+163704X0198Y0197R180 S2      
327m3609            R2916 -1          A18X+068054Y+164204X0198Y0197     S2      
327m3610            U195  -4          A18X+069836Y+163420X0160Y0200R270 S2      
327m3610            VIA   -    M      A18X+070513Y+163750X0260Y         S2      
327m3610            R2924 -1          A18X+071812Y+163296X0198Y0197R180 S2      
327m3610            R2911 -2   M      A18X+071332Y+163786X0198Y0197R270 S2      
327m3610            R2927 -1   M      A18X+070932Y+163786X0198Y0197R090 S2      
317m3611            VIA   -    MD0100PA00X+065187Y+161299X0200Y         S0      
317m3611            VIA   -    M      A01X+115198Y+166668X0200Y         S2      
017m3611            VIA   -    M      A18X+115198Y+166668X0260Y         S2      
017m3611                  -    MD0100PA00X+115198Y+166668                       
317m3611            VIA   -    MD0100PA00X+068704Y+145230X0200Y         S0      
317m3611            J105  -N6   D0142PA00X+160925Y+167201X0302Y    R180 S3      
317m3611            VIA   -    MD0100PA00X+112695Y+148465X0200Y         S0      
317m3611            VIA   -    MD0100PA00X+063991Y+157044X0200Y         S0      
317m3611            VIA   -    MD0100PA00X+071812Y+163633X0200Y         S0      
327m3611            R2924 -2          A18X+072127Y+163296X0198Y0197R180 S2      
317m3612            VIA   -    MD0100PA00X+108463Y+167300X0200Y         S0      
317m3612            VIA   -    MD0100PA00X+094380Y+166076X0200Y         S0      
327m3612            R2905 -1          A18X+094380Y+166319X0198Y0197R270 S2      
317m3612            VIA   -    MD0100PA00X+107112Y+144500X0200Y         S0      
317m3612            VIA   -    M      A01X+069072Y+057891X0200Y         S2      
017m3612            VIA   -    M      A18X+069072Y+057891X0260Y         S2      
017m3612                  -    MD0100PA00X+069072Y+057891                       
317m3612            VIA   -    MD0100PA00X+055376Y+016008X0200Y         S0      
327m3612            U225  -2          A01X+020562Y+011302X0170Y0240     S1      
317m3612            VIA   -    MD0100PA00X+023519Y+011202X0200Y         S0      
317m3612            VIA   -    MD0100PA00X+149975Y+048842X0200Y         S0      
317m3612            VIA   -    MD0100PA00X+180016Y+036254X0200Y         S0      
327m3612            U224  -2          A01X+180507Y+036861X0170Y0240R270 S1      
327m3612            R2268 -1          A01X+109887Y+047936X0198Y0197     S1      
317m3612            VIA   -    MD0100PA00X+108343Y+048150X0200Y         S0      
327m3612            R1822 -2   M      A01X+109351Y+048460X0198Y0197     S1      
317m3612            VIA   -    MD0100PA00X+111100Y+036127X0200Y         S0      
317m3612            VIA   -    MD0100PA00X+100708Y+048494X0200Y         S0      
317m3612            VIA   -    MD0100PA00X+101160Y+056847X0200Y         S0      
327m3612            U18   -D17        A01X+070678Y+047029X0160Y    R090 S1      
317m3612            VIA   -    MD0100PA00X+070524Y+047182X0180Y    R090 S0      
317m3612            VIA   -    MD0100PA00X+055336Y+047782X0200Y         S0      
327m3612            R3710 -1          A01X+101119Y+048416X0198Y0197     S1      
327m3612            R3705 -2          A01X+100391Y+049018X0198Y0197     S1      
317m3612            VIA   -    MD0100PA00X+179436Y+127555X0200Y         S0      
317m3612            VIA   -    MD0100PA00X+170027Y+146055X0200Y         S0      
317m3612            VIA   -    MD0100PA00X+071574Y+162284X0200Y         S0      
327m3612            R2922 -1   M      A01X+071515Y+162751X0198Y0197R090 S1      
327m3612            R2921 -2          A01X+071915Y+162751X0198Y0197R270 S1      
317m3612            VIA   -    MD0100PA00X+078467Y+146218X0200Y         S0      
327m3613            R3236 -2          A01X+022406Y+012066X0198Y0197     S1      
317m3613            VIA   -    MD0100PA00X+023546Y+011579X0200Y         S0      
327m3613            J35   -A9         A01X+024042Y+003276X0150Y0570R180 S1      
317m3613            VIA   -    M      A01X+024131Y+002032X0200Y         S2      
017m3613            VIA   -    M      A18X+024131Y+002032X0260Y         S2      
017m3613                  -    MD0100PA00X+024131Y+002032                       
327m3614            J38   -A9         A01X+171483Y+003276X0150Y0570R180 S1      
317m3614            VIA   -    MD0100PA00X+172215Y+001991X0200Y         S0      
317m3614            VIA   -    M      A01X+182973Y+037133X0200Y         S2      
017m3614            VIA   -    M      A18X+182973Y+037133X0260Y         S2      
017m3614                  -    MD0100PA00X+182973Y+037133                       
327m3614            R3233 -2          A01X+182731Y+037133X0198Y0197     S1      
327RST_SMB_E1S_N    VIA   -    M      A01X+099251Y+029563X0300Y         S1      
327RST_SMB_E1S_N    U134  -3          A01X+099769Y+029052X0170Y0240R270 S1      
327RST_SMB_E1S_N    U134  -1   M      A01X+099769Y+029563X0170Y0240R270 S1      
327RST_SMB_E1S_N    R3775 -2          A01X+098766Y+029564X0198Y0197     S1      
317m3615            VIA   -    MD0100PA00X+088713Y+018317X0200Y         S0      
327m3615            R1673 -2          A01X+088429Y+018317X0198Y0197     S1      
327m3615            J90   -A9         A01X+091339Y+018648X0150Y0500R090 S1      
317m3615            VIA   -    MD0100PA00X+102769Y+023790X0200Y         S0      
317m3615            VIA   -    M      A01X+102300Y+029831X0200Y         S2      
017m3615            VIA   -    M      A18X+102300Y+029831X0260Y         S2      
017m3615                  -    MD0100PA00X+102300Y+029831                       
327m3615            R3772 -2          A01X+101841Y+029831X0198Y0197     S1      
327m3615            R3773 -2          A01X+102783Y+029831X0198Y0197R180 S1      
327m3616            VIA   -    M      A01X+101055Y+029831X0300Y         S1      
327m3616            U134  -6          A01X+100517Y+029563X0170Y0240R270 S1      
327m3616            R3772 -1          A01X+101526Y+029831X0198Y0197     S1      
327m3617            U18   -W17        A01X+075402Y+047029X0160Y    R090 S1      
317m3617            VIA   -    MD0100PA00X+075556Y+047182X0180Y    R090 S0      
327m3617            R9023 -1          A01X+083192Y+047100X0198Y0197     S1      
317m3617            VIA   -    M      A01X+083021Y+048389X0200Y         S2      
017m3617            VIA   -    M      A18X+083021Y+048389X0260Y         S2      
017m3617                  -    MD0100PA00X+083021Y+048389                       
327m3618            R798  -1          A01X+077508Y+047234X0198Y0197     S1      
317m3618            VIA   -    M      A01X+077059Y+047094X0200Y    R090 S2      
017m3618            VIA   -    M      A18X+077059Y+047094X0260Y    R090 S2      
017m3618                  -    MD0100PA00X+077059Y+047094                       
327m3618            U18   -V16        A01X+075087Y+046714X0160Y    R090 S1      
317m3618            VIA   -    MD0100PA00X+075241Y+046867X0180Y    R090 S0      
327m3619            VIA   -           A01X+077738Y+046688X0300Y         S1      
327m3619            U18   -AA13       A01X+076032Y+045769X0160Y    R090 S1      
327m3619            R685  -1   M      A01X+077508Y+046334X0198Y0197     S1      
317m3620            VIA   -    M      A01X+016274Y+172389X0200Y         S2      
017m3620            VIA   -    M      A18X+016274Y+172389X0260Y         S2      
017m3620                  -    MD0100PA00X+016274Y+172389                       
327m3620            R3466 -1          A01X+015889Y+172650X0198Y0197R180 S1      
327m3620            U256  -6          A01X+016274Y+172106X0160Y0200R270 S1      
327m3620            R3468 -1   M      A01X+016274Y+172650X0198Y0197     S1      
317m3621            VIA   -    M      A01X+021236Y+170540X0200Y         S2      
017m3621            VIA   -    M      A18X+021236Y+170540X0260Y         S2      
017m3621                  -    MD0100PA00X+021236Y+170540                       
317m3621            J112  -A1   D0142PA00X+023090Y+173421X0302Y0302R180 S3      
327m3621            R3391 -2          A01X+020908Y+170700X0198Y0197     S1      
317m3622            VIA   -    M      A01X+020351Y+171244X0200Y         S2      
017m3622            VIA   -    M      A18X+020351Y+171244X0260Y         S2      
017m3622                  -    MD0100PA00X+020351Y+171244                       
327m3622            R3391 -1          A01X+020592Y+170700X0198Y0197     S1      
327m3622            R3455 -1   M      A01X+020208Y+170700X0198Y0197R180 S1      
327m3622            U252  -4          A01X+020624Y+171244X0160Y0200R270 S1      
317m3623            VIA   -    M      A01X+017194Y+173069X0200Y         S2      
017m3623            VIA   -    M      A18X+017194Y+173069X0260Y         S2      
017m3623                  -    MD0100PA00X+017194Y+173069                       
327m3623            R3468 -2          A01X+016589Y+172650X0198Y0197     S1      
317m3623            J112  -A5   D0142PA00X+026240Y+173421X0302Y    R180 S3      
317m3624            VIA   -    M      A01X+020366Y+172300X0200Y         S2      
017m3624            VIA   -    M      A18X+020366Y+172300X0260Y         S2      
017m3624                  -    MD0100PA00X+020366Y+172300                       
327m3624            R3467 -1          A01X+020085Y+172300X0198Y0197R180 S1      
327m3624            U252  -6          A01X+020624Y+171756X0160Y0200R270 S1      
327m3624            R3469 -1   M      A01X+020624Y+172300X0198Y0197     S1      
317m3625            VIA   -    M      A01X+021186Y+170110X0300Y         S1      
017m3625            VIA   -    M      A18X+021186Y+170110X0200Y         S1      
017m3625                  -    MD0100PA00X+021186Y+170110                       
327m3625            R3469 -2          A01X+020939Y+172300X0198Y0197     S1      
317m3625            J112  -T8   D0142PA00X+028602Y+164366X0302Y    R180 S3      
317m3626            VIA   -    M      A01X+032365Y+015212X0200Y    R270 S2      
017m3626            VIA   -    M      A18X+032365Y+015212X0260Y    R270 S2      
017m3626                  -    MD0100PA00X+032365Y+015212                       
327m3626            J35   -OA2        A01X+030497Y+003276X0150Y0570R180 S1      
317m3626            VIA   -    MD0100PA00X+030497Y+002836X0200Y         S0      
327m3626            R6059 -2          A01X+032607Y+015212X0198Y0197R180 S1      
317m3627            VIA   -    MD0100PA00X+078373Y+032847X0200Y         S0      
327m3627            R956  -2          A01X+084378Y+048213X0198Y0197     S1      
317m3627            VIA   -    MD0100PA00X+084641Y+048213X0200Y         S0      
317m3627            VIA   -    M      A01X+177592Y+002203X0200Y         S2      
017m3627            VIA   -    M      A18X+177592Y+002203X0260Y         S2      
017m3627                  -    MD0100PA00X+177592Y+002203                       
327m3627            J38   -OA2        A01X+177938Y+003276X0150Y0570R180 S1      
327m3628            R6058 -2          A01X+032607Y+014712X0198Y0197R180 S1      
317m3628            VIA   -    M      A01X+032365Y+014712X0200Y    R270 S2      
017m3628            VIA   -    M      A18X+032365Y+014712X0260Y    R270 S2      
017m3628                  -    MD0100PA00X+032365Y+014712                       
327m3628            J35   -OA1        A01X+030733Y+003276X0150Y0570R180 S1      
317m3628            VIA   -    MD0100PA00X+030492Y+002466X0200Y         S0      
327m3629            R905  -2          A01X+084378Y+049057X0198Y0197     S1      
317m3629            VIA   -    MD0100PA00X+084752Y+049090X0200Y         S0      
317m3629            VIA   -    MD0100PA00X+079173Y+032847X0200Y         S0      
317m3629            VIA   -    M      A01X+178783Y+003755X0200Y         S2      
017m3629            VIA   -    M      A18X+178783Y+003755X0260Y         S2      
017m3629                  -    MD0100PA00X+178783Y+003755                       
327m3629            J38   -OA1        A01X+178174Y+003276X0150Y0570R180 S1      
317m3630            VIA   -    MD0100PA00X+032365Y+015612X0200Y    R270 S0      
327m3630            R6057 -2          A01X+032607Y+015612X0198Y0197R180 S1      
327m3630            J35   -A11        A01X+023570Y+003276X0150Y0570R180 S1      
317m3630            VIA   -    M      A01X+023570Y+002158X0200Y         S2      
017m3630            VIA   -    M      A18X+023570Y+002158X0260Y         S2      
017m3630                  -    MD0100PA00X+023570Y+002158                       
317m3631            VIA   -    MD0100PA00X+084610Y+049466X0200Y         S0      
317m3631            VIA   -    M      A01X+079923Y+032847X0200Y         S2      
017m3631            VIA   -    M      A18X+079923Y+032847X0260Y         S2      
017m3631                  -    MD0100PA00X+079923Y+032847                       
327m3631            R899  -2          A01X+084366Y+049466X0198Y0197     S1      
317m3631            VIA   -    MD0100PA00X+171298Y+001999X0200Y         S0      
327m3631            J38   -A11        A01X+171011Y+003276X0150Y0570R180 S1      
327m3632            J35   -B10        A01X+023806Y+004437X0150Y0570R180 S1      
317m3632            VIA   -    M      A01X+023982Y+005436X0200Y         S2      
017m3632            VIA   -    M      A18X+023982Y+005436X0260Y         S2      
017m3632                  -    MD0100PA00X+023982Y+005436                       
317m3632            VIA   -    MD0100PA00X+032365Y+016012X0200Y    R270 S0      
327m3632            R6056 -2          A01X+032607Y+016012X0198Y0197R180 S1      
327m3633            J38   -B10        A01X+171247Y+004437X0150Y0570R180 S1      
327m3633            R877  -2          A01X+084381Y+048648X0198Y0197     S1      
317m3633            VIA   -    M      A01X+084730Y+048579X0200Y         S2      
017m3633            VIA   -    M      A18X+084730Y+048579X0260Y         S2      
017m3633                  -    MD0100PA00X+084730Y+048579                       
317m3633            VIA   -    MD0100PA00X+078750Y+032836X0200Y         S0      
317m3633            VIA   -    MD0100PA00X+171586Y+007259X0200Y         S0      
327m3634            J90   -B10        A01X+093150Y+018884X0150Y0500R090 S1      
327m3634            R3779 -2          A01X+094137Y+018905X0198Y0197R180 S1      
317m3634            VIA   -    M      A01X+093727Y+018901X0200Y         S2      
017m3634            VIA   -    M      A18X+093727Y+018901X0260Y         S2      
017m3634                  -    MD0100PA00X+093727Y+018901                       
327m3635            U259  -4          A01X+057378Y+039860X0140Y0440R270 S1      
327m3635            VIA   -    M      A01X+055625Y+039479X0300Y    R270 S1      
327m3635            R2113 -1          A01X+055625Y+040359X0198Y0197R180 S1      
327m3635            R2121 -2   M      A01X+055625Y+039959X0198Y0197     S1      
317m3636            VIA   -    M      A01X+065433Y+017444X0300Y         S1      
017m3636            VIA   -    M      A18X+065433Y+017444X0200Y         S1      
017m3636                  -    MD0100PA00X+065433Y+017444                       
327m3636            J59   -50         A01X+066755Y+017342X0110Y0630R270 S1      
317m3636            VIA   -    MD0100PA00X+055057Y+040359X0200Y    R270 S0      
327m3636            R2113 -2          A01X+055310Y+040359X0198Y0197R180 S1      
317m3636            VIA   -    MD0100PA00X+062637Y+019343X0200Y         S0      
327m3637            R3235 -1          A01X+022090Y+012466X0198Y0197     S1      
327m3637            VIA   -    M      A01X+021490Y+012050X0300Y         S1      
327m3637            U225  -4          A01X+020818Y+012050X0170Y0240     S1      
327m3637            R3236 -1   M      A01X+022090Y+012066X0198Y0197     S1      
327m3638            R3233 -1          A01X+182416Y+037133X0198Y0197     S1      
327m3638            R3232 -1   M      A01X+182416Y+036736X0198Y0197     S1      
327m3638            VIA   -    M      A01X+181827Y+036605X0300Y         S1      
327m3638            U224  -4          A01X+181255Y+036605X0170Y0240R270 S1      
317m3639            VIA   -    MD0080PA00X+145809Y+115242X0160Y         S0      
327m3639            U25   -DE27       A01X+145625Y+115138X0177Y    R180 S1      
327m3639            VIA   -    M      A18X+154854Y+129714X0260Y    R180 S2      
327m3639            R474  -2          A18X+156943Y+129957X0198Y0197     S2      
327m3640            VIA   -    M      A18X+074017Y+048907X0260Y    R270 S2      
327m3640            U18   -T22        A01X+074458Y+048604X0160Y    R090 S1      
327m3640            R1558 -1          A18X+074044Y+049777X0198Y0197R270 S2      
317m3640            VIA   -    MD0100PA00X+074296Y+049007X0180Y    R090 S0      
327m3641            J41   -B4         A01X+069711Y+006516X0150Y0570R180 S1      
317m3641            VIA   -    M      A01X+158529Y+128510X0200Y    R180 S2      
017m3641            VIA   -    M      A18X+158529Y+128510X0260Y    R180 S2      
017m3641                  -    MD0100PA00X+158529Y+128510                       
317m3641            VIA   -    MD0100PA00X+069670Y+007246X0200Y         S0      
327m3641            R1558 -2          A18X+074044Y+050092X0198Y0197R270 S2      
317m3641            VIA   -    MD0100PA00X+074509Y+055356X0200Y    R180 S0      
327m3641            R474  -1          A18X+157258Y+129957X0198Y0197     S2      
327m3641            R457  -2   M      A18X+157643Y+129957X0198Y0197     S2      
317RST_CPU1_SYS_N   VIA   -    M      A01X+064615Y+053523X0200Y         S2      
017RST_CPU1_SYS_N   VIA   -    M      A18X+064615Y+053523X0260Y         S2      
017RST_CPU1_SYS_N         -    MD0100PA00X+064615Y+053523                       
317RST_CPU1_SYS_N   VIA   -    MD0100PA00X+005504Y+129568X0200Y         S0      
317RST_CPU1_SYS_N   VIA   -    MD0100PA00X+061055Y+126989X0200Y    R180 S0      
327RST_CPU1_SYS_N   U26   -DH6        A01X+055968Y+116095X0177Y    R180 S1      
317RST_CPU1_SYS_N   VIA   -    MD0100PA00X+071211Y+053780X0200Y         S0      
327RST_CPU1_SYS_N   R272  -1          A01X+071250Y+051094X0198Y0197R270 S1      
317RST_CPU1_SYS_N   VIA   -    MD0100PA00X+042762Y+127792X0200Y         S0      
327RST_CPU1_SYS_N   R559  -2          A18X+061321Y+127089X0198Y0197     S2      
317m3642            VIA   -    MD0080PA00X+054486Y+115880X0160Y         S0      
327m3642            U26   -DG10       A01X+054302Y+115776X0177Y    R180 S1      
317m3642            VIA   -    M      A01X+059811Y+126436X0200Y    R180 S2      
017m3642            VIA   -    M      A18X+059811Y+126436X0260Y    R180 S2      
017m3642                  -    MD0100PA00X+059811Y+126436                       
327m3642            R583  -1   M      A01X+060020Y+126260X0198Y0197     S1      
327m3642            R584  -2          A01X+060020Y+127060X0198Y0197R180 S1      
327m3642            C5024 -1   M      A01X+060020Y+126660X0198Y0197     S1      
317m3642            VIA   -    MD0100PA00X+042402Y+127464X0200Y         S0      
327m3642            R273  -1          A01X+070850Y+051094X0198Y0197R270 S1      
317m3642            VIA   -    MD0100PA00X+070850Y+053386X0200Y         S0      
317m3642            VIA   -    MD0100PA00X+065597Y+054438X0200Y         S0      
327m3643            U26   -B67        A01X+033275Y+087748X0177Y    R180 S1      
327m3643            R556  -2          A18X+026987Y+079191X0198Y0197R090 S2      
327m3643            R530  -2          A18X+027470Y+079399X0198Y0197     S2      
317m3643            VIA   -    M      A01X+027428Y+078674X0200Y    R180 S2      
017m3643            VIA   -    M      A18X+027428Y+078674X0260Y    R180 S2      
017m3643                  -    MD0100PA00X+027428Y+078674                       
327m3643            R57   -1          A01X+071650Y+051094X0198Y0197R270 S1      
317m3643            VIA   -    MD0100PA00X+071672Y+051337X0200Y    R180 S0      
317m3643            VIA   -    MD0100PA00X+044802Y+050534X0200Y    R090 S0      
327m3644            R198  -2          A01X+070450Y+054029X0198Y0197R270 S1      
317m3644            VIA   -    MD0100PA00X+070450Y+053786X0200Y         S0      
327m3644            U18   -G16        A01X+071623Y+046714X0160Y    R090 S1      
317m3644            VIA   -    MD0100PA00X+071469Y+046867X0180Y    R090 S2      
317m3645            VIA   -    MD0080PA00X+044864Y+115880X0160Y         S0      
327m3645            U26   -DG36       A01X+044680Y+115776X0177Y    R180 S1      
317m3645            VIA   -    M      A01X+046577Y+052499X0200Y         S2      
017m3645            VIA   -    M      A18X+046577Y+052499X0260Y         S2      
017m3645                  -    MD0100PA00X+046577Y+052499                       
317m3645            VIA   -    MD0100PA00X+042415Y+045317X0200Y         S0      
317m3645            VIA   -    MD0100PA00X+070450Y+054586X0200Y         S0      
327m3645            R19   -1          A01X+070450Y+055029X0198Y0197R090 S1      
327m3645            R198  -1          A01X+070450Y+054344X0198Y0197R270 S1      
327m3646            U18   -E19        A01X+070993Y+047659X0160Y    R090 S1      
317m3646            VIA   -    MD0100PA00X+070840Y+047812X0180Y    R090 S2      
327m3646            R197  -2          A01X+070050Y+052429X0198Y0197R270 S1      
317m3646            VIA   -    MD0100PA00X+069980Y+052176X0200Y    R180 S0      
327m3647            R197  -1          A01X+070050Y+052744X0198Y0197R270 S1      
317m3647            VIA   -    MD0100PA00X+070079Y+053773X0200Y         S0      
327m3647            R18   -1          A01X+070050Y+054029X0198Y0197R090 S1      
317m3647            VIA   -    MD0100PA00X+075774Y+065535X0200Y         S0      
317m3647            VIA   -    M      A01X+082249Y+080294X0200Y         S2      
017m3647            VIA   -    M      A18X+082249Y+080294X0260Y         S2      
017m3647                  -    MD0100PA00X+082249Y+080294                       
317m3647            VIA   -    MD0100PA00X+063625Y+077118X0200Y         S0      
327m3647            U26   -D18        A01X+051409Y+088386X0177Y    R180 S1      
317m3647            VIA   -    MD0080PA00X+051592Y+088281X0160Y    R180 S0      
317RST_CPU0_SYS_N   VIA   -    MD0080PA00X+153766Y+116199X0160Y         S0      
327RST_CPU0_SYS_N   U25   -DH6        A01X+153582Y+116094X0177Y    R180 S1      
317RST_CPU0_SYS_N   VIA   -    MD0100PA00X+120327Y+048124X0200Y         S0      
317RST_CPU0_SYS_N   VIA   -    MD0100PA00X+159888Y+127077X0200Y    R180 S0      
317RST_CPU0_SYS_N   VIA   -    MD0100PA00X+115527Y+020734X0200Y    R180 S0      
327RST_CPU0_SYS_N   R422  -2   M      A01X+115527Y+020484X0198Y0197     S1      
317RST_CPU0_SYS_N   J6    -3    D0440PA00X+118386Y+020720X0640Y    R090 S3      
317RST_CPU0_SYS_N   VIA   -    MD0100PA00X+070450Y+052986X0200Y         S2      
317RST_CPU0_SYS_N   VIA   -    MD0100PA00X+112508Y+051150X0200Y         S0      
327RST_CPU0_SYS_N   R216  -1          A01X+070450Y+052744X0198Y0197R270 S1      
317m3648            VIA   -    MD0080PA00X+152100Y+115880X0160Y         S0      
327m3648            R217  -1          A01X+071248Y+052613X0198Y0197R270 S1      
327m3648            U25   -DG10       A01X+151916Y+115776X0177Y    R180 S1      
317m3648            VIA   -    MD0100PA00X+152100Y+116949X0200Y    R180 S0      
317m3648            VIA   -    MD0100PA00X+154352Y+124820X0200Y    R180 S0      
327m3648            R581  -1          A01X+155618Y+126279X0198Y0197R090 S1      
327m3648            R582  -2          A01X+155025Y+126627X0198Y0197     S1      
327m3648            C5023 -1   M      A01X+155021Y+126231X0198Y0197R180 S1      
317m3648            VIA   -    MD0100PA00X+093339Y+038640X0200Y         S0      
317m3648            VIA   -    MD0100PA00X+093339Y+055994X0200Y         S0      
317m3648            VIA   -    MD0100PA00X+071241Y+055541X0200Y         S0      
317m3648            VIA   -    MD0100PA00X+120745Y+034138X0200Y         S0      
327m3648            Q87   -2          A18X+123266Y+028951X0170Y0200R270 S2      
317m3648            VIA   -    M      A01X+123009Y+028795X0300Y         S1      
017m3648            VIA   -    M      A18X+123009Y+028795X0200Y         S1      
017m3648                  -    MD0100PA00X+123009Y+028795                       
317m3649            VIA   -    MD0080PA00X+130705Y+087643X0160Y    R180 S0      
327m3649            U25   -B67        A01X+130889Y+087748X0177Y    R180 S1      
317m3649            VIA   -    MD0100PA00X+028232Y+079487X0200Y    R180 S0      
327m3649            R442  -1          A18X+126918Y+080440X0198Y0197R090 S2      
317m3649            VIA   -    MD0100PA00X+127118Y+080896X0200Y    R180 S0      
317m3649            VIA   -    MD0100PA00X+077246Y+065529X0200Y         S0      
317m3649            VIA   -    M      A01X+044368Y+050226X0200Y    R090 S2      
017m3649            VIA   -    M      A18X+044368Y+050226X0260Y    R090 S2      
017m3649                  -    MD0100PA00X+044368Y+050226                       
317m3649            VIA   -    MD0100PA00X+072045Y+051336X0200Y    R180 S0      
327m3649            R241  -1          A01X+072050Y+051094X0198Y0197R270 S1      
317m3649            VIA   -    MD0100PA00X+110444Y+064698X0200Y         S0      
327m3649            R530  -1          A18X+027785Y+079399X0198Y0197     S2      
327m3650            U18   -D20        A01X+070678Y+047974X0160Y    R090 S1      
317m3650            VIA   -    MD0100PA00X+070524Y+048127X0180Y    R090 S0      
327m3650            R255  -2          A18X+069663Y+050253X0198Y0197R180 S2      
327m3650            VIA   -    M      A18X+069665Y+049744X0260Y    R090 S2      
317m3651            VIA   -    MD0080PA00X+142478Y+115880X0160Y         S0      
327m3651            U25   -DG36       A01X+142294Y+115776X0177Y    R180 S1      
327m3651            VIA   -    M      A18X+158099Y+131611X0260Y    R180 S2      
317m3651            VIA   -    MD0100PA00X+159924Y+130662X0200Y    R180 S0      
317m3651            VIA   -    MD0100PA00X+069602Y+052184X0200Y    R180 S0      
327m3651            R17   -1          A01X+069650Y+052429X0198Y0197R090 S1      
327m3651            R255  -1          A18X+069348Y+050253X0198Y0197R180 S2      
317m3651            VIA   -    MD0100PA00X+083906Y+055581X0200Y         S0      
327m3652            R254  -2          A18X+070065Y+049777X0198Y0197R090 S2      
327m3652            U18   -F17        A01X+071308Y+047029X0160Y    R090 S1      
317m3652            VIA   -    MD0100PA00X+071154Y+047182X0180Y    R090 S0      
327m3652            VIA   -    M      A18X+070295Y+049304X0260Y    R090 S2      
317m3653            VIA   -    MD0080PA00X+149207Y+088281X0160Y    R180 S0      
327m3653            U25   -D18        A01X+149023Y+088386X0177Y    R180 S1      
317m3653            VIA   -    M      A01X+109573Y+050936X0200Y         S2      
017m3653            VIA   -    M      A18X+109573Y+050936X0260Y         S2      
017m3653                  -    MD0100PA00X+109573Y+050936                       
317m3653            VIA   -    MD0100PA00X+070379Y+052182X0200Y    R180 S0      
327m3653            R16   -1          A18X+070331Y+052470X0198Y0197     S2      
317m3653            VIA   -    MD0100PA00X+169349Y+062067X0200Y         S0      
317m3653            VIA   -    MD0100PA00X+168589Y+070861X0200Y         S0      
327m3653            R254  -1          A18X+070065Y+050092X0198Y0197R090 S2      
317m3654            VIA   -    MD0080PA00X+146179Y+116518X0160Y         S0      
327m3654            U25   -DJ26       A01X+145995Y+116413X0177Y    R180 S1      
327m3654            VIA   -    M      A18X+146304Y+120164X0260Y    R180 S2      
327m3654            R1351 -1   M      A18X+155963Y+129042X0198Y0197R180 S2      
327m3654            R463  -1          A18X+155963Y+129392X0198Y0197R180 S2      
327m3655            R463  -2          A18X+156278Y+129392X0198Y0197R180 S2      
317m3655            VIA   -    MD0100PA00X+156700Y+129345X0200Y    R180 S0      
317m3655            VIA   -    M      A01X+103421Y+035160X0200Y         S2      
017m3655            VIA   -    M      A18X+103421Y+035160X0260Y         S2      
017m3655                  -    MD0100PA00X+103421Y+035160                       
317m3655            VIA   -    MD0100PA00X+103972Y+056327X0200Y         S0      
317m3655            VIA   -    MD0100PA00X+072348Y+057489X0200Y         S0      
317m3655            VIA   -    MD0100PA00X+071469Y+047182X0180Y    R090 S0      
327m3655            U18   -G17        A01X+071623Y+047029X0160Y    R090 S1      
317m3656            J105  -N8   D0142PA00X+162500Y+167201X0302Y    R180 S3      
317m3656            VIA   -    M      A01X+164503Y+173076X0200Y         S2      
017m3656            VIA   -    M      A18X+164503Y+173076X0260Y         S2      
017m3656                  -    MD0100PA00X+164503Y+173076                       
327m3656            Q69   -2          A01X+166302Y+172947X0170Y0200R090 S1      
327m3656            R2828 -2   M      A01X+165451Y+173076X0198Y0197R270 S1      
327m3656            R2829 -1   M      A01X+165051Y+173076X0198Y0197R090 S1      
317m3657            VIA   -    M      A01X+164503Y+172576X0200Y         S2      
017m3657            VIA   -    M      A18X+164503Y+172576X0260Y         S2      
017m3657                  -    MD0100PA00X+164503Y+172576                       
327m3657            Q69   -3          A01X+166302Y+172691X0170Y0200R090 S1      
327m3657            R2919 -2   M      A01X+165051Y+172691X0198Y0197R090 S1      
327m3657            C1772 -1   M      A01X+165451Y+172691X0198Y0197R270 S1      
317m3657            VIA   -    MD0100PA00X+080225Y+050050X0200Y    R180 S0      
327m3657            R2847 -2          A01X+077823Y+049934X0198Y0197     S1      
327m3658            R2834 -2          A01X+167536Y+172683X0198Y0197R090 S1      
327m3658            VIA   -    M      A01X+167536Y+173203X0300Y    R270 S1      
327m3658            Q69   -5          A01X+167050Y+172947X0170Y0200R090 S1      
327m3658            Q69   -6   M      A01X+167050Y+173203X0170Y0200R090 S1      
327m3659            J41   -A53        A01X+055097Y+005354X0150Y0570R180 S1      
327m3659            R1798 -2          A18X+054992Y+003724X0198Y0197R270 S2      
317m3659            VIA   -    M      A01X+055097Y+004290X0200Y         S2      
017m3659            VIA   -    M      A18X+055097Y+004290X0260Y         S2      
017m3659                  -    MD0100PA00X+055097Y+004290                       
327ROM_SD_LS_OE     U53   -9          A01X+100863Y+053250X0140Y0630R090 S1      
317ROM_SD_LS_OE     VIA   -    M      A01X+101331Y+053250X0200Y    R270 S2      
017ROM_SD_LS_OE     VIA   -    M      A18X+101331Y+053250X0260Y    R270 S2      
017ROM_SD_LS_OE           -    MD0100PA00X+101331Y+053250                       
327ROM_SD_LS_OE     R1616 -2          A18X+076850Y+054344X0198Y0197R270 S2      
317ROM_SD_LS_OE     VIA   -    MD0100PA00X+076450Y+054586X0200Y         S0      
317ROM_LS_EN        VIA   -    MD0100PA00X+092673Y+054090X0200Y         S0      
317ROM_LS_EN        VIA   -    M      A01X+102563Y+054010X0200Y         S2      
017ROM_LS_EN        VIA   -    M      A18X+102563Y+054010X0260Y         S2      
017ROM_LS_EN              -    MD0100PA00X+102563Y+054010                       
327ROM_LS_EN        U54   -12         A01X+102752Y+054350X0070Y0280R180 S1      
327ROM_LS_EN        R1567 -2          A01X+075650Y+054029X0198Y0197R270 S1      
317ROM_LS_EN        VIA   -    MD0100PA00X+075786Y+053786X0200Y         S0      
327ROM_LS_EN        R1564 -2          A01X+076050Y+051094X0198Y0197R090 S1      
327m3660            J41   -B25        A01X+064751Y+006516X0150Y0570R180 S1      
327m3660            R80   -1          A01X+077602Y+030876X0198Y0197R180 S1      
327m3660            R73   -2   M      A01X+078597Y+030876X0198Y0197R180 S1      
317m3660            VIA   -    MD0100PA00X+077912Y+030876X0200Y         S0      
317m3660            VIA   -    M      A01X+086007Y+030485X0200Y         S2      
017m3660            VIA   -    M      A18X+086007Y+030485X0260Y         S2      
017m3660                  -    MD0100PA00X+086007Y+030485                       
327m3660            R3212 -2          A18X+085296Y+030885X0198Y0197R180 S2      
317m3660            VIA   -    MD0100PA00X+064420Y+008460X0200Y         S0      
327m3661            J41   -B24        A01X+064987Y+006516X0150Y0570R180 S1      
317m3661            VIA   -    M      A01X+064794Y+008380X0200Y         S2      
017m3661            VIA   -    M      A18X+064794Y+008380X0260Y         S2      
017m3661                  -    MD0100PA00X+064794Y+008380                       
327m3661            R72   -2   M      A01X+078605Y+030341X0198Y0197R180 S1      
327m3661            R79   -1          A01X+077610Y+030341X0198Y0197R180 S1      
317m3661            VIA   -    MD0100PA00X+077912Y+030341X0200Y         S0      
317m3661            VIA   -    MD0100PA00X+085548Y+029969X0200Y         S0      
327m3661            R3211 -2          A18X+085281Y+030154X0198Y0197R180 S2      
327m3662            J41   -B19        A01X+066168Y+006516X0150Y0570R180 S1      
317m3662            VIA   -    M      A01X+066159Y+006966X0200Y         S2      
017m3662            VIA   -    M      A18X+066159Y+006966X0260Y         S2      
017m3662                  -    MD0100PA00X+066159Y+006966                       
327m3662            R77   -1   M      A01X+077747Y+029928X0198Y0197     S1      
327m3662            R59   -2          A01X+076682Y+029928X0198Y0197     S1      
317m3662            VIA   -    MD0100PA00X+077747Y+029632X0200Y         S0      
327m3662            R3210 -2          A18X+079792Y+029549X0198Y0197     S2      
317m3662            VIA   -    MD0100PA00X+079911Y+029773X0200Y         S0      
327m3663            J41   -B20        A01X+065932Y+006516X0150Y0570R180 S1      
327m3663            R74   -2          A18X+080330Y+026862X0198Y0197     S2      
317m3663            VIA   -    M      A01X+080330Y+026585X0300Y         S1      
017m3663            VIA   -    M      A18X+080330Y+026585X0200Y         S1      
017m3663                  -    MD0100PA00X+080330Y+026585                       
317m3663            VIA   -    MD0100PA00X+065643Y+007543X0200Y         S0      
327m3663            R3213 -2          A18X+075430Y+027340X0198Y0197     S2      
317m3663            VIA   -    MD0100PA00X+075476Y+028101X0200Y         S0      
327m3663            R82   -1   M      A18X+075430Y+027740X0198Y0197     S2      
327m3664            J41   -B22        A01X+065460Y+006516X0150Y0570R180 S1      
327m3664            R84   -1          A18X+084691Y+029156X0198Y0197R180 S2      
327m3664            R76   -2   M      A18X+084693Y+028760X0198Y0197     S2      
317m3664            VIA   -    MD0100PA00X+084350Y+028760X0200Y         S0      
317m3664            VIA   -    M      A01X+065717Y+007913X0300Y         S1      
017m3664            VIA   -    M      A18X+065717Y+007913X0200Y         S1      
017m3664                  -    MD0100PA00X+065717Y+007913                       
327m3664            R3215 -2          A18X+081019Y+028431X0198Y0197R180 S2      
317m3664            VIA   -    MD0100PA00X+080433Y+028138X0200Y         S0      
327m3665            J41   -B21        A01X+065696Y+006516X0150Y0570R180 S1      
327m3665            R75   -2          A18X+085808Y+027356X0198Y0197R180 S2      
317m3665            VIA   -    MD0100PA00X+085383Y+026206X0200Y         S0      
327m3665            R83   -1   M      A18X+085853Y+026796X0198Y0197R090 S2      
327m3665            R3214 -2          A18X+081014Y+027682X0198Y0197R180 S2      
317m3665            VIA   -    M      A01X+081014Y+027410X0300Y         S1      
017m3665            VIA   -    M      A18X+081014Y+027410X0200Y         S1      
017m3665                  -    MD0100PA00X+081014Y+027410                       
317m3665            VIA   -    MD0100PA00X+065650Y+006966X0200Y         S0      
327m3666            J41   -B23        A01X+065223Y+006516X0150Y0570R180 S1      
327m3666            R87   -1          A01X+065382Y+008419X0198Y0197R090 S1      
317m3666            VIA   -    M      A01X+065085Y+007407X0200Y         S2      
017m3666            VIA   -    M      A18X+065085Y+007407X0260Y         S2      
017m3666                  -    MD0100PA00X+065085Y+007407                       
317m3667            VIA   -    M      A01X+010208Y+142783X0200Y         S2      
017m3667            VIA   -    M      A18X+010208Y+142783X0260Y         S2      
017m3667                  -    MD0100PA00X+010208Y+142783                       
327m3667            PU34  -20         A01X+010868Y+143114X0070Y0260R270 S1      
327m3667            C8362 -1          A01X+009908Y+142600X0198Y0197R180 S1      
327m3667            R8243 -2          A18X+009908Y+142150X0198Y0197R180 S2      
327m3667            R8242 -2   M      A18X+009908Y+142600X0198Y0197R180 S2      
327m3668            VIA   -    M      A18X+079505Y+036385X0260Y         S2      
317m3668            VIA   -    MD0100PA00X+077019Y+031256X0200Y         S0      
317m3668            VIA   -    MD0100PA00X+079568Y+035750X0200Y         S0      
317m3668            VIA   -    MD0100PA00X+078030Y+040354X0200Y         S0      
327m3668            R283  -1          A01X+077823Y+044734X0198Y0197R180 S1      
317m3668            VIA   -    MD0100PA00X+078088Y+044734X0200Y    R180 S0      
317m3668            VIA   -    MD0100PA00X+037844Y+044339X0200Y         S0      
327m3668            R8243 -1          A18X+009592Y+142150X0198Y0197R180 S2      
327m3668            C5006 -2   M      A18X+009008Y+142600X0198Y0197R180 S2      
317m3668            VIA   -    MD0100PA00X+008113Y+142420X0200Y         S0      
317m3669            VIA   -    M      A01X+120324Y+141744X0200Y         S2      
017m3669            VIA   -    M      A18X+120324Y+141744X0260Y         S2      
017m3669                  -    MD0100PA00X+120324Y+141744                       
327m3669            R8066 -2          A18X+120008Y+141000X0198Y0197R180 S2      
327m3669            R8065 -2   M      A18X+120008Y+141450X0198Y0197R180 S2      
327m3669            C8072 -1          A01X+120008Y+141450X0198Y0197R180 S1      
327m3669            PU12  -20         A01X+120968Y+141764X0070Y0260R270 S1      
317m3670            VIA   -    MD0100PA00X+116430Y+146330X0200Y         S0      
327m3670            R8066 -1          A18X+119692Y+141000X0198Y0197R180 S2      
327m3670            C5005 -2   M      A18X+119108Y+141450X0198Y0197R180 S2      
317m3670            VIA   -    MD0100PA00X+118800Y+141980X0200Y         S0      
317m3670            VIA   -    M      A01X+085152Y+041174X0200Y         S2      
017m3670            VIA   -    M      A18X+085152Y+041174X0260Y         S2      
017m3670                  -    MD0100PA00X+085152Y+041174                       
317m3670            VIA   -    MD0100PA00X+088440Y+143151X0200Y         S0      
317m3670            VIA   -    MD0100PA00X+091004Y+144054X0200Y         S0      
327m3670            R230  -1          A18X+077923Y+041134X0198Y0197     S2      
327m3671            VIA   -    M      A18X+035329Y+057851X0260Y    R180 S2      
327m3671            R8166 -2   M      A01X+035673Y+057442X0198Y0197     S1      
327m3671            R8165 -2          A01X+035673Y+057042X0198Y0197     S1      
327m3671            C8246 -1          A18X+035673Y+057442X0198Y0197     S2      
327m3671            PU25  -20         A18X+036534Y+057228X0070Y0260R270 S2      
317m3671            VIA   -    MD0100PA00X+035916Y+057442X0200Y    R180 S0      
327m3672            U18   -A17        A01X+069733Y+047029X0160Y    R090 S1      
317m3672            VIA   -    MD0100PA00X+069580Y+047182X0180Y    R090 S0      
317m3672            VIA   -    MD0100PA00X+055092Y+047518X0200Y         S0      
327m3672            C5019 -2   M      A01X+034816Y+057126X0198Y0197R270 S1      
327m3672            R8166 -1          A01X+035358Y+057442X0198Y0197     S1      
317m3672            VIA   -    M      A01X+037527Y+054219X0200Y    R180 S2      
017m3672            VIA   -    M      A18X+037527Y+054219X0260Y    R180 S2      
017m3672                  -    MD0100PA00X+037527Y+054219                       
327m3673            VIA   -    M      A18X+147411Y+056313X0160Y0041R315 S2      
327m3673            R8299 -2          A01X+146983Y+056498X0198Y0197     S1      
327m3673            R8298 -2          A01X+146983Y+056098X0198Y0197     S1      
327m3673            C465  -1          A18X+146983Y+056498X0198Y0197     S2      
327m3673            PU42  -20         A18X+147844Y+056284X0070Y0260R270 S2      
317m3673            VIA   -    MD0100PA00X+147226Y+056498X0200Y    R180 S0      
317m3674            VIA   -    M      A01X+145698Y+043736X0200Y         S2      
017m3674            VIA   -    M      A18X+145698Y+043736X0260Y         S2      
017m3674                  -    MD0100PA00X+145698Y+043736                       
327m3674            U18   -Y2         A01X+075717Y+042304X0160Y    R090 S1      
317m3674            VIA   -    MD0100PA00X+075871Y+042151X0180Y    R090 S0      
327m3674            C5018 -2   M      A01X+146183Y+056498X0198Y0197     S1      
327m3674            R8299 -1          A01X+146668Y+056498X0198Y0197     S1      
317m3675            VIA   -    M      A01X+010240Y+144000X0200Y         S2      
017m3675            VIA   -    M      A18X+010240Y+144000X0260Y         S2      
017m3675                  -    MD0100PA00X+010240Y+144000                       
327m3675            PU34  -16         A01X+010868Y+143744X0070Y0260R270 S1      
327m3675            R8233 -2          A18X+009900Y+144392X0198Y0197R090 S2      
327m3675            R8234 -2   M      A18X+009908Y+144000X0198Y0197R180 S2      
327m3675            C8360 -1          A01X+009908Y+144000X0198Y0197R180 S1      
317m3676            VIA   -    M      A01X+083800Y+042336X0200Y         S2      
017m3676            VIA   -    M      A18X+083800Y+042336X0260Y         S2      
017m3676                  -    MD0100PA00X+083800Y+042336                       
327m3676            R8234 -1          A18X+009592Y+144000X0198Y0197R180 S2      
327m3676            C5022 -2   M      A18X+009008Y+144000X0198Y0197R180 S2      
317m3676            VIA   -    MD0100PA00X+008140Y+143610X0200Y         S0      
317m3676            VIA   -    MD0100PA00X+037594Y+044339X0200Y         S0      
327m3676            R286  -1          A18X+077823Y+042734X0198Y0197     S2      
317m3676            VIA   -    MD0100PA00X+082934Y+035622X0200Y         S0      
317m3676            VIA   -    MD0100PA00X+082692Y+031184X0200Y         S0      
317m3677            VIA   -    M      A01X+120248Y+143247X0200Y         S2      
017m3677            VIA   -    M      A18X+120248Y+143247X0260Y         S2      
017m3677                  -    MD0100PA00X+120248Y+143247                       
327m3677            PU12  -16         A01X+120968Y+142394X0070Y0260R270 S1      
327m3677            C8070 -1   M      A01X+120008Y+143300X0198Y0197R180 S1      
327m3677            R8056 -2   M      A01X+119118Y+142850X0198Y0197     S1      
327m3677            R8057 -2          A01X+119118Y+143300X0198Y0197     S1      
317m3678            VIA   -    MD0100PA00X+116075Y+146325X0200Y         S0      
317m3678            VIA   -    MD0100PA00X+091327Y+144043X0200Y         S0      
317m3678            VIA   -           A01X+149568Y+047330X0200Y         S2      
017m3678            VIA   -           A18X+149568Y+047330X0260Y         S2      
017m3678                  -     D0100PA00X+149568Y+047330                       
327m3678            R233  -1          A18X+077923Y+040734X0198Y0197     S2      
317m3678            VIA   -    MD0100PA00X+085424Y+041291X0200Y         S0      
317m3678            VIA   -    MD0100PA00X+088636Y+142897X0200Y         S0      
327m3678            R8057 -1          A01X+118802Y+143300X0198Y0197     S1      
327m3678            C5004 -2   M      A01X+118418Y+143300X0198Y0197     S1      
317m3678            VIA   -    MD0100PA00X+118418Y+143560X0200Y         S0      
317m3679            VIA   -    M      A01X+036026Y+056104X0300Y    R180 S1      
017m3679            VIA   -    M      A18X+036026Y+056104X0200Y    R180 S1      
017m3679                  -    MD0100PA00X+036026Y+056104                       
327m3679            C248  -1          A18X+035673Y+055842X0198Y0197     S2      
327m3679            PU25  -16         A18X+036534Y+056598X0070Y0260R270 S2      
327m3679            R8167 -2          A01X+035358Y+055836X0198Y0197R090 S1      
327m3679            R8178 -2   M      A01X+035758Y+055836X0198Y0197R090 S1      
317m3680            VIA   -    MD0100PA00X+079628Y+042734X0200Y    R180 S0      
317m3680            VIA   -    M      A01X+037898Y+047923X0200Y         S2      
017m3680            VIA   -    M      A18X+037898Y+047923X0260Y         S2      
017m3680                  -    MD0100PA00X+037898Y+047923                       
317m3680            VIA   -    MD0100PA00X+059033Y+044502X0200Y         S0      
317m3680            VIA   -    MD0100PA00X+035510Y+054439X0200Y         S0      
327m3680            R8178 -1          A01X+035758Y+055522X0198Y0197R090 S1      
327m3680            C5003 -2   M      A01X+035918Y+055042X0198Y0197     S1      
327m3680            R209  -1          A01X+079268Y+042734X0198Y0197R180 S1      
327m3681            VIA   -    M      A18X+147378Y+055309X0160Y0041R045 S2      
327m3681            R8300 -2          A01X+146983Y+054498X0198Y0197     S1      
327m3681            R8311 -2   M      A01X+146983Y+054898X0198Y0197     S1      
327m3681            C467  -1          A18X+146983Y+054898X0198Y0197     S2      
327m3681            PU42  -16         A18X+147844Y+055654X0070Y0260R270 S2      
317m3681            VIA   -    MD0100PA00X+147226Y+055124X0200Y    R180 S0      
317m3682            VIA   -    M      A01X+146268Y+045037X0200Y         S2      
017m3682            VIA   -    M      A18X+146268Y+045037X0260Y         S2      
017m3682                  -    MD0100PA00X+146268Y+045037                       
327m3682            C5017 -2   M      A01X+146268Y+053783X0198Y0197R180 S1      
327m3682            R8311 -1          A01X+146668Y+054898X0198Y0197     S1      
317m3682            VIA   -    MD0100PA00X+075871Y+042466X0180Y    R090 S0      
327m3682            U18   -Y3         A01X+075717Y+042619X0160Y    R090 S1      
327m3683            R453  -2          A18X+079745Y+134592X0198Y0197R180 S2      
317m3683            VIA   -    M      A01X+086673Y+065074X0200Y         S2      
017m3683            VIA   -    M      A18X+086673Y+065074X0260Y         S2      
017m3683                  -    MD0100PA00X+086673Y+065074                       
327m3683            PU55  -9          A01X+079628Y+134786X0120Y0320R270 S1      
317m3683            VIA   -    MD0100PA00X+079907Y+135009X0200Y         S0      
317m3683            VIA   -    MD0100PA00X+073532Y+073674X0200Y         S0      
317m3683            VIA   -    MD0100PA00X+071212Y+068029X0200Y         S0      
327m3683            R225  -1          A01X+077823Y+042334X0198Y0197R180 S1      
317m3683            VIA   -    MD0100PA00X+078088Y+042334X0200Y    R180 S0      
317m3683            VIA   -    MD0100PA00X+077510Y+050250X0200Y         S0      
327m3684            VIA   -    M      A01X+080218Y+041836X0300Y         S1      
327m3684            C5016 -1   M      A01X+080650Y+042269X0198Y0197     S1      
327m3684            R259  -2          A01X+080646Y+042734X0198Y0197R180 S1      
327m3684            U18   -AA6        A01X+076032Y+043564X0160Y    R090 S1      
327m3685            PU3   -9          A01X+028170Y+059422X0120Y0320R180 S1      
327m3685            R8009 -2   M      A01X+029782Y+058603X0198Y0197R090 S1      
317m3685            VIA   -    M      A01X+030213Y+058416X0200Y         S2      
017m3685            VIA   -    M      A18X+030213Y+058416X0260Y         S2      
017m3685                  -    MD0100PA00X+030213Y+058416                       
317m3685            VIA   -    MD0100PA00X+055104Y+037308X0200Y         S0      
317m3685            VIA   -    MD0100PA00X+031175Y+044092X0200Y         S0      
317m3685            VIA   -    MD0100PA00X+082269Y+030515X0200Y         S0      
327m3685            R259  -1          A01X+080961Y+042734X0198Y0197R180 S1      
317m3685            VIA   -    MD0100PA00X+081325Y+042706X0200Y         S0      
327m3686            R177  -1          A01X+077823Y+043934X0198Y0197R180 S1      
317m3686            VIA   -    MD0100PA00X+078388Y+043544X0200Y    R180 S0      
317m3686            VIA   -    M      A01X+115104Y+050163X0300Y         S1      
017m3686            VIA   -    M      A18X+115104Y+050163X0200Y         S1      
017m3686                  -    MD0100PA00X+115104Y+050163                       
327m3686            R8465 -2   M      A01X+130722Y+053730X0198Y0197     S1      
327m3686            PU57  -9          A01X+131541Y+054792X0120Y0320R090 S1      
317m3687            VIA   -    M      A01X+062520Y+138346X0200Y    R180 S2      
017m3687            VIA   -    M      A18X+062520Y+138346X0260Y    R180 S2      
017m3687                  -    MD0100PA00X+062520Y+138346                       
327m3687            PU54  -12         A01X+062925Y+137777X0070Y0240R270 S1      
327m3687            R8380 -2          A01X+062235Y+138673X0198Y0197     S1      
327m3687            C8641 -1   M      A01X+062241Y+138286X0198Y0197R180 S1      
327m3687            R8385 -2          A18X+062520Y+138806X0198Y0197R180 S2      
317m3688            VIA   -    MD0100PA00X+077912Y+034175X0200Y         S0      
327m3688            R280  -1          A01X+077823Y+043134X0198Y0197R180 S1      
317m3688            VIA   -    MD0100PA00X+078388Y+042734X0200Y    R180 S0      
327m3688            R8385 -1          A18X+062204Y+138806X0198Y0197R180 S2      
327m3688            VIA   -    M      A18X+060924Y+138855X0260Y    R090 S2      
317m3688            VIA   -    MD0100PA00X+068129Y+141829X0200Y         S0      
317m3689            VIA   -    M      A01X+163523Y+143653X0200Y    R180 S2      
017m3689            VIA   -    M      A18X+163523Y+143653X0260Y    R180 S2      
017m3689                  -    MD0100PA00X+163523Y+143653                       
327m3689            R122  -2          A01X+163274Y+144402X0198Y0197     S1      
327m3689            R117  -2   M      A01X+163274Y+144002X0198Y0197     S1      
327m3689            C196  -1   M      A01X+163280Y+143615X0198Y0197R180 S1      
327m3689            PU21  -12         A01X+163983Y+143105X0070Y0240R270 S1      
317m3690            VIA   -    MD0100PA00X+079628Y+041934X0200Y    R180 S0      
317m3690            VIA   -    M      A01X+149739Y+046498X0200Y         S2      
017m3690            VIA   -    M      A18X+149739Y+046498X0260Y         S2      
017m3690                  -    MD0100PA00X+149739Y+046498                       
327m3690            R228  -1          A01X+079268Y+041934X0198Y0197R180 S1      
327m3690            R122  -1          A01X+162959Y+144402X0198Y0197     S1      
317m3690            VIA   -    MD0100PA00X+162517Y+144402X0200Y    R270 S0      
327m3691            J41   -A44        A01X+057223Y+005354X0150Y0570R180 S1      
327m3691            R1816 -2          A18X+057220Y+005261X0198Y0197R090 S2      
317m3691            VIA   -    M      A01X+057319Y+004291X0200Y         S2      
017m3691            VIA   -    M      A18X+057319Y+004291X0260Y         S2      
017m3691                  -    MD0100PA00X+057319Y+004291                       
327m3692            U326  -9          A01X+162154Y+054757X0120Y0320R090 S1      
327m3692            R2316 -1          A01X+161364Y+053872X0198Y0197R180 S1      
317m3692            VIA   -    M      A01X+161886Y+054282X0200Y    R270 S2      
017m3692            VIA   -    M      A18X+161886Y+054282X0260Y    R270 S2      
017m3692                  -    MD0100PA00X+161886Y+054282                       
327m3692            R2356 -2          A18X+162038Y+054736X0198Y0197R090 S2      
317PWRGD_P5V_AUX    VIA   -    MD0100PA00X+174240Y+048430X0200Y         S0      
317PWRGD_P5V_AUX    VIA   -    MD0100PA00X+158662Y+048430X0200Y         S0      
327PWRGD_P5V_AUX    R2316 -2          A01X+161049Y+053872X0198Y0197R180 S1      
327PWRGD_P5V_AUX    R2343 -2   M      A01X+159872Y+053123X0198Y0197R180 S1      
327PWRGD_P5V_AUX    Q50   -2   M      A01X+159041Y+053378X0170Y0200R270 S1      
327PWRGD_P5V_AUX    R1571 -1          A01X+177850Y+019080X0198Y0197     S1      
317PWRGD_P5V_AUX    VIA   -    M      A01X+177693Y+017905X0200Y    R180 S2      
017PWRGD_P5V_AUX    VIA   -    M      A18X+177693Y+017905X0260Y    R180 S2      
017PWRGD_P5V_AUX          -    MD0100PA00X+177693Y+017905                       
327PWRGD_P3V3_AUX   R6047 -1          A01X+079268Y+043134X0198Y0197R180 S1      
327PWRGD_P3V3_AUX   R6078 -1          A01X+080631Y+043134X0198Y0197     S1      
317PWRGD_P3V3_AUX   VIA   -    MD0100PA00X+079628Y+043134X0200Y         S0      
327PWRGD_P3V3_AUX   R6119 -1          A01X+085584Y+052441X0198Y0197R180 S1      
317PWRGD_P3V3_AUX   VIA   -    M      A01X+181883Y+017524X0200Y    R270 S2      
017PWRGD_P3V3_AUX   VIA   -    M      A18X+181883Y+017524X0260Y    R270 S2      
017PWRGD_P3V3_AUX         -    MD0100PA00X+181883Y+017524                       
327PWRGD_P3V3_AUX   C5015 -1          A18X+181420Y+017487X0198Y0197     S2      
327PWRGD_P3V3_AUX   R6099 -2          A01X+181171Y+017747X0198Y0197R270 S1      
317PWRGD_P3V3_AUX   VIA   -    MD0100PA00X+102815Y+035596X0200Y         S0      
317PWRGD_P3V3_AUX   VIA   -    MD0100PA00X+085584Y+051971X0200Y         S0      
317PWRGD_P3V3_AUX   VIA   -    MD0100PA00X+096204Y+051899X0200Y         S0      
327PWRGD_P1V8_AUX   R214  -1          A01X+084618Y+050711X0198Y0197     S1      
317PWRGD_P1V8_AUX   VIA   -    MD0100PA00X+057245Y+029947X0200Y         S0      
317PWRGD_P1V8_AUX   VIA   -    M      A01X+084185Y+050497X0300Y         S1      
017PWRGD_P1V8_AUX   VIA   -    M      A18X+084185Y+050497X0200Y         S1      
017PWRGD_P1V8_AUX         -    MD0100PA00X+084185Y+050497                       
327PWRGD_P1V8_AUX   R6243 -2          A01X+057411Y+029730X0198Y0197R090 S1      
327PWRGD_P1V8_AUX   PU6000-9          A01X+056816Y+030625X0100Y0360R090 S1      
327m3693            VIA   -           A18X+073761Y+050748X0260Y         S2      
327m3693            U18   -N20        A01X+073513Y+047974X0160Y    R090 S1      
317m3693            VIA   -    MD0100PA00X+073666Y+048127X0180Y    R090 S0      
317m3694            VIA   -    MD0080PA00X+032351Y+088281X0160Y    R180 S0      
327m3694            R203  -1          A18X+071134Y+052541X0198Y0197R090 S2      
327m3694            U26   -D69        A01X+032535Y+088386X0177Y    R180 S1      
317m3694            VIA   -    MD0100PA00X+028399Y+081134X0200Y    R180 S0      
327m3694            R1422 -2   M      A18X+070780Y+052564X0198Y0197R270 S2      
317m3694            VIA   -    MD0100PA00X+070850Y+052986X0200Y         S0      
317m3694            VIA   -    M      A01X+045708Y+051187X0200Y    R090 S2      
017m3694            VIA   -    M      A18X+045708Y+051187X0260Y    R090 S2      
017m3694                  -    MD0100PA00X+045708Y+051187                       
327m3694            U40   -1   M      A01X+032582Y+055240X0140Y0440     S1      
327m3694            U40   -3          A01X+033093Y+055240X0140Y0440     S1      
327m3694            R703  -1   M      A01X+032582Y+054552X0198Y0197     S1      
317m3694            VIA   -    MD0100PA00X+032582Y+054301X0200Y         S0      
327m3694            R557  -2          A18X+028533Y+080405X0198Y0197R180 S2      
317m3695            VIA   -    MD0080PA00X+129965Y+088281X0160Y    R180 S0      
327m3695            U25   -D69        A01X+130149Y+088386X0177Y    R180 S1      
327m3695            R443  -1          A18X+126068Y+080440X0198Y0197R090 S2      
317m3695            VIA   -    MD0100PA00X+126365Y+080912X0200Y    R180 S0      
317m3695            VIA   -    M      A01X+153969Y+054361X0200Y    R180 S2      
017m3695            VIA   -    M      A18X+153969Y+054361X0260Y    R180 S2      
017m3695                  -    MD0100PA00X+153969Y+054361                       
327m3695            R702  -1          A01X+153969Y+054119X0198Y0197R270 S1      
327m3695            U29   -3          A01X+154523Y+054734X0140Y0440     S1      
327m3695            U29   -1   M      A01X+154012Y+054734X0140Y0440     S1      
317m3695            VIA   -    MD0100PA00X+113539Y+061566X0200Y         S0      
317m3695            VIA   -    MD0100PA00X+103206Y+058726X0200Y         S0      
327m3695            R242  -1          A18X+070865Y+050092X0198Y0197R090 S2      
327m3695            R1422 -1          A18X+070780Y+052249X0198Y0197R270 S2      
317m3695            VIA   -    MD0100PA00X+070766Y+051338X0200Y    R180 S0      
317m3695            VIA   -    MD0100PA00X+071618Y+058556X0200Y         S0      
327m3696            VIA   -    M      A18X+078990Y+075226X0260Y         S2      
317m3696            VIA   -    MD0100PA00X+079131Y+076352X0190Y         S0      
327m3696            R314  -1          A18X+079432Y+075176X0198Y0197R180 S2      
327m3696            R115  -2          A18X+079726Y+076376X0198Y0197     S2      
327m3696            J37   -147        A01X+079586Y+076352X0205Y0590R090 S1      
327m3697            VIA   -    M      A18X+176530Y+075226X0260Y         S2      
317m3697            VIA   -    MD0100PA00X+176745Y+076352X0190Y         S0      
327m3697            R302  -1          A18X+176973Y+075326X0198Y0197R180 S2      
327m3697            R101  -2          A18X+177340Y+076376X0198Y0197     S2      
327m3697            J67   -147        A01X+177200Y+076352X0205Y0590R090 S1      
317m3698            VIA   -    MD0100PA00X+076161Y+076352X0190Y         S0      
327m3698            VIA   -    M      A18X+076049Y+075227X0260Y         S2      
327m3698            R313  -1          A18X+075606Y+075127X0198Y0197     S2      
327m3698            R114  -2          A18X+076756Y+076377X0198Y0197     S2      
327m3698            J99   -147        A01X+076616Y+076352X0205Y0590R090 S1      
327m3699            VIA   -    M      A18X+173480Y+075226X0260Y         S2      
317m3699            VIA   -    MD0100PA00X+173775Y+076352X0190Y         S0      
327m3699            R301  -1          A18X+173973Y+075276X0198Y0197R180 S2      
327m3699            R100  -2          A18X+174370Y+076376X0198Y0197     S2      
327m3699            J20   -147        A01X+174230Y+076352X0205Y0590R090 S1      
317m3700            VIA   -    MD0100PA00X+073191Y+076352X0190Y         S0      
327m3700            VIA   -    M      A18X+072949Y+075227X0260Y         S2      
327m3700            R312  -1          A18X+073392Y+075177X0198Y0197R180 S2      
327m3700            R113  -2          A18X+073786Y+076377X0198Y0197     S2      
327m3700            J29   -147        A01X+073646Y+076352X0205Y0590R090 S1      
327m3701            VIA   -    M      A18X+170580Y+075226X0260Y         S2      
317m3701            VIA   -    MD0100PA00X+170805Y+076352X0190Y         S0      
327m3701            R300  -1          A18X+171023Y+075276X0198Y0197R180 S2      
327m3701            R99   -2          A18X+171400Y+076376X0198Y0197     S2      
327m3701            J68   -147        A01X+171260Y+076352X0205Y0590R090 S1      
317m3702            VIA   -    MD0100PA00X+070221Y+076352X0190Y         S0      
327m3702            VIA   -    M      A18X+069999Y+075227X0260Y         S2      
327m3702            R311  -1          A18X+070442Y+075177X0198Y0197R180 S2      
327m3702            R112  -2          A18X+070816Y+076377X0198Y0197     S2      
327m3702            J100  -147        A01X+070676Y+076352X0205Y0590R090 S1      
327m3703            VIA   -    M      A18X+167680Y+075226X0260Y         S2      
317m3703            VIA   -    MD0100PA00X+167835Y+076352X0190Y         S0      
327m3703            R299  -1          A18X+168173Y+075326X0198Y0197R180 S2      
327m3703            R98   -2          A18X+168430Y+076376X0198Y0197     S2      
327m3703            J18   -147        A01X+168290Y+076352X0205Y0590R090 S1      
317m3704            VIA   -    MD0100PA00X+067250Y+076352X0190Y         S0      
327m3704            VIA   -    M      A18X+067049Y+075227X0260Y         S2      
327m3704            R310  -1          A18X+067492Y+075177X0198Y0197R180 S2      
327m3704            R111  -2          A18X+067846Y+076377X0198Y0197     S2      
327m3704            J27   -147        A01X+067706Y+076352X0205Y0590R090 S1      
327m3705            VIA   -    M      A18X+164630Y+075226X0260Y         S2      
317m3705            VIA   -    MD0100PA00X+164865Y+076352X0190Y         S0      
327m3705            R298  -1          A18X+165073Y+075326X0198Y0197R180 S2      
327m3705            R97   -2          A18X+165460Y+076376X0198Y0197     S2      
327m3705            J69   -147        A01X+165320Y+076352X0205Y0590R090 S1      
317m3706            VIA   -    MD0100PA00X+064280Y+076352X0190Y         S0      
327m3706            VIA   -    M      A18X+064099Y+075077X0260Y         S2      
327m3706            R1184 -1          A18X+064542Y+075127X0198Y0197R180 S2      
327m3706            R110  -2          A18X+064876Y+076377X0198Y0197     S2      
327m3706            J102  -147        A01X+064735Y+076352X0205Y0590R090 S1      
327m3707            VIA   -    M      A18X+161680Y+075226X0260Y         S2      
317m3707            VIA   -    MD0100PA00X+161895Y+076352X0190Y         S0      
327m3707            R297  -1          A18X+162123Y+075276X0198Y0197R180 S2      
327m3707            R96   -2          A18X+162490Y+076376X0198Y0197     S2      
327m3707            J16   -147        A01X+162350Y+076352X0205Y0590R090 S1      
327m3708            R8040 -2   M      A01X+077508Y+036400X0198Y0197     S1      
327m3708            R8089 -1          A01X+077892Y+036400X0198Y0197     S1      
317m3708            VIA   -    MD0100PA00X+074939Y+036082X0200Y         S0      
327m3708            VIA   -    M      A18X+071592Y+075111X0260Y         S2      
327m3708            R109  -2   M      A18X+065292Y+075127X0198Y0197     S2      
327m3708            R1184 -2          A18X+064856Y+075127X0198Y0197R180 S2      
327m3708            R310  -2   M      A18X+067806Y+075177X0198Y0197R180 S2      
327m3708            R311  -2   M      A18X+070756Y+075177X0198Y0197R180 S2      
327m3708            R312  -2   M      A18X+073706Y+075177X0198Y0197R180 S2      
327m3708            R313  -2   M      A18X+075292Y+075127X0198Y0197     S2      
327m3708            R314  -2          A18X+079747Y+075176X0198Y0197R180 S2      
317m3708            VIA   -    MD0100PA00X+067329Y+073316X0200Y         S0      
317m3708            VIA   -    MD0100PA00X+062413Y+034652X0200Y         S0      
317m3708            VIA   -    MD0100PA00X+075134Y+034385X0200Y         S0      
317m3708            VIA   -    MD0100PA00X+063591Y+049796X0200Y         S0      
317m3708            VIA   -    MD0100PA00X+068651Y+067744X0200Y         S0      
327m3709            R8038 -2   M      A01X+081242Y+039250X0198Y0197R180 S1      
327m3709            R8083 -1          A01X+080858Y+039250X0198Y0197R180 S1      
317m3709            VIA   -    MD0100PA00X+084181Y+042322X0200Y         S0      
327m3709            VIA   -    M      A18X+168989Y+075167X0260Y         S2      
317m3709            VIA   -    MD0100PA00X+177699Y+074902X0200Y         S0      
317m3709            VIA   -    MD0100PA00X+108173Y+050917X0200Y         S0      
317m3709            VIA   -    MD0100PA00X+105745Y+050924X0200Y         S0      
327m3709            R297  -2          A18X+162438Y+075276X0198Y0197R180 S2      
327m3709            R95   -2   M      A18X+162873Y+075276X0198Y0197     S2      
327m3709            R298  -2   M      A18X+165388Y+075326X0198Y0197R180 S2      
327m3709            R299  -2   M      A18X+168488Y+075326X0198Y0197R180 S2      
327m3709            R300  -2   M      A18X+171338Y+075276X0198Y0197R180 S2      
327m3709            R301  -2   M      A18X+174288Y+075276X0198Y0197R180 S2      
327m3709            R302  -2   M      A18X+177288Y+075326X0198Y0197R180 S2      
317m3710            VIA   -    M      A01X+005644Y+076618X0200Y         S2      
017m3710            VIA   -    M      A18X+005644Y+076618X0260Y         S2      
017m3710                  -    MD0100PA00X+005644Y+076618                       
327m3710            R108  -2          A18X+005550Y+075891X0198Y0197R270 S2      
327m3710            R1183 -1   M      A18X+005950Y+075891X0198Y0197R090 S2      
327m3710            J33   -147        A01X+006932Y+076352X0205Y0590R090 S1      
327m3711            VIA   -    M      A18X+103880Y+075176X0260Y         S2      
317m3711            VIA   -    MD0100PA00X+104092Y+076352X0190Y         S0      
327m3711            R94   -2          A18X+104686Y+076376X0198Y0197     S2      
327m3711            R296  -1          A18X+104373Y+075126X0198Y0197R180 S2      
327m3711            J23   -147        A01X+104546Y+076352X0205Y0590R090 S1      
317m3712            VIA   -    MD0100PA00X+009447Y+076352X0190Y         S0      
327m3712            VIA   -    M      A18X+009216Y+075050X0260Y         S2      
327m3712            R307  -1          A18X+009808Y+075177X0198Y0197R180 S2      
327m3712            R107  -2          A18X+010048Y+076377X0198Y0197     S2      
327m3712            J32   -147        A01X+009902Y+076352X0205Y0590R090 S1      
327m3713            VIA   -    M      A18X+106880Y+075176X0260Y         S2      
317m3713            VIA   -    MD0100PA00X+107062Y+076352X0190Y         S0      
327m3713            R295  -1          A18X+107423Y+075176X0198Y0197R180 S2      
327m3713            R93   -2          A18X+107657Y+076376X0198Y0197     S2      
327m3713            J21   -147        A01X+107517Y+076352X0205Y0590R090 S1      
327m3714            VIA   -    M      A18X+012216Y+075027X0260Y         S2      
317m3714            VIA   -    MD0100PA00X+012417Y+076352X0190Y         S0      
327m3714            R306  -1          A18X+012658Y+075177X0198Y0197R180 S2      
327m3714            R106  -2          A18X+013019Y+076377X0198Y0197     S2      
327m3714            J30   -147        A01X+012872Y+076352X0205Y0590R090 S1      
327m3715            VIA   -    M      A18X+109830Y+075226X0260Y         S2      
317m3715            VIA   -    MD0100PA00X+110032Y+076352X0190Y         S0      
327m3715            R294  -1          A18X+110273Y+075176X0198Y0197R180 S2      
327m3715            R92   -2          A18X+110627Y+076376X0198Y0197     S2      
327m3715            J19   -147        A01X+110487Y+076352X0205Y0590R090 S1      
327m3716            VIA   -    M      A18X+015166Y+074977X0260Y         S2      
317m3716            VIA   -    MD0100PA00X+015388Y+076352X0190Y         S0      
327m3716            R305  -1          A18X+015608Y+075177X0198Y0197R180 S2      
327m3716            R105  -2          A18X+015982Y+076377X0198Y0197     S2      
327m3716            J28   -147        A01X+015842Y+076352X0205Y0590R090 S1      
327m3717            VIA   -    M      A18X+112780Y+075226X0260Y         S2      
317m3717            VIA   -    MD0100PA00X+113002Y+076352X0190Y         S0      
327m3717            R91   -2          A18X+113597Y+076376X0198Y0197     S2      
327m3717            R293  -1          A18X+113223Y+075176X0198Y0197R180 S2      
327m3717            J17   -147        A01X+113457Y+076352X0205Y0590R090 S1      
317m3718            VIA   -    MD0100PA00X+018358Y+076352X0190Y         S0      
327m3718            VIA   -    M      A18X+018116Y+075077X0260Y         S2      
327m3718            R304  -1          A18X+018558Y+075177X0198Y0197R180 S2      
327m3718            R104  -2          A18X+018959Y+076377X0198Y0197     S2      
327m3718            J26   -147        A01X+018813Y+076352X0205Y0590R090 S1      
327m3719            VIA   -    M      A18X+115730Y+075226X0260Y         S2      
317m3719            VIA   -    MD0100PA00X+115972Y+076352X0190Y         S0      
327m3719            R292  -1          A18X+116173Y+075176X0198Y0197R180 S2      
327m3719            R90   -2          A18X+116567Y+076376X0198Y0197     S2      
327m3719            J15   -147        A01X+116427Y+076352X0205Y0590R090 S1      
317m3720            VIA   -    MD0100PA00X+021328Y+076352X0190Y    R180 S0      
327m3720            VIA   -    M      A18X+021240Y+075020X0260Y         S2      
327m3720            R303  -1          A18X+020773Y+075127X0198Y0197     S2      
327m3720            R103  -2          A18X+021919Y+076377X0198Y0197     S2      
327m3720            J24   -147        A01X+021783Y+076352X0205Y0590R090 S1      
327m3721            VIA   -    M      A18X+118830Y+075226X0260Y         S2      
317m3721            VIA   -    MD0100PA00X+118942Y+076352X0190Y         S0      
327m3721            R291  -1          A18X+118388Y+075126X0198Y0197     S2      
327m3721            R89   -2          A18X+119537Y+076376X0198Y0197     S2      
327m3721            J1    -147        A01X+119397Y+076352X0205Y0590R090 S1      
327m3722            R8039 -2   M      A01X+057308Y+047550X0198Y0197     S1      
327m3722            R8086 -1          A01X+057692Y+047550X0198Y0197     S1      
317m3722            VIA   -    MD0100PA00X+056089Y+048466X0200Y         S0      
317m3722            VIA   -    MD0100PA00X+020625Y+073254X0200Y         S0      
317m3722            VIA   -    MD0100PA00X+034034Y+049646X0200Y         S0      
327m3722            VIA   -    M      A18X+006488Y+074877X0260Y         S2      
327m3722            R1183 -2          A18X+005950Y+075576X0198Y0197R090 S2      
327m3722            R307  -2   M      A18X+010123Y+075177X0198Y0197R180 S2      
327m3722            R306  -2   M      A18X+012973Y+075177X0198Y0197R180 S2      
327m3722            R305  -2   M      A18X+015923Y+075177X0198Y0197R180 S2      
327m3722            R304  -2   M      A18X+018873Y+075177X0198Y0197R180 S2      
327m3722            R102  -2   M      A18X+020073Y+075127X0198Y0197R180 S2      
327m3722            R303  -2   M      A18X+020458Y+075127X0198Y0197     S2      
327m3723            R8037 -2   M      A01X+082692Y+040950X0198Y0197R180 S1      
327m3723            R8080 -1          A01X+082308Y+040950X0198Y0197R180 S1      
317m3723            VIA   -    MD0100PA00X+083850Y+040950X0200Y         S0      
317m3723            VIA   -    MD0100PA00X+106838Y+073680X0200Y         S0      
327m3723            R296  -2   M      A18X+104688Y+075126X0198Y0197R180 S2      
327m3723            R295  -2   M      A18X+107738Y+075176X0198Y0197R180 S2      
327m3723            R294  -2   M      A18X+110588Y+075176X0198Y0197R180 S2      
327m3723            R293  -2   M      A18X+113538Y+075176X0198Y0197R180 S2      
327m3723            R292  -2   M      A18X+116488Y+075176X0198Y0197R180 S2      
327m3723            R88   -2   M      A18X+117688Y+075126X0198Y0197R180 S2      
327m3723            R291  -2          A18X+118073Y+075126X0198Y0197     S2      
317m3723            VIA   -    M      A01X+107223Y+066775X0200Y         S2      
017m3723            VIA   -    M      A18X+107223Y+066775X0260Y         S2      
017m3723                  -    MD0100PA00X+107223Y+066775                       
327PVDD_33_S5_VCC   R453  -1          A18X+079430Y+134592X0198Y0197R180 S2      
327PVDD_33_S5_VCC   PU55  -19         A01X+078525Y+133447X0120Y0320R090 S1      
317PVDD_33_S5_VCC   VIA   -    M      A01X+078212Y+133417X0200Y    R090 S2      
017PVDD_33_S5_VCC   VIA   -    M      A18X+078212Y+133417X0260Y    R090 S2      
017PVDD_33_S5_VCC         -    MD0100PA00X+078212Y+133417                       
327PVDD_33_S5_VCC   PC118 -1          A01X+077945Y+133418X0198Y0197R090 S1      
327PVDD_33_S5_REF   PC127 -1          A01X+080429Y+134076X0198Y0197     S1      
327PVDD_33_S5_REF   PU55  -5          A01X+079628Y+134116X0070Y0320R270 S1      
327PVDD_33_S5_FB    PR454 -1   M      A01X+080446Y+134833X0198Y0197R270 S1      
327PVDD_33_S5_FB    PU55  -7          A01X+079628Y+134431X0070Y0320R270 S1      
327PVDD_33_S5_FB    PC132 -1          A01X+081253Y+134833X0198Y0197R270 S1      
327PVDD_33_S5_FB    PR455 -1   M      A01X+080853Y+134833X0198Y0197R270 S1      
327PVDD_33_S5_CS    PR452 -1          A01X+080429Y+133633X0198Y0197     S1      
327PVDD_33_S5_CS    PU55  -3          A01X+079628Y+133801X0070Y0320R270 S1      
317PVDD_33_S5       VIA   -    MD0080PA00X+038945Y+105038X0160Y         S0      
317PVDD_33_S5       VIA   -    MD0080PA00X+039130Y+105357X0160Y         S0      
317PVDD_33_S5       VIA   -    MD0080PA00X+136560Y+105038X0160Y         S0      
317PVDD_33_S5       VIA   -    MD0080PA00X+136744Y+105357X0160Y         S0      
317PVDD_33_S5       VIA   -    MD0100PA00X+086204Y+124969X0200Y         S0      
327PVDD_33_S5       U26   -BP51       A01X+039314Y+105252X0177Y    R180 S1      
327PVDD_33_S5       C2662 -1          A18X+039119Y+105327X0198Y0197     S2      
327PVDD_33_S5       U26   -BN52       A01X+039129Y+104933X0177Y    R180 S1      
327PVDD_33_S5       C2659 -1          A18X+038919Y+104977X0198Y0197     S2      
327PVDD_33_S5       U25   -BN52       A01X+136743Y+104933X0177Y    R180 S1      
327PVDD_33_S5       C2515 -1          A18X+136588Y+104976X0198Y0197     S2      
327PVDD_33_S5       U25   -BP51       A01X+136928Y+105252X0177Y    R180 S1      
327PVDD_33_S5       C2512 -1          A18X+136738Y+105326X0198Y0197     S2      
327PVDD_33_S5       PC130 -1          A18X+080328Y+129976X0400Y0500R090 S2      
327PVDD_33_S5       PC134 -1          A18X+079528Y+129976X0400Y0500R090 S2      
327PVDD_33_S5       PC129 -1          A18X+078728Y+129976X0400Y0500R090 S2      
327PVDD_33_S5       PC135 -1          A18X+077928Y+129976X0400Y0500R090 S2      
327PVDD_33_S5       PC136 -1          A01X+080767Y+130164X0198Y0197R090 S1      
327PVDD_33_S5       PL72  -2          A01X+079128Y+129798X0848Y1300R270 S1      
317PVDD_33_S5       VIA   -    MD0100PA00X+079928Y+130101X0200Y    R180 S0      
317PVDD_33_S5       VIA   -    MD0100PA00X+079928Y+129851X0200Y    R180 S0      
317PVDD_33_S5       VIA   -    MD0100PA00X+080760Y+129924X0200Y    R180 S0      
317PVDD_33_S5       VIA   -    MD0100PA00X+080453Y+129626X0200Y    R180 S0      
317PVDD_33_S5       VIA   -    MD0100PA00X+080203Y+129626X0200Y    R180 S0      
317PVDD_33_S5       VIA   -    MD0100PA00X+079928Y+129601X0200Y    R180 S0      
317PVDD_33_S5       VIA   -    M      A01X+079602Y+129216X0200Y    R180 S2      
017PVDD_33_S5       VIA   -    M      A18X+079602Y+129216X0260Y    R180 S2      
017PVDD_33_S5             -    MD0100PA00X+079602Y+129216                       
317PVDD_33_S5       VIA   -    MD0100PA00X+079252Y+129216X0200Y    R180 S0      
317PVDD_33_S5       VIA   -    MD0100PA00X+078902Y+129216X0200Y    R180 S0      
317PVDD_33_S5       VIA   -    M      A01X+078552Y+129216X0200Y    R180 S2      
017PVDD_33_S5       VIA   -    M      A18X+078552Y+129216X0260Y    R180 S2      
017PVDD_33_S5             -    MD0100PA00X+078552Y+129216                       
317PVDD_33_S5       VIA   -    MD0100PA00X+078328Y+130101X0200Y    R180 S0      
317PVDD_33_S5       VIA   -    MD0100PA00X+078328Y+129851X0200Y    R180 S0      
317PVDD_33_S5       VIA   -    MD0100PA00X+078053Y+129626X0200Y    R180 S0      
317PVDD_33_S5       VIA   -    MD0100PA00X+077803Y+129626X0200Y    R180 S0      
317PVDD_33_S5       VIA   -    MD0100PA00X+078328Y+129601X0200Y    R180 S0      
317PVDD_33_S5       VIA   -    MD0100PA00X+103646Y+127895X0200Y    R180 S0      
317PVDD_33_S5       VIA   -    MD0100PA00X+103641Y+127566X0200Y    R180 S0      
317PVDD_33_S5       VIA   -    MD0100PA00X+103318Y+127600X0200Y    R180 S0      
317PVDD_33_S5       VIA   -    MD0100PA00X+103324Y+127929X0200Y    R180 S0      
317PVDD_33_S5       VIA   -    MD0100PA00X+104265Y+127915X0200Y    R180 S0      
317PVDD_33_S5       VIA   -    MD0100PA00X+104286Y+127555X0200Y    R180 S0      
317PVDD_33_S5       VIA   -    MD0100PA00X+103960Y+127876X0200Y    R180 S0      
317PVDD_33_S5       VIA   -    MD0100PA00X+103955Y+127547X0200Y    R180 S0      
327PVDD_33_S5       PR455 -2          A01X+080853Y+134518X0198Y0197R270 S1      
327PVDD_33_S5       PC132 -2   M      A01X+081253Y+134518X0198Y0197R270 S1      
327PVDD_33_S5       R1235 -1          A18X+093823Y+128616X0198Y0197     S2      
317PVDD_33_S5       VIA   -    MD0100PA00X+094108Y+128616X0200Y         S0      
317PVDDIO_P1_VOS4   VIA   -    MD0100PA00X+010187Y+137641X0200Y         S0      
327PVDDIO_P1_VOS4   PR375 -1          A18X+009819Y+137396X0198Y0197R270 S2      
327PVDDIO_P1_VOS4   PU53  -1          A01X+010315Y+137400X0090Y0240R090 S1      
317PVDDIO_P1_VOS3   VIA   -    MD0100PA00X+013447Y+137641X0200Y         S0      
327PVDDIO_P1_VOS3   PR374 -1          A18X+013079Y+137396X0198Y0197R270 S2      
327PVDDIO_P1_VOS3   PU52  -1          A01X+013575Y+137400X0090Y0240R090 S1      
317PVDDIO_P1_VOS2   VIA   -    MD0100PA00X+016717Y+137641X0200Y         S0      
327PVDDIO_P1_VOS2   PR281 -1          A18X+016349Y+137396X0198Y0197R270 S2      
327PVDDIO_P1_VOS2   PU40  -1          A01X+016845Y+137400X0090Y0240R090 S1      
317PVDDIO_P1_VOS1   VIA   -    MD0100PA00X+020007Y+137641X0200Y         S0      
327PVDDIO_P1_VOS1   PR280 -1          A18X+019639Y+137396X0198Y0197R270 S2      
327PVDDIO_P1_VOS1   PU39  -1          A01X+020135Y+137400X0090Y0240R090 S1      
327PVDDIO_P1_VCC4   PU53  -35         A01X+011185Y+137646X0090Y0240     S1      
317PVDDIO_P1_VCC4   VIA   -    MD0100PA00X+011156Y+137956X0200Y         S0      
327PVDDIO_P1_VCC4   VIA   -    M      A18X+010530Y+137595X0260Y    R180 S2      
327PVDDIO_P1_VCC4   PR370 -2   M      A18X+010350Y+137079X0198Y0197R270 S2      
317PVDDIO_P1_VCC4   VIA   -    MD0100PA00X+009810Y+137156X0200Y         S0      
327PVDDIO_P1_VCC4   PU53  -3          A01X+010315Y+137046X0090Y0240R090 S1      
327PVDDIO_P1_VCC4   PC616 -1          A01X+009810Y+137396X0198Y0197R090 S1      
327PVDDIO_P1_VCC3   VIA   -    M      A18X+013790Y+137595X0260Y    R180 S2      
327PVDDIO_P1_VCC3   PU52  -35         A01X+014445Y+137646X0090Y0240     S1      
317PVDDIO_P1_VCC3   VIA   -    MD0100PA00X+014416Y+137956X0200Y         S0      
327PVDDIO_P1_VCC3   PR371 -2   M      A18X+013610Y+137079X0198Y0197R270 S2      
317PVDDIO_P1_VCC3   VIA   -    MD0100PA00X+013070Y+137156X0200Y         S0      
327PVDDIO_P1_VCC3   PU52  -3          A01X+013575Y+137046X0090Y0240R090 S1      
327PVDDIO_P1_VCC3   PC617 -1          A01X+013070Y+137396X0198Y0197R090 S1      
327PVDDIO_P1_VCC2   VIA   -    M      A18X+017060Y+137595X0260Y    R180 S2      
327PVDDIO_P1_VCC2   PU40  -35         A01X+017715Y+137646X0090Y0240     S1      
317PVDDIO_P1_VCC2   VIA   -    MD0100PA00X+017686Y+137956X0200Y         S0      
327PVDDIO_P1_VCC2   PR276 -2   M      A18X+016880Y+137079X0198Y0197R270 S2      
317PVDDIO_P1_VCC2   VIA   -    MD0100PA00X+016340Y+137156X0200Y         S0      
327PVDDIO_P1_VCC2   PC432 -1          A01X+016340Y+137396X0198Y0197R090 S1      
327PVDDIO_P1_VCC2   PU40  -3          A01X+016845Y+137046X0090Y0240R090 S1      
327PVDDIO_P1_VCC1   VIA   -    M      A18X+020350Y+137595X0260Y    R180 S2      
327PVDDIO_P1_VCC1   PU39  -35         A01X+021005Y+137646X0090Y0240     S1      
317PVDDIO_P1_VCC1   VIA   -    MD0100PA00X+020976Y+137956X0200Y         S0      
327PVDDIO_P1_VCC1   PR277 -2   M      A18X+020170Y+137079X0198Y0197R270 S2      
317PVDDIO_P1_VCC1   VIA   -    MD0100PA00X+019630Y+137156X0200Y         S0      
327PVDDIO_P1_VCC1   PC433 -1          A01X+019630Y+137396X0198Y0197R090 S1      
327PVDDIO_P1_VCC1   PU39  -3          A01X+020135Y+137046X0090Y0240R090 S1      
327m3724            PC367 -1          A01X+014492Y+142950X0198Y0197     S1      
327m3724            PU34  -43         A01X+013132Y+143429X0070Y0260R270 S1      
317m3724            VIA   -    MD0100PA00X+014150Y+142950X0200Y         S0      
327m3724            PU53  -36         A01X+011008Y+137646X0090Y0240     S1      
317m3724            VIA   -    MD0100PA00X+010882Y+138053X0200Y         S2      
327m3724            PU39  -36         A01X+020828Y+137646X0090Y0240     S1      
317m3724            VIA   -    MD0100PA00X+020702Y+138053X0200Y         S0      
317m3724            VIA   -    MD0100PA00X+017412Y+138053X0200Y         S0      
327m3724            PU40  -36         A01X+017538Y+137646X0090Y0240     S1      
317m3724            VIA   -    MD0100PA00X+014142Y+138053X0200Y         S0      
327m3724            PU52  -36         A01X+014268Y+137646X0090Y0240     S1      
317PVDDIO_P1_PWM4   VIA   -    M      A01X+011210Y+146750X0200Y         S2      
017PVDDIO_P1_PWM4   VIA   -    M      A18X+011210Y+146750X0260Y         S2      
017PVDDIO_P1_PWM4         -    MD0100PA00X+011210Y+146750                       
327PVDDIO_P1_PWM4   PU53  -34         A01X+011362Y+137646X0090Y0240     S1      
317PVDDIO_P1_PWM4   VIA   -    MD0100PA00X+011230Y+138213X0200Y         S0      
327PVDDIO_P1_PWM4   PU34  -4          A01X+012394Y+144482X0070Y0260R180 S1      
317PVDDIO_P1_PWM3   VIA   -    M      A01X+012150Y+146740X0300Y         S1      
017PVDDIO_P1_PWM3   VIA   -    M      A18X+012150Y+146740X0200Y         S1      
017PVDDIO_P1_PWM3         -    MD0100PA00X+012150Y+146740                       
327PVDDIO_P1_PWM3   PU34  -3          A01X+012551Y+144482X0070Y0260R180 S1      
327PVDDIO_P1_PWM3   PU52  -34         A01X+014622Y+137646X0090Y0240     S1      
317PVDDIO_P1_PWM3   VIA   -    MD0100PA00X+014490Y+138213X0200Y         S0      
317PVDDIO_P1_PWM2   VIA   -    MD0100PA00X+017760Y+138213X0200Y         S0      
327PVDDIO_P1_PWM2   PU40  -34         A01X+017892Y+137646X0090Y0240     S1      
317PVDDIO_P1_PWM2   VIA   -    MD0100PA00X+012460Y+146510X0200Y         S0      
327PVDDIO_P1_PWM2   PU34  -2          A01X+012709Y+144482X0070Y0260R180 S1      
317PVDDIO_P1_PWM1   VIA   -    MD0100PA00X+021050Y+138213X0200Y         S0      
327PVDDIO_P1_PWM1   PU39  -34         A01X+021182Y+137646X0090Y0240     S1      
317PVDDIO_P1_PWM1   VIA   -    MD0100PA00X+012866Y+146400X0200Y         S0      
327PVDDIO_P1_PWM1   PU34  -1          A01X+012866Y+144482X0070Y0260R180 S1      
327m3725            VIA   -    M      A01X+010684Y+138114X0160Y0041R090 S1      
327m3725            PR368 -1          A01X+010589Y+138556X0198Y0197     S1      
327m3725            PU53  -37         A01X+010831Y+137646X0090Y0240     S1      
327m3726            VIA   -    M      A01X+013944Y+138114X0160Y0041R090 S1      
327m3726            PU52  -37         A01X+014091Y+137646X0090Y0240     S1      
327m3726            PR369 -1          A01X+013849Y+138556X0198Y0197     S1      
327m3727            VIA   -    M      A01X+017214Y+138125X0160Y0041R090 S1      
327m3727            PR274 -1          A01X+017119Y+138556X0198Y0197     S1      
327m3727            PU40  -37         A01X+017361Y+137646X0090Y0240     S1      
327m3728            VIA   -    M      A01X+020504Y+138114X0160Y0041R090 S1      
327m3728            PU39  -37         A01X+020651Y+137646X0090Y0240     S1      
327m3728            PR275 -1          A01X+020409Y+138556X0198Y0197     S1      
317m3729            VIA   -    M      A01X+012470Y+140100X0300Y         S1      
017m3729            VIA   -    M      A18X+012470Y+140100X0200Y         S1      
017m3729                  -    MD0100PA00X+012470Y+140100                       
317m3729            VIA   -    MD0100PA00X+010486Y+138008X0200Y    R180 S0      
327m3729            PU53  -38         A01X+010654Y+137646X0090Y0240     S1      
327m3729            PU34  -35         A01X+012709Y+142218X0070Y0260R180 S1      
317m3730            VIA   -    M      A01X+012920Y+140100X0200Y         S2      
017m3730            VIA   -    M      A18X+012920Y+140100X0260Y         S2      
017m3730                  -    MD0100PA00X+012920Y+140100                       
317m3730            VIA   -    MD0100PA00X+013746Y+138008X0200Y         S0      
327m3730            PU52  -38         A01X+013914Y+137646X0090Y0240     S1      
327m3730            PU34  -36         A01X+012866Y+142218X0070Y0260R180 S1      
317m3731            VIA   -    M      A01X+013480Y+140810X0200Y         S2      
017m3731            VIA   -    M      A18X+013480Y+140810X0260Y         S2      
017m3731                  -    MD0100PA00X+013480Y+140810                       
317m3731            VIA   -    MD0100PA00X+017016Y+138008X0200Y         S0      
327m3731            PU40  -38         A01X+017184Y+137646X0090Y0240     S1      
327m3731            PU34  -37         A01X+013132Y+142484X0070Y0260R270 S1      
317m3732            VIA   -    M      A01X+013800Y+140060X0200Y         S2      
017m3732            VIA   -    M      A18X+013800Y+140060X0260Y         S2      
017m3732                  -    MD0100PA00X+013800Y+140060                       
317m3732            VIA   -    MD0100PA00X+020306Y+138008X0200Y         S0      
327m3732            PU39  -38         A01X+020474Y+137646X0090Y0240     S1      
327m3732            PU34  -38         A01X+013132Y+142641X0070Y0260R270 S1      
327PVDDIO_P1_EN_R   VIA   -    M      A01X+006625Y+141290X0300Y         S1      
327PVDDIO_P1_EN_R   PQ16  -G          A01X+007226Y+141867X0400Y0560     S1      
327PVDDIO_P1_EN_R   R6088 -1   M      A01X+007238Y+141223X0198Y0197R270 S1      
327PVDDIO_P1_EN_R   R8224 -2          A01X+008038Y+141223X0198Y0197R090 S1      
327PVDDIO_P1_EN_R   C8356 -1   M      A01X+007638Y+141223X0198Y0197R270 S1      
327PVDDIO_P1_EN_G   VIA   -    M      A01X+006839Y+143201X0300Y         S1      
327PVDDIO_P1_EN_G   PQ16  -D          A01X+007600Y+142733X0400Y0560     S1      
327PVDDIO_P1_EN_G   PQ12  -G          A01X+007326Y+143956X0320Y0360     S1      
327PVDDIO_P1_EN_G   PR232 -2   M      A01X+007342Y+143400X0198Y0197R180 S1      
317PVDDIO_P1_EN     VIA   -    M      A01X+078088Y+044334X0200Y    R180 S2      
017PVDDIO_P1_EN     VIA   -    M      A18X+078088Y+044334X0260Y    R180 S2      
017PVDDIO_P1_EN           -    MD0100PA00X+078088Y+044334                       
327PVDDIO_P1_EN     R282  -1          A01X+077823Y+044334X0198Y0197R180 S1      
317PVDDIO_P1_EN     VIA   -    MD0100PA00X+078881Y+034224X0200Y         S0      
317PVDDIO_P1_EN     VIA   -    MD0100PA00X+044655Y+048012X0200Y         S0      
317PVDDIO_P1_EN     VIA   -    MD0100PA00X+066102Y+034483X0200Y         S0      
327PVDDIO_P1_EN     R8224 -1          A01X+008038Y+140908X0198Y0197R090 S1      
317PVDDIO_P1_EN     VIA   -    MD0100PA00X+008038Y+140668X0200Y         S0      
317PVDDIO_P1        VIA   -    MD0080PA00X+031611Y+091470X0160Y    R180 S0      
317PVDDIO_P1        VIA   -    MD0080PA00X+031426Y+092427X0160Y    R180 S0      
317PVDDIO_P1        VIA   -    MD0080PA00X+031426Y+090514X0160Y    R180 S0      
317PVDDIO_P1        VIA   -    MD0080PA00X+031611Y+089557X0160Y    R180 S0      
317PVDDIO_P1        VIA   -    MD0080PA00X+031426Y+094340X0160Y    R180 S0      
317PVDDIO_P1        VIA   -    MD0080PA00X+031611Y+095297X0160Y    R180 S0      
317PVDDIO_P1        VIA   -    MD0080PA00X+031611Y+093384X0160Y    R180 S0      
317PVDDIO_P1        VIA   -    MD0080PA00X+031611Y+099124X0160Y    R180 S0      
317PVDDIO_P1        VIA   -    MD0080PA00X+031426Y+100080X0160Y    R180 S0      
317PVDDIO_P1        VIA   -    MD0080PA00X+031426Y+098167X0160Y    R180 S0      
317PVDDIO_P1        VIA   -    MD0080PA00X+031611Y+097210X0160Y    R180 S0      
317PVDDIO_P1        VIA   -    MD0080PA00X+031426Y+096254X0160Y    R180 S0      
317PVDDIO_P1        VIA   -    MD0080PA00X+031729Y+104719X0160Y         S0      
317PVDDIO_P1        VIA   -    MD0080PA00X+031544Y+105676X0160Y         S0      
317PVDDIO_P1        VIA   -    MD0080PA00X+031544Y+103762X0160Y         S0      
317PVDDIO_P1        VIA   -    MD0080PA00X+031729Y+102806X0160Y         S0      
317PVDDIO_P1        VIA   -    MD0080PA00X+031544Y+109502X0160Y         S0      
317PVDDIO_P1        VIA   -    MD0080PA00X+031729Y+110459X0160Y         S0      
317PVDDIO_P1        VIA   -    MD0080PA00X+031544Y+107589X0160Y         S0      
317PVDDIO_P1        VIA   -    MD0080PA00X+031729Y+108546X0160Y         S0      
317PVDDIO_P1        VIA   -    MD0080PA00X+031729Y+106632X0160Y         S0      
317PVDDIO_P1        VIA   -    MD0080PA00X+031729Y+112373X0160Y         S0      
317PVDDIO_P1        VIA   -    MD0080PA00X+031544Y+113329X0160Y         S0      
317PVDDIO_P1        VIA   -    MD0080PA00X+031544Y+111416X0160Y         S0      
317PVDDIO_P1        VIA   -    MD0080PA00X+031914Y+115880X0160Y         S0      
317PVDDIO_P1        VIA   -    MD0080PA00X+031544Y+115243X0160Y         S0      
317PVDDIO_P1        VIA   -    MD0080PA00X+031729Y+114286X0160Y         S0      
317PVDDIO_P1        VIA   -    MD0080PA00X+034201Y+089557X0160Y    R180 S0      
317PVDDIO_P1        VIA   -    MD0080PA00X+034201Y+091470X0160Y    R180 S0      
317PVDDIO_P1        VIA   -    MD0080PA00X+034016Y+092427X0160Y    R180 S0      
317PVDDIO_P1        VIA   -    MD0080PA00X+034016Y+090514X0160Y    R180 S0      
317PVDDIO_P1        VIA   -    MD0080PA00X+034016Y+094340X0160Y    R180 S0      
317PVDDIO_P1        VIA   -    MD0080PA00X+034201Y+095297X0160Y    R180 S0      
317PVDDIO_P1        VIA   -    MD0080PA00X+034201Y+093384X0160Y    R180 S0      
317PVDDIO_P1        VIA   -    MD0080PA00X+034016Y+098167X0160Y    R180 S0      
317PVDDIO_P1        VIA   -    MD0080PA00X+034201Y+097210X0160Y    R180 S0      
317PVDDIO_P1        VIA   -    MD0080PA00X+034016Y+096254X0160Y    R180 S0      
317PVDDIO_P1        VIA   -    MD0080PA00X+034134Y+103762X0160Y         S0      
317PVDDIO_P1        VIA   -    MD0080PA00X+034319Y+102806X0160Y         S0      
317PVDDIO_P1        VIA   -    MD0080PA00X+034201Y+099124X0160Y    R180 S0      
317PVDDIO_P1        VIA   -    MD0080PA00X+034016Y+100080X0160Y    R180 S0      
317PVDDIO_P1        VIA   -    MD0080PA00X+034134Y+107589X0160Y         S0      
317PVDDIO_P1        VIA   -    MD0080PA00X+034319Y+108546X0160Y         S0      
317PVDDIO_P1        VIA   -    MD0080PA00X+034319Y+106632X0160Y         S0      
317PVDDIO_P1        VIA   -    MD0080PA00X+034319Y+104719X0160Y         S0      
317PVDDIO_P1        VIA   -    MD0080PA00X+034134Y+105676X0160Y         S0      
317PVDDIO_P1        VIA   -    MD0080PA00X+034134Y+111416X0160Y         S0      
317PVDDIO_P1        VIA   -    MD0080PA00X+034319Y+110459X0160Y         S0      
317PVDDIO_P1        VIA   -    MD0080PA00X+034134Y+109502X0160Y         S0      
317PVDDIO_P1        VIA   -    MD0080PA00X+034319Y+114286X0160Y         S0      
317PVDDIO_P1        VIA   -    MD0080PA00X+034134Y+113329X0160Y         S0      
317PVDDIO_P1        VIA   -    MD0080PA00X+034319Y+112373X0160Y         S0      
317PVDDIO_P1        VIA   -    MD0080PA00X+034504Y+115880X0160Y         S0      
317PVDDIO_P1        VIA   -    MD0080PA00X+034134Y+115243X0160Y         S0      
317PVDDIO_P1        VIA   -    MD0080PA00X+036792Y+089557X0160Y    R180 S0      
317PVDDIO_P1        VIA   -    MD0080PA00X+037902Y+091470X0160Y    R180 S0      
317PVDDIO_P1        VIA   -    MD0080PA00X+036792Y+091470X0160Y    R180 S0      
317PVDDIO_P1        VIA   -    MD0080PA00X+036607Y+092427X0160Y    R180 S0      
317PVDDIO_P1        VIA   -    MD0080PA00X+037902Y+090195X0160Y    R180 S0      
317PVDDIO_P1        VIA   -    MD0080PA00X+036607Y+090514X0160Y    R180 S0      
317PVDDIO_P1        VIA   -    MD0080PA00X+037902Y+092746X0160Y    R180 S0      
317PVDDIO_P1        VIA   -    MD0080PA00X+036792Y+093384X0160Y    R180 S0      
317PVDDIO_P1        VIA   -    MD0080PA00X+037902Y+095935X0160Y    R180 S0      
317PVDDIO_P1        VIA   -    MD0080PA00X+036607Y+096254X0160Y    R180 S0      
317PVDDIO_P1        VIA   -    MD0080PA00X+037902Y+094659X0160Y    R180 S0      
317PVDDIO_P1        VIA   -    MD0080PA00X+036792Y+095297X0160Y    R180 S0      
317PVDDIO_P1        VIA   -    MD0080PA00X+036607Y+094340X0160Y    R180 S0      
317PVDDIO_P1        VIA   -    MD0080PA00X+037902Y+097210X0160Y    R180 S0      
317PVDDIO_P1        VIA   -    MD0080PA00X+036792Y+097210X0160Y    R180 S0      
317PVDDIO_P1        VIA   -    MD0080PA00X+036607Y+098167X0160Y    R180 S0      
317PVDDIO_P1        VIA   -    MD0080PA00X+036910Y+102806X0160Y         S0      
317PVDDIO_P1        VIA   -    MD0080PA00X+037902Y+101037X0160Y    R180 S0      
317PVDDIO_P1        VIA   -    MD0080PA00X+036792Y+099124X0160Y    R180 S0      
317PVDDIO_P1        VIA   -    MD0080PA00X+036607Y+100080X0160Y    R180 S0      
317PVDDIO_P1        VIA   -    MD0080PA00X+036910Y+104719X0160Y         S0      
317PVDDIO_P1        VIA   -    MD0080PA00X+036725Y+105676X0160Y         S0      
317PVDDIO_P1        VIA   -    MD0080PA00X+036725Y+103762X0160Y         S0      
317PVDDIO_P1        VIA   -    MD0080PA00X+038020Y+106632X0160Y         S0      
317PVDDIO_P1        VIA   -    MD0080PA00X+036910Y+106632X0160Y         S0      
317PVDDIO_P1        VIA   -    MD0080PA00X+038020Y+107908X0160Y         S0      
317PVDDIO_P1        VIA   -    MD0080PA00X+036910Y+108546X0160Y         S0      
317PVDDIO_P1        VIA   -    MD0080PA00X+036725Y+107589X0160Y         S0      
317PVDDIO_P1        VIA   -    MD0080PA00X+038020Y+111097X0160Y         S0      
317PVDDIO_P1        VIA   -    MD0080PA00X+036725Y+111416X0160Y         S0      
317PVDDIO_P1        VIA   -    MD0080PA00X+036910Y+110459X0160Y         S0      
317PVDDIO_P1        VIA   -    MD0080PA00X+036725Y+109502X0160Y         S0      
317PVDDIO_P1        VIA   -    MD0080PA00X+038020Y+109184X0160Y         S0      
317PVDDIO_P1        VIA   -    MD0080PA00X+038020Y+112373X0160Y         S0      
317PVDDIO_P1        VIA   -    MD0080PA00X+036725Y+113329X0160Y         S0      
317PVDDIO_P1        VIA   -    MD0080PA00X+036910Y+112373X0160Y         S0      
317PVDDIO_P1        VIA   -    MD0080PA00X+036725Y+115243X0160Y         S0      
317PVDDIO_P1        VIA   -    MD0080PA00X+038020Y+113648X0160Y         S0      
317PVDDIO_P1        VIA   -    MD0080PA00X+036910Y+114286X0160Y         S0      
317PVDDIO_P1        VIA   -    MD0080PA00X+038087Y+093702X0160Y    R180 S0      
317PVDDIO_P1        VIA   -    MD0080PA00X+038390Y+104719X0160Y         S0      
317PVDDIO_P1        VIA   -    MD0080PA00X+039130Y+104719X0160Y         S0      
317PVDDIO_P1        VIA   -    MD0080PA00X+038205Y+105038X0160Y         S0      
317PVDDIO_P1        VIA   -    MD0080PA00X+038390Y+103443X0160Y         S0      
317PVDDIO_P1        VIA   -    MD0080PA00X+038390Y+104081X0160Y         S0      
317PVDDIO_P1        VIA   -    MD0080PA00X+038945Y+103124X0160Y         S0      
317PVDDIO_P1        VIA   -    MD0080PA00X+038945Y+104400X0160Y         S0      
317PVDDIO_P1        VIA   -    MD0080PA00X+039130Y+104081X0160Y         S0      
317PVDDIO_P1        VIA   -    MD0080PA00X+038945Y+103762X0160Y         S0      
317PVDDIO_P1        VIA   -    MD0080PA00X+039130Y+103443X0160Y         S0      
317PVDDIO_P1        VIA   -    MD0080PA00X+038205Y+104400X0160Y         S0      
317PVDDIO_P1        VIA   -    MD0080PA00X+038205Y+103762X0160Y         S0      
317PVDDIO_P1        VIA   -    MD0080PA00X+038205Y+103124X0160Y         S0      
317PVDDIO_P1        VIA   -    MD0080PA00X+038390Y+102806X0160Y         S0      
317PVDDIO_P1        VIA   -    MD0080PA00X+039130Y+102806X0160Y         S0      
317PVDDIO_P1        VIA   -    MD0080PA00X+038642Y+101037X0160Y    R180 S0      
317PVDDIO_P1        VIA   -    MD0080PA00X+039382Y+101037X0160Y    R180 S0      
317PVDDIO_P1        VIA   -    MD0080PA00X+038205Y+110140X0160Y         S0      
317PVDDIO_P1        VIA   -    MD0080PA00X+039686Y+103762X0160Y         S0      
317PVDDIO_P1        VIA   -    MD0080PA00X+039686Y+103124X0160Y         S0      
317PVDDIO_P1        VIA   -    MD0080PA00X+039686Y+104400X0160Y         S0      
327PVDDIO_P1        C2102 -1          A18X+040149Y+102256X0198Y0197R180 S2      
327PVDDIO_P1        C2103 -1   M      A18X+039401Y+102256X0198Y0197R180 S2      
327PVDDIO_P1        C2104 -1   M      A18X+038658Y+101077X0198Y0197R180 S2      
327PVDDIO_P1        C2105 -1   M      A18X+039635Y+103749X0198Y0197     S2      
327PVDDIO_P1        C2106 -1   M      A18X+039635Y+103129X0198Y0197     S2      
327PVDDIO_P1        C2107 -1   M      A18X+038653Y+102256X0198Y0197R180 S2      
327PVDDIO_P1        C2108 -1   M      A18X+038935Y+104349X0198Y0197     S2      
327PVDDIO_P1        C2109 -1   M      A18X+038653Y+101902X0198Y0197R180 S2      
327PVDDIO_P1        C2110 -1          A18X+040149Y+101547X0198Y0197R180 S2      
327PVDDIO_P1        C2111 -1          A18X+041559Y+101360X0198Y0197R180 S2      
327PVDDIO_P1        C2112 -1   M      A18X+039401Y+101547X0198Y0197R180 S2      
327PVDDIO_P1        C2116 -1   M      A18X+038935Y+103129X0198Y0197     S2      
327PVDDIO_P1        C2117 -1   M      A18X+039635Y+104349X0198Y0197     S2      
327PVDDIO_P1        C2122 -1          A18X+042502Y+101888X0198Y0197R180 S2      
327PVDDIO_P1        C2123 -1   M      A18X+038653Y+101547X0198Y0197R180 S2      
327PVDDIO_P1        C2127 -1          A01X+042502Y+102301X0198Y0197     S1      
327PVDDIO_P1        C2260 -1          A01X+041559Y+101734X0198Y0197     S1      
327PVDDIO_P1        C2265 -1          A18X+041559Y+102482X0198Y0197R180 S2      
327PVDDIO_P1        C2270 -1          A01X+041559Y+101360X0198Y0197     S1      
327PVDDIO_P1        C2274 -1          A01X+041559Y+102482X0198Y0197     S1      
327PVDDIO_P1        C2278 -1          A01X+041559Y+102108X0198Y0197     S1      
327PVDDIO_P1        C2477 -1          A18X+042502Y+102301X0198Y0197R180 S2      
327PVDDIO_P1        C2478 -1          A01X+042502Y+101888X0198Y0197     S1      
327PVDDIO_P1        C2479 -1          A18X+041559Y+101734X0198Y0197R180 S2      
327PVDDIO_P1        C2484 -1          A18X+040149Y+101902X0198Y0197R180 S2      
327PVDDIO_P1        C2493 -1   M      A18X+038935Y+103749X0198Y0197     S2      
327PVDDIO_P1        C2498 -1   M      A18X+039408Y+101077X0198Y0197R180 S2      
327PVDDIO_P1        C2507 -1   M      A18X+039401Y+101902X0198Y0197R180 S2      
327PVDDIO_P1        C2509 -1          A18X+041559Y+102856X0198Y0197R180 S2      
327PVDDIO_P1        C3910 -1          A18X+041559Y+102108X0198Y0197R180 S2      
327PVDDIO_P1        C3911 -1          A01X+041559Y+102856X0198Y0197     S1      
327PVDDIO_P1        U26   -AA54       A01X+038271Y+093807X0177Y    R180 S1      
327PVDDIO_P1        U26   -AC58       A01X+036790Y+094445X0177Y    R180 S1      
327PVDDIO_P1        U26   -AC65       A01X+034200Y+094445X0177Y    R180 S1      
327PVDDIO_P1        U26   -AC72       A01X+031609Y+094445X0177Y    R180 S1      
327PVDDIO_P1        U26   -AD54       A01X+038086Y+094764X0177Y    R180 S1      
327PVDDIO_P1        U26   -AF57       A01X+036976Y+095402X0177Y    R180 S1      
327PVDDIO_P1        U26   -AF64       A01X+034385Y+095402X0177Y    R180 S1      
327PVDDIO_P1        U26   -AF71       A01X+031794Y+095402X0177Y    R180 S1      
327PVDDIO_P1        U26   -AH54       A01X+038086Y+096040X0177Y    R180 S1      
327PVDDIO_P1        U26   -AJ58       A01X+036790Y+096358X0177Y    R180 S1      
327PVDDIO_P1        U26   -AJ65       A01X+034200Y+096358X0177Y    R180 S1      
327PVDDIO_P1        U26   -AJ72       A01X+031609Y+096358X0177Y    R180 S1      
327PVDDIO_P1        U26   -AM54       A01X+038086Y+097315X0177Y    R180 S1      
327PVDDIO_P1        U26   -AM57       A01X+036976Y+097315X0177Y    R180 S1      
327PVDDIO_P1        U26   -AM64       A01X+034385Y+097315X0177Y    R180 S1      
327PVDDIO_P1        U26   -AM71       A01X+031794Y+097315X0177Y    R180 S1      
327PVDDIO_P1        U26   -AR58       A01X+036790Y+098272X0177Y    R180 S1      
327PVDDIO_P1        U26   -AR65       A01X+034200Y+098272X0177Y    R180 S1      
327PVDDIO_P1        U26   -AR72       A01X+031609Y+098272X0177Y    R180 S1      
327PVDDIO_P1        U26   -AV57       A01X+036976Y+099228X0177Y    R180 S1      
327PVDDIO_P1        U26   -AV64       A01X+034385Y+099228X0177Y    R180 S1      
327PVDDIO_P1        U26   -AV71       A01X+031794Y+099228X0177Y    R180 S1      
327PVDDIO_P1        U26   -BA58       A01X+036790Y+100185X0177Y    R180 S1      
327PVDDIO_P1        U26   -BA65       A01X+034200Y+100185X0177Y    R180 S1      
327PVDDIO_P1        U26   -BA72       A01X+031609Y+100185X0177Y    R180 S1      
327PVDDIO_P1        U26   -BD50       A01X+039566Y+101142X0177Y    R180 S1      
327PVDDIO_P1        U26   -BD52       A01X+038826Y+101142X0177Y    R180 S1      
327PVDDIO_P1        U26   -BD54       A01X+038086Y+101142X0177Y    R180 S1      
327PVDDIO_P1        U26   -BF51       A01X+039314Y+102701X0177Y    R180 S1      
327PVDDIO_P1        U26   -BF53       A01X+038574Y+102701X0177Y    R180 S1      
327PVDDIO_P1        U26   -BF57       A01X+037094Y+102701X0177Y    R180 S1      
327PVDDIO_P1        U26   -BF64       A01X+034503Y+102701X0177Y    R180 S1      
327PVDDIO_P1        U26   -BF71       A01X+031913Y+102701X0177Y    R180 S1      
327PVDDIO_P1        U26   -BG50       A01X+039869Y+103020X0177Y    R180 S1      
327PVDDIO_P1        U26   -BG52       A01X+039129Y+103020X0177Y    R180 S1      
327PVDDIO_P1        U26   -BG54       A01X+038389Y+103020X0177Y    R180 S1      
327PVDDIO_P1        U26   -BH51       A01X+039314Y+103339X0177Y    R180 S1      
327PVDDIO_P1        U26   -BH53       A01X+038574Y+103339X0177Y    R180 S1      
327PVDDIO_P1        U26   -BJ50       A01X+039869Y+103658X0177Y    R180 S1      
327PVDDIO_P1        U26   -BJ52       A01X+039129Y+103658X0177Y    R180 S1      
327PVDDIO_P1        U26   -BJ54       A01X+038389Y+103658X0177Y    R180 S1      
327PVDDIO_P1        U26   -BJ58       A01X+036909Y+103658X0177Y    R180 S1      
327PVDDIO_P1        U26   -BJ65       A01X+034318Y+103658X0177Y    R180 S1      
327PVDDIO_P1        U26   -BJ72       A01X+031728Y+103658X0177Y    R180 S1      
327PVDDIO_P1        U26   -BK51       A01X+039314Y+103976X0177Y    R180 S1      
327PVDDIO_P1        U26   -BK53       A01X+038574Y+103976X0177Y    R180 S1      
327PVDDIO_P1        U26   -BL50       A01X+039869Y+104295X0177Y    R180 S1      
327PVDDIO_P1        U26   -BL52       A01X+039129Y+104295X0177Y    R180 S1      
327PVDDIO_P1        U26   -BL54       A01X+038389Y+104295X0177Y    R180 S1      
327PVDDIO_P1        U26   -BM51       A01X+039314Y+104614X0177Y    R180 S1      
327PVDDIO_P1        U26   -BM53       A01X+038574Y+104614X0177Y    R180 S1      
327PVDDIO_P1        U26   -BM57       A01X+037094Y+104614X0177Y    R180 S1      
327PVDDIO_P1        U26   -BM64       A01X+034503Y+104614X0177Y    R180 S1      
327PVDDIO_P1        U26   -BM71       A01X+031913Y+104614X0177Y    R180 S1      
327PVDDIO_P1        U26   -BN54       A01X+038389Y+104933X0177Y    R180 S1      
327PVDDIO_P1        U26   -BR58       A01X+036909Y+105571X0177Y    R180 S1      
327PVDDIO_P1        U26   -BR65       A01X+034318Y+105571X0177Y    R180 S1      
327PVDDIO_P1        U26   -BR72       A01X+031728Y+105571X0177Y    R180 S1      
327PVDDIO_P1        U26   -BV54       A01X+038204Y+106528X0177Y    R180 S1      
327PVDDIO_P1        U26   -BV57       A01X+037094Y+106528X0177Y    R180 S1      
327PVDDIO_P1        U26   -BV64       A01X+034503Y+106528X0177Y    R180 S1      
327PVDDIO_P1        U26   -BV71       A01X+031913Y+106528X0177Y    R180 S1      
327PVDDIO_P1        U26   -CA58       A01X+036909Y+107484X0177Y    R180 S1      
327PVDDIO_P1        U26   -CA65       A01X+034318Y+107484X0177Y    R180 S1      
327PVDDIO_P1        U26   -CA72       A01X+031728Y+107484X0177Y    R180 S1      
327PVDDIO_P1        U26   -CB54       A01X+038204Y+107803X0177Y    R180 S1      
327PVDDIO_P1        U26   -CD57       A01X+037094Y+108441X0177Y    R180 S1      
327PVDDIO_P1        U26   -CD64       A01X+034503Y+108441X0177Y    R180 S1      
327PVDDIO_P1        U26   -CD71       A01X+031913Y+108441X0177Y    R180 S1      
327PVDDIO_P1        U26   -CF54       A01X+038204Y+109079X0177Y    R180 S1      
327PVDDIO_P1        U26   -CG58       A01X+036909Y+109398X0177Y    R180 S1      
327PVDDIO_P1        U26   -CG65       A01X+034318Y+109398X0177Y    R180 S1      
327PVDDIO_P1        U26   -CG72       A01X+031728Y+109398X0177Y    R180 S1      
327PVDDIO_P1        U26   -CJ54       A01X+038389Y+110036X0177Y    R180 S1      
327PVDDIO_P1        U26   -CK57       A01X+037094Y+110354X0177Y    R180 S1      
327PVDDIO_P1        U26   -CK64       A01X+034503Y+110354X0177Y    R180 S1      
327PVDDIO_P1        U26   -CK71       A01X+031913Y+110354X0177Y    R180 S1      
327PVDDIO_P1        U26   -CM54       A01X+038204Y+110992X0177Y    R180 S1      
327PVDDIO_P1        U26   -CN58       A01X+036909Y+111311X0177Y    R180 S1      
327PVDDIO_P1        U26   -CN65       A01X+034318Y+111311X0177Y    R180 S1      
327PVDDIO_P1        U26   -CN72       A01X+031728Y+111311X0177Y    R180 S1      
327PVDDIO_P1        U26   -CT54       A01X+038204Y+112268X0177Y    R180 S1      
327PVDDIO_P1        U26   -CT57       A01X+037094Y+112268X0177Y    R180 S1      
327PVDDIO_P1        U26   -CT64       A01X+034503Y+112268X0177Y    R180 S1      
327PVDDIO_P1        U26   -CT71       A01X+031913Y+112268X0177Y    R180 S1      
327PVDDIO_P1        U26   -CW58       A01X+036909Y+113225X0177Y    R180 S1      
327PVDDIO_P1        U26   -CW65       A01X+034318Y+113225X0177Y    R180 S1      
327PVDDIO_P1        U26   -CW72       A01X+031728Y+113225X0177Y    R180 S1      
327PVDDIO_P1        U26   -CY54       A01X+038204Y+113543X0177Y    R180 S1      
327PVDDIO_P1        U26   -DB57       A01X+037094Y+114181X0177Y    R180 S1      
327PVDDIO_P1        U26   -DB64       A01X+034503Y+114181X0177Y    R180 S1      
327PVDDIO_P1        U26   -DB71       A01X+031913Y+114181X0177Y    R180 S1      
327PVDDIO_P1        U26   -DE58       A01X+036909Y+115138X0177Y    R180 S1      
327PVDDIO_P1        U26   -DE65       A01X+034318Y+115138X0177Y    R180 S1      
327PVDDIO_P1        U26   -DE72       A01X+031728Y+115138X0177Y    R180 S1      
327PVDDIO_P1        U26   -DG64       A01X+034688Y+115776X0177Y    R180 S1      
327PVDDIO_P1        U26   -DG71       A01X+032098Y+115776X0177Y    R180 S1      
327PVDDIO_P1        U26   -H57        A01X+036976Y+089662X0177Y    R180 S1      
327PVDDIO_P1        U26   -H64        A01X+034385Y+089662X0177Y    R180 S1      
327PVDDIO_P1        U26   -H71        A01X+031794Y+089662X0177Y    R180 S1      
327PVDDIO_P1        U26   -K54        A01X+038086Y+090299X0177Y    R180 S1      
327PVDDIO_P1        U26   -L58        A01X+036790Y+090618X0177Y    R180 S1      
327PVDDIO_P1        U26   -L65        A01X+034200Y+090618X0177Y    R180 S1      
327PVDDIO_P1        U26   -L72        A01X+031609Y+090618X0177Y    R180 S1      
327PVDDIO_P1        U26   -P54        A01X+038086Y+091575X0177Y    R180 S1      
327PVDDIO_P1        U26   -P57        A01X+036976Y+091575X0177Y    R180 S1      
327PVDDIO_P1        U26   -P64        A01X+034385Y+091575X0177Y    R180 S1      
327PVDDIO_P1        U26   -P71        A01X+031794Y+091575X0177Y    R180 S1      
327PVDDIO_P1        U26   -U58        A01X+036790Y+092532X0177Y    R180 S1      
327PVDDIO_P1        U26   -U65        A01X+034200Y+092532X0177Y    R180 S1      
327PVDDIO_P1        U26   -U72        A01X+031609Y+092532X0177Y    R180 S1      
327PVDDIO_P1        U26   -V54        A01X+038086Y+092850X0177Y    R180 S1      
327PVDDIO_P1        U26   -Y57        A01X+036976Y+093488X0177Y    R180 S1      
327PVDDIO_P1        U26   -Y64        A01X+034385Y+093488X0177Y    R180 S1      
327PVDDIO_P1        U26   -Y71        A01X+031794Y+093488X0177Y    R180 S1      
327PVDDIO_P1        VIA   -           A18X+014026Y+129738X0260Y    R180 S2      
327PVDDIO_P1        VIA   -           A18X+017296Y+129738X0260Y    R180 S2      
327PVDDIO_P1        PR378 -1          A18X+009283Y+132948X0198Y0197R270 S2      
327PVDDIO_P1        PC450 -1          A18X+020899Y+132555X0950Y1110R270 S2      
327PVDDIO_P1        PC456_-1          A18X+019449Y+132715X0400Y0500R090 S2      
327PVDDIO_P1        PC459_-1          A18X+018668Y+132717X0400Y0500R090 S2      
327PVDDIO_P1        PC460_-1          A18X+017847Y+132717X0400Y0500R090 S2      
327PVDDIO_P1        PC458_-1          A18X+017027Y+132717X0400Y0500R090 S2      
327PVDDIO_P1        PC637_-1          A18X+016206Y+132717X0400Y0500R090 S2      
327PVDDIO_P1        PC452 -1          A18X+014789Y+132565X0950Y1110R270 S2      
327PVDDIO_P1        PC635_-1          A18X+013399Y+132725X0400Y0500R090 S2      
327PVDDIO_P1        PC636_-1          A18X+012556Y+132717X0400Y0500R090 S2      
327PVDDIO_P1        PC455 -1          A18X+011179Y+132545X0950Y1110R270 S2      
327PVDDIO_P1        PC634_-1          A18X+009799Y+132715X0400Y0500R090 S2      
327PVDDIO_P1        VIA   -           A18X+020586Y+129738X0260Y    R180 S2      
327PVDDIO_P1        PC451 -1          A01X+009416Y+130803X0198Y0197R090 S1      
327PVDDIO_P1        PR227 -2          A01X+009013Y+130750X0198Y0197     S1      
317PVDDIO_P1        VIA   -    MD0100PA00X+021866Y+131788X0200Y         S0      
317PVDDIO_P1        VIA   -    MD0100PA00X+022116Y+131788X0200Y         S0      
317PVDDIO_P1        VIA   -    MD0100PA00X+022116Y+131538X0200Y         S0      
317PVDDIO_P1        VIA   -    MD0100PA00X+020286Y+131788X0200Y         S0      
317PVDDIO_P1        VIA   -    MD0100PA00X+020536Y+131788X0200Y         S0      
317PVDDIO_P1        VIA   -    MD0100PA00X+021616Y+131788X0200Y         S0      
317PVDDIO_P1        VIA   -    MD0100PA00X+018856Y+131788X0200Y         S0      
317PVDDIO_P1        VIA   -    MD0100PA00X+018856Y+131538X0200Y         S0      
317PVDDIO_P1        VIA   -    MD0100PA00X+020036Y+131788X0200Y         S0      
317PVDDIO_P1        VIA   -    MD0100PA00X+020036Y+131538X0200Y         S0      
317PVDDIO_P1        VIA   -    MD0100PA00X+017276Y+131788X0200Y         S0      
317PVDDIO_P1        VIA   -    MD0100PA00X+018606Y+131788X0200Y         S0      
317PVDDIO_P1        VIA   -    MD0100PA00X+018356Y+131788X0200Y         S0      
317PVDDIO_P1        VIA   -    MD0100PA00X+017026Y+131788X0200Y         S0      
317PVDDIO_P1        VIA   -    MD0100PA00X+016776Y+131788X0200Y         S0      
317PVDDIO_P1        VIA   -    MD0100PA00X+016776Y+131538X0200Y         S0      
317PVDDIO_P1        VIA   -    MD0100PA00X+015356Y+131788X0200Y         S0      
317PVDDIO_P1        VIA   -    MD0100PA00X+015106Y+131788X0200Y         S0      
317PVDDIO_P1        VIA   -    MD0100PA00X+015606Y+131788X0200Y         S0      
317PVDDIO_P1        VIA   -    MD0100PA00X+015606Y+131538X0200Y         S0      
317PVDDIO_P1        VIA   -    MD0100PA00X+013776Y+131788X0200Y         S0      
317PVDDIO_P1        VIA   -    MD0100PA00X+014026Y+131788X0200Y         S0      
317PVDDIO_P1        VIA   -    MD0100PA00X+013219Y+137993X0200Y    R180 S0      
317PVDDIO_P1        VIA   -    MD0100PA00X+013526Y+131788X0200Y         S0      
327PVDDIO_P1        PR374 -2          A18X+013079Y+137711X0198Y0197R270 S2      
317PVDDIO_P1        VIA   -    MD0100PA00X+013526Y+131538X0200Y         S0      
317PVDDIO_P1        VIA   -    MD0100PA00X+012346Y+131538X0200Y         S0      
317PVDDIO_P1        VIA   -    MD0100PA00X+012346Y+131788X0200Y         S0      
317PVDDIO_P1        VIA   -    MD0100PA00X+011846Y+131788X0200Y         S0      
317PVDDIO_P1        VIA   -    MD0100PA00X+012096Y+131788X0200Y         S0      
317PVDDIO_P1        VIA   -    MD0100PA00X+010266Y+131538X0200Y         S0      
317PVDDIO_P1        VIA   -    MD0100PA00X+009959Y+137993X0200Y    R180 S0      
317PVDDIO_P1        VIA   -    MD0100PA00X+010266Y+131788X0200Y         S0      
327PVDDIO_P1        PR375 -2          A18X+009819Y+137711X0198Y0197R270 S2      
317PVDDIO_P1        VIA   -    MD0100PA00X+010766Y+131788X0200Y         S0      
317PVDDIO_P1        VIA   -    MD0100PA00X+010516Y+131788X0200Y         S0      
317PVDDIO_P1        VIA   -    MD0100PA00X+021866Y+130038X0200Y         S0      
317PVDDIO_P1        VIA   -    MD0100PA00X+021866Y+130288X0200Y         S0      
317PVDDIO_P1        VIA   -    MD0100PA00X+022116Y+130288X0200Y         S0      
317PVDDIO_P1        VIA   -    MD0100PA00X+022116Y+130038X0200Y         S0      
317PVDDIO_P1        VIA   -    MD0100PA00X+021866Y+130538X0200Y         S0      
317PVDDIO_P1        VIA   -    MD0100PA00X+022116Y+130538X0200Y         S0      
317PVDDIO_P1        VIA   -    MD0100PA00X+022116Y+130788X0200Y         S0      
317PVDDIO_P1        VIA   -    MD0100PA00X+022116Y+131038X0200Y         S0      
317PVDDIO_P1        VIA   -    MD0100PA00X+022116Y+131288X0200Y         S0      
317PVDDIO_P1        VIA   -    MD0100PA00X+020286Y+130038X0200Y         S0      
317PVDDIO_P1        VIA   -    MD0100PA00X+020286Y+130288X0200Y         S0      
317PVDDIO_P1        VIA   -    MD0100PA00X+020536Y+130288X0200Y         S0      
317PVDDIO_P1        VIA   -    MD0100PA00X+020536Y+130038X0200Y         S0      
317PVDDIO_P1        VIA   -    MD0100PA00X+020286Y+130538X0200Y         S0      
317PVDDIO_P1        VIA   -    MD0100PA00X+020536Y+130538X0200Y         S0      
317PVDDIO_P1        VIA   -    MD0100PA00X+021616Y+130288X0200Y         S0      
317PVDDIO_P1        VIA   -    MD0100PA00X+021616Y+130038X0200Y         S0      
317PVDDIO_P1        VIA   -    MD0100PA00X+021616Y+130538X0200Y         S0      
317PVDDIO_P1        VIA   -    MD0100PA00X+021616Y+131538X0200Y         S0      
317PVDDIO_P1        VIA   -    MD0100PA00X+020286Y+131538X0200Y         S0      
317PVDDIO_P1        VIA   -    MD0100PA00X+020536Y+131538X0200Y         S0      
317PVDDIO_P1        VIA   -    MD0100PA00X+021616Y+131288X0200Y         S0      
317PVDDIO_P1        VIA   -    MD0100PA00X+021616Y+131038X0200Y         S0      
317PVDDIO_P1        VIA   -    MD0100PA00X+021616Y+130788X0200Y         S0      
317PVDDIO_P1        VIA   -    MD0100PA00X+020286Y+130788X0200Y         S0      
317PVDDIO_P1        VIA   -    MD0100PA00X+020286Y+131038X0200Y         S0      
317PVDDIO_P1        VIA   -    MD0100PA00X+020286Y+131288X0200Y         S0      
317PVDDIO_P1        VIA   -    MD0100PA00X+020536Y+131288X0200Y         S0      
317PVDDIO_P1        VIA   -    MD0100PA00X+020536Y+131038X0200Y         S0      
317PVDDIO_P1        VIA   -    MD0100PA00X+020536Y+130788X0200Y         S0      
317PVDDIO_P1        VIA   -    MD0100PA00X+021866Y+131538X0200Y         S0      
317PVDDIO_P1        VIA   -    MD0100PA00X+021866Y+130788X0200Y         S0      
317PVDDIO_P1        VIA   -    MD0100PA00X+021866Y+131038X0200Y         S0      
317PVDDIO_P1        VIA   -    MD0100PA00X+021866Y+131288X0200Y         S0      
327PVDDIO_P1        PL47  -4   M      A01X+021076Y+131163X0950Y1780R270 S1      
317PVDDIO_P1        VIA   -    MD0100PA00X+018856Y+130288X0200Y         S0      
317PVDDIO_P1        VIA   -    MD0100PA00X+018856Y+130038X0200Y         S0      
317PVDDIO_P1        VIA   -    MD0100PA00X+018856Y+130538X0200Y         S0      
317PVDDIO_P1        VIA   -    MD0100PA00X+018856Y+130788X0200Y         S0      
317PVDDIO_P1        VIA   -    MD0100PA00X+018856Y+131038X0200Y         S0      
317PVDDIO_P1        VIA   -    MD0100PA00X+018856Y+131288X0200Y         S0      
317PVDDIO_P1        VIA   -    MD0100PA00X+020036Y+130288X0200Y         S0      
317PVDDIO_P1        VIA   -    MD0100PA00X+020036Y+130038X0200Y         S0      
317PVDDIO_P1        VIA   -    MD0100PA00X+020036Y+130538X0200Y         S0      
317PVDDIO_P1        VIA   -    MD0100PA00X+020036Y+130788X0200Y         S0      
317PVDDIO_P1        VIA   -    MD0100PA00X+020036Y+131038X0200Y         S0      
317PVDDIO_P1        VIA   -    MD0100PA00X+020036Y+131288X0200Y         S0      
317PVDDIO_P1        VIA   -    MD0100PA00X+017276Y+130288X0200Y         S0      
317PVDDIO_P1        VIA   -    MD0100PA00X+017276Y+130038X0200Y         S0      
317PVDDIO_P1        VIA   -    MD0100PA00X+017276Y+130538X0200Y         S0      
317PVDDIO_P1        VIA   -    MD0100PA00X+018606Y+130038X0200Y         S0      
317PVDDIO_P1        VIA   -    MD0100PA00X+018606Y+130288X0200Y         S0      
317PVDDIO_P1        VIA   -    MD0100PA00X+018356Y+130288X0200Y         S0      
317PVDDIO_P1        VIA   -    MD0100PA00X+018356Y+130038X0200Y         S0      
317PVDDIO_P1        VIA   -    MD0100PA00X+018606Y+130538X0200Y         S0      
317PVDDIO_P1        VIA   -    MD0100PA00X+018356Y+130538X0200Y         S0      
317PVDDIO_P1        VIA   -    MD0100PA00X+017026Y+130038X0200Y         S0      
317PVDDIO_P1        VIA   -    MD0100PA00X+017026Y+130288X0200Y         S0      
317PVDDIO_P1        VIA   -    MD0100PA00X+016776Y+130288X0200Y         S0      
317PVDDIO_P1        VIA   -    MD0100PA00X+016776Y+130038X0200Y         S0      
317PVDDIO_P1        VIA   -    MD0100PA00X+017026Y+130538X0200Y         S0      
317PVDDIO_P1        VIA   -    MD0100PA00X+016776Y+130538X0200Y         S0      
317PVDDIO_P1        VIA   -    MD0100PA00X+016776Y+130788X0200Y         S0      
317PVDDIO_P1        VIA   -    MD0100PA00X+016776Y+131038X0200Y         S0      
317PVDDIO_P1        VIA   -    MD0100PA00X+016776Y+131288X0200Y         S0      
317PVDDIO_P1        VIA   -    MD0100PA00X+017026Y+131538X0200Y         S0      
317PVDDIO_P1        VIA   -    MD0100PA00X+017026Y+130788X0200Y         S0      
317PVDDIO_P1        VIA   -    MD0100PA00X+017026Y+131038X0200Y         S0      
317PVDDIO_P1        VIA   -    MD0100PA00X+017026Y+131288X0200Y         S0      
317PVDDIO_P1        VIA   -    MD0100PA00X+018356Y+130788X0200Y         S0      
317PVDDIO_P1        VIA   -    MD0100PA00X+017276Y+131288X0200Y         S0      
317PVDDIO_P1        VIA   -    MD0100PA00X+017276Y+131038X0200Y         S0      
317PVDDIO_P1        VIA   -    MD0100PA00X+017276Y+130788X0200Y         S0      
317PVDDIO_P1        VIA   -    MD0100PA00X+018606Y+131538X0200Y         S0      
317PVDDIO_P1        VIA   -    MD0100PA00X+018356Y+131538X0200Y         S0      
317PVDDIO_P1        VIA   -    MD0100PA00X+017276Y+131538X0200Y         S0      
317PVDDIO_P1        VIA   -    MD0100PA00X+018606Y+130788X0200Y         S0      
317PVDDIO_P1        VIA   -    MD0100PA00X+018606Y+131038X0200Y         S0      
317PVDDIO_P1        VIA   -    MD0100PA00X+018606Y+131288X0200Y         S0      
317PVDDIO_P1        VIA   -    MD0100PA00X+018356Y+131288X0200Y         S0      
317PVDDIO_P1        VIA   -    MD0100PA00X+018356Y+131038X0200Y         S0      
327PVDDIO_P1        PL48  -4   M      A01X+017816Y+131163X0950Y1780R270 S1      
317PVDDIO_P1        VIA   -    MD0100PA00X+015356Y+130038X0200Y         S0      
317PVDDIO_P1        VIA   -    MD0100PA00X+015356Y+130288X0200Y         S0      
317PVDDIO_P1        VIA   -    MD0100PA00X+015106Y+130288X0200Y         S0      
317PVDDIO_P1        VIA   -    MD0100PA00X+015106Y+130038X0200Y         S0      
317PVDDIO_P1        VIA   -    MD0100PA00X+015606Y+130288X0200Y         S0      
317PVDDIO_P1        VIA   -    MD0100PA00X+015606Y+130038X0200Y         S0      
317PVDDIO_P1        VIA   -    MD0100PA00X+015356Y+130538X0200Y         S0      
317PVDDIO_P1        VIA   -    MD0100PA00X+015106Y+130538X0200Y         S0      
317PVDDIO_P1        VIA   -    MD0100PA00X+015606Y+130538X0200Y         S0      
317PVDDIO_P1        VIA   -    MD0100PA00X+015606Y+130788X0200Y         S0      
317PVDDIO_P1        VIA   -    MD0100PA00X+015606Y+131038X0200Y         S0      
317PVDDIO_P1        VIA   -    MD0100PA00X+015606Y+131288X0200Y         S0      
317PVDDIO_P1        VIA   -    MD0100PA00X+013776Y+130038X0200Y         S0      
317PVDDIO_P1        VIA   -    MD0100PA00X+013776Y+130288X0200Y         S0      
317PVDDIO_P1        VIA   -    MD0100PA00X+014026Y+130288X0200Y         S0      
317PVDDIO_P1        VIA   -    MD0100PA00X+014026Y+130038X0200Y         S0      
317PVDDIO_P1        VIA   -    MD0100PA00X+013526Y+130288X0200Y         S0      
317PVDDIO_P1        VIA   -    MD0100PA00X+013526Y+130038X0200Y         S0      
317PVDDIO_P1        VIA   -    MD0100PA00X+013776Y+130538X0200Y         S0      
317PVDDIO_P1        VIA   -    MD0100PA00X+014026Y+130538X0200Y         S0      
317PVDDIO_P1        VIA   -    MD0100PA00X+013526Y+130538X0200Y         S0      
317PVDDIO_P1        VIA   -    MD0100PA00X+013526Y+130788X0200Y         S0      
317PVDDIO_P1        VIA   -    MD0100PA00X+013526Y+131038X0200Y         S0      
317PVDDIO_P1        VIA   -    MD0100PA00X+013526Y+131288X0200Y         S0      
317PVDDIO_P1        VIA   -    MD0100PA00X+013776Y+131538X0200Y         S0      
317PVDDIO_P1        VIA   -    MD0100PA00X+014026Y+131538X0200Y         S0      
317PVDDIO_P1        VIA   -    MD0100PA00X+013776Y+130788X0200Y         S0      
317PVDDIO_P1        VIA   -    MD0100PA00X+013776Y+131038X0200Y         S0      
317PVDDIO_P1        VIA   -    MD0100PA00X+013776Y+131288X0200Y         S0      
317PVDDIO_P1        VIA   -    MD0100PA00X+014026Y+131288X0200Y         S0      
317PVDDIO_P1        VIA   -    MD0100PA00X+014026Y+131038X0200Y         S0      
317PVDDIO_P1        VIA   -    MD0100PA00X+014026Y+130788X0200Y         S0      
317PVDDIO_P1        VIA   -    MD0100PA00X+015356Y+131538X0200Y         S0      
317PVDDIO_P1        VIA   -    MD0100PA00X+015106Y+131538X0200Y         S0      
317PVDDIO_P1        VIA   -    MD0100PA00X+015356Y+130788X0200Y         S0      
317PVDDIO_P1        VIA   -    MD0100PA00X+015356Y+131038X0200Y         S0      
317PVDDIO_P1        VIA   -    MD0100PA00X+015356Y+131288X0200Y         S0      
317PVDDIO_P1        VIA   -    MD0100PA00X+015106Y+131288X0200Y         S0      
317PVDDIO_P1        VIA   -    MD0100PA00X+015106Y+131038X0200Y         S0      
317PVDDIO_P1        VIA   -    MD0100PA00X+015106Y+130788X0200Y         S0      
327PVDDIO_P1        PL68  -4   M      A01X+014566Y+131163X0950Y1780R270 S1      
317PVDDIO_P1        VIA   -    MD0100PA00X+011846Y+130288X0200Y         S0      
317PVDDIO_P1        VIA   -    MD0100PA00X+012096Y+130288X0200Y         S0      
317PVDDIO_P1        VIA   -    MD0100PA00X+012096Y+130038X0200Y         S0      
317PVDDIO_P1        VIA   -    MD0100PA00X+012346Y+131288X0200Y         S0      
317PVDDIO_P1        VIA   -    MD0100PA00X+012346Y+131038X0200Y         S0      
317PVDDIO_P1        VIA   -    MD0100PA00X+012346Y+130788X0200Y         S0      
317PVDDIO_P1        VIA   -    MD0100PA00X+012346Y+130538X0200Y         S0      
317PVDDIO_P1        VIA   -    MD0100PA00X+011846Y+130538X0200Y         S0      
317PVDDIO_P1        VIA   -    MD0100PA00X+012096Y+130538X0200Y         S0      
317PVDDIO_P1        VIA   -    MD0100PA00X+012346Y+130038X0200Y         S0      
317PVDDIO_P1        VIA   -    MD0100PA00X+012346Y+130288X0200Y         S0      
317PVDDIO_P1        VIA   -    MD0100PA00X+011846Y+130038X0200Y         S0      
317PVDDIO_P1        VIA   -    MD0100PA00X+010766Y+131538X0200Y         S0      
317PVDDIO_P1        VIA   -    MD0100PA00X+010516Y+131538X0200Y         S0      
317PVDDIO_P1        VIA   -    MD0100PA00X+010766Y+130788X0200Y         S0      
317PVDDIO_P1        VIA   -    MD0100PA00X+010766Y+131038X0200Y         S0      
317PVDDIO_P1        VIA   -    MD0100PA00X+010766Y+131288X0200Y         S0      
317PVDDIO_P1        VIA   -    MD0100PA00X+010516Y+131288X0200Y         S0      
317PVDDIO_P1        VIA   -    MD0100PA00X+010516Y+131038X0200Y         S0      
317PVDDIO_P1        VIA   -    MD0100PA00X+010516Y+130788X0200Y         S0      
317PVDDIO_P1        VIA   -    MD0100PA00X+011846Y+130788X0200Y         S0      
317PVDDIO_P1        VIA   -    MD0100PA00X+011846Y+131038X0200Y         S0      
317PVDDIO_P1        VIA   -    MD0100PA00X+011846Y+131288X0200Y         S0      
317PVDDIO_P1        VIA   -    MD0100PA00X+012096Y+131288X0200Y         S0      
317PVDDIO_P1        VIA   -    MD0100PA00X+012096Y+131038X0200Y         S0      
317PVDDIO_P1        VIA   -    MD0100PA00X+012096Y+130788X0200Y         S0      
317PVDDIO_P1        VIA   -    MD0100PA00X+011846Y+131538X0200Y         S0      
317PVDDIO_P1        VIA   -    MD0100PA00X+012096Y+131538X0200Y         S0      
327PVDDIO_P1        PL67  -4   M      A01X+011306Y+131163X0950Y1780R270 S1      
317PVDDIO_P1        VIA   -    MD0100PA00X+010266Y+131288X0200Y         S0      
317PVDDIO_P1        VIA   -    MD0100PA00X+010266Y+131038X0200Y         S0      
317PVDDIO_P1        VIA   -    MD0100PA00X+010266Y+130788X0200Y         S0      
317PVDDIO_P1        VIA   -    MD0100PA00X+010266Y+130538X0200Y         S0      
317PVDDIO_P1        VIA   -    MD0100PA00X+010766Y+130538X0200Y         S0      
317PVDDIO_P1        VIA   -    MD0100PA00X+010516Y+130538X0200Y         S0      
317PVDDIO_P1        VIA   -    MD0100PA00X+010266Y+130038X0200Y         S0      
317PVDDIO_P1        VIA   -    MD0100PA00X+010266Y+130288X0200Y         S0      
317PVDDIO_P1        VIA   -    MD0100PA00X+010766Y+130038X0200Y         S0      
317PVDDIO_P1        VIA   -    MD0100PA00X+010766Y+130288X0200Y         S0      
317PVDDIO_P1        VIA   -    MD0100PA00X+010516Y+130288X0200Y         S0      
317PVDDIO_P1        VIA   -    MD0100PA00X+010516Y+130038X0200Y         S0      
317PVDDIO_P1        VIA   -    MD0100PA00X+041532Y+101724X0190Y    R270 S0      
317PVDDIO_P1        VIA   -    MD0100PA00X+041532Y+102473X0190Y    R270 S0      
317PVDDIO_P1        VIA   -    MD0100PA00X+041532Y+102099X0190Y    R270 S0      
317PVDDIO_P1        VIA   -    MD0100PA00X+041532Y+102847X0190Y    R270 S0      
317PVDDIO_P1        VIA   -    MD0100PA00X+042487Y+101888X0190Y    R180 S0      
317PVDDIO_P1        VIA   -    MD0100PA00X+042487Y+102301X0190Y    R180 S0      
317PVDDIO_P1        VIA   -    MD0100PA00X+040134Y+102256X0190Y    R180 S0      
317PVDDIO_P1        VIA   -    MD0100PA00X+040134Y+101902X0190Y    R180 S0      
317PVDDIO_P1        VIA   -    MD0100PA00X+039386Y+101902X0190Y    R180 S0      
317PVDDIO_P1        VIA   -    MD0100PA00X+039386Y+102256X0190Y    R180 S0      
317PVDDIO_P1        VIA   -    MD0100PA00X+038638Y+101902X0190Y    R180 S0      
317PVDDIO_P1        VIA   -    MD0100PA00X+038638Y+102256X0190Y    R180 S0      
317PVDDIO_P1        VIA   -    MD0100PA00X+041532Y+101350X0190Y    R270 S0      
317PVDDIO_P1        VIA   -    MD0100PA00X+040134Y+101547X0190Y    R180 S0      
317PVDDIO_P1        VIA   -    MD0100PA00X+039386Y+101547X0190Y    R180 S0      
317PVDDIO_P1        VIA   -    MD0100PA00X+038638Y+101547X0190Y    R180 S0      
327PVDDIO_P1        PR280 -2          A18X+019639Y+137711X0198Y0197R270 S2      
317PVDDIO_P1        VIA   -    MD0100PA00X+019779Y+137993X0200Y    R180 S0      
327PVDDIO_P1        PR281 -2          A18X+016349Y+137711X0198Y0197R270 S2      
317PVDDIO_P1        VIA   -    MD0100PA00X+016489Y+137993X0200Y    R180 S0      
317PVDDIO_P0_VOS4   VIA   -    MD0100PA00X+107361Y+137639X0200Y         S0      
327PVDDIO_P0_VOS4   PU20  -1          A01X+107489Y+137398X0090Y0240R090 S1      
327PVDDIO_P0_VOS4   PR112 -1          A18X+106992Y+137394X0198Y0197R270 S2      
317PVDDIO_P0_VOS3   VIA   -    MD0100PA00X+110621Y+137639X0200Y         S0      
327PVDDIO_P0_VOS3   PU19  -1          A01X+110749Y+137398X0090Y0240R090 S1      
327PVDDIO_P0_VOS3   PR111 -1          A18X+110252Y+137394X0198Y0197R270 S2      
317PVDDIO_P0_VOS2   VIA   -    MD0100PA00X+113891Y+137639X0200Y         S0      
327PVDDIO_P0_VOS2   PU18  -1          A01X+114019Y+137398X0090Y0240R090 S1      
327PVDDIO_P0_VOS2   PR104 -1          A18X+113522Y+137394X0198Y0197R270 S2      
317PVDDIO_P0_VOS1   VIA   -    MD0100PA00X+117181Y+137639X0200Y         S0      
327PVDDIO_P0_VOS1   PU17  -1          A01X+117309Y+137398X0090Y0240R090 S1      
327PVDDIO_P0_VOS1   PR103 -1          A18X+116812Y+137394X0198Y0197R270 S2      
327PVDDIO_P0_VCC4   PU20  -35         A01X+108359Y+137644X0090Y0240     S1      
317PVDDIO_P0_VCC4   VIA   -    MD0100PA00X+108329Y+137954X0200Y         S0      
327PVDDIO_P0_VCC4   VIA   -    M      A18X+107703Y+137593X0260Y    R180 S2      
327PVDDIO_P0_VCC4   PR107 -2   M      A18X+107524Y+137077X0198Y0197R270 S2      
317PVDDIO_P0_VCC4   VIA   -    MD0100PA00X+106984Y+137154X0200Y         S0      
327PVDDIO_P0_VCC4   PC171 -1          A01X+106984Y+137394X0198Y0197R090 S1      
327PVDDIO_P0_VCC4   PU20  -3          A01X+107489Y+137044X0090Y0240R090 S1      
327PVDDIO_P0_VCC3   VIA   -    M      A18X+110963Y+137593X0260Y    R180 S2      
327PVDDIO_P0_VCC3   PU19  -35         A01X+111619Y+137644X0090Y0240     S1      
317PVDDIO_P0_VCC3   VIA   -    MD0100PA00X+111589Y+137954X0200Y         S0      
327PVDDIO_P0_VCC3   PR108 -2   M      A18X+110784Y+137077X0198Y0197R270 S2      
317PVDDIO_P0_VCC3   VIA   -    MD0100PA00X+110244Y+137154X0200Y         S0      
327PVDDIO_P0_VCC3   PC172 -1          A01X+110244Y+137394X0198Y0197R090 S1      
327PVDDIO_P0_VCC3   PU19  -3          A01X+110749Y+137044X0090Y0240R090 S1      
327PVDDIO_P0_VCC2   VIA   -    M      A18X+114233Y+137593X0260Y    R180 S2      
327PVDDIO_P0_VCC2   PU18  -35         A01X+114889Y+137644X0090Y0240     S1      
317PVDDIO_P0_VCC2   VIA   -    MD0100PA00X+114859Y+137954X0200Y         S0      
327PVDDIO_P0_VCC2   PR99  -2   M      A18X+114054Y+137077X0198Y0197R270 S2      
317PVDDIO_P0_VCC2   VIA   -    MD0100PA00X+113514Y+137154X0200Y         S0      
327PVDDIO_P0_VCC2   PC142 -1          A01X+113514Y+137394X0198Y0197R090 S1      
327PVDDIO_P0_VCC2   PU18  -3          A01X+114019Y+137044X0090Y0240R090 S1      
327PVDDIO_P0_VCC1   VIA   -    M      A18X+117523Y+137593X0260Y    R180 S2      
327PVDDIO_P0_VCC1   PU17  -35         A01X+118179Y+137644X0090Y0240     S1      
317PVDDIO_P0_VCC1   VIA   -    MD0100PA00X+118149Y+137954X0200Y         S0      
327PVDDIO_P0_VCC1   PR100 -2   M      A18X+117344Y+137077X0198Y0197R270 S2      
317PVDDIO_P0_VCC1   VIA   -    MD0100PA00X+116804Y+137154X0200Y         S0      
327PVDDIO_P0_VCC1   PC143 -1          A01X+116804Y+137394X0198Y0197R090 S1      
327PVDDIO_P0_VCC1   PU17  -3          A01X+117309Y+137044X0090Y0240R090 S1      
317m3733            VIA   -    MD0100PA00X+108056Y+138051X0200Y         S2      
317m3733            VIA   -    MD0100PA00X+111316Y+138051X0200Y         S0      
327m3733            PU19  -36         A01X+111442Y+137644X0090Y0240     S1      
317m3733            VIA   -    MD0100PA00X+114586Y+138051X0200Y         S0      
327m3733            PU18  -36         A01X+114712Y+137644X0090Y0240     S1      
317m3733            VIA   -    MD0100PA00X+117876Y+138051X0200Y         S0      
327m3733            PU17  -36         A01X+118002Y+137644X0090Y0240     S1      
327m3733            PU20  -36         A01X+108182Y+137644X0090Y0240     S1      
317m3733            VIA   -    MD0100PA00X+123924Y+141846X0200Y         S0      
327m3733            PC77  -1          A01X+124174Y+141846X0198Y0197     S1      
327m3733            PU12  -43         A01X+123232Y+142079X0070Y0260R270 S1      
317PVDDIO_P0_PWM4   VIA   -    M      A01X+122020Y+144910X0200Y         S2      
017PVDDIO_P0_PWM4   VIA   -    M      A18X+122020Y+144910X0260Y         S2      
017PVDDIO_P0_PWM4         -    MD0100PA00X+122020Y+144910                       
327PVDDIO_P0_PWM4   PU20  -34         A01X+108536Y+137644X0090Y0240     S1      
317PVDDIO_P0_PWM4   VIA   -    MD0100PA00X+108404Y+138211X0200Y         S0      
327PVDDIO_P0_PWM4   PU12  -4          A01X+122494Y+143132X0070Y0260R180 S1      
327PVDDIO_P0_PWM3   PU19  -34         A01X+111796Y+137644X0090Y0240     S1      
317PVDDIO_P0_PWM3   VIA   -    MD0100PA00X+111664Y+138211X0200Y         S0      
317PVDDIO_P0_PWM3   VIA   -    MD0100PA00X+122270Y+144630X0200Y         S0      
327PVDDIO_P0_PWM3   PU12  -3          A01X+122651Y+143132X0070Y0260R180 S1      
317PVDDIO_P0_PWM2   VIA   -    MD0100PA00X+122620Y+144430X0200Y         S0      
327PVDDIO_P0_PWM2   PU12  -2          A01X+122809Y+143132X0070Y0260R180 S1      
317PVDDIO_P0_PWM2   VIA   -    MD0100PA00X+114934Y+138211X0200Y         S0      
327PVDDIO_P0_PWM2   PU18  -34         A01X+115066Y+137644X0090Y0240     S1      
327PVDDIO_P0_PWM1   PU12  -1          A01X+122966Y+143132X0070Y0260R180 S1      
317PVDDIO_P0_PWM1   VIA   -    MD0100PA00X+122966Y+144200X0200Y         S0      
317PVDDIO_P0_PWM1   VIA   -    MD0100PA00X+118224Y+138211X0200Y         S0      
327PVDDIO_P0_PWM1   PU17  -34         A01X+118356Y+137644X0090Y0240     S1      
327m3734            VIA   -    M      A01X+107858Y+138110X0160Y0041R090 S1      
327m3734            PU20  -37         A01X+108005Y+137644X0090Y0240     S1      
327m3734            PR105 -1          A01X+107763Y+138554X0198Y0197     S1      
327m3735            VIA   -    M      A01X+111118Y+138107X0160Y0041R270 S1      
327m3735            PU19  -37         A01X+111265Y+137644X0090Y0240     S1      
327m3735            PR106 -1          A01X+111023Y+138554X0198Y0197     S1      
327m3736            VIA   -    M      A01X+114388Y+138096X0160Y0041R090 S1      
327m3736            PR97  -1          A01X+114293Y+138554X0198Y0197     S1      
327m3736            PU18  -37         A01X+114535Y+137644X0090Y0240     S1      
327m3737            VIA   -    M      A01X+117678Y+138096X0160Y0041R090 S1      
327m3737            PU17  -37         A01X+117825Y+137644X0090Y0240     S1      
327m3737            PR98  -1          A01X+117583Y+138554X0198Y0197     S1      
317m3738            VIA   -    M      A01X+123820Y+139550X0200Y         S2      
017m3738            VIA   -    M      A18X+123820Y+139550X0260Y         S2      
017m3738                  -    MD0100PA00X+123820Y+139550                       
327m3738            PU20  -38         A01X+107828Y+137644X0090Y0240     S1      
317m3738            VIA   -    MD0100PA00X+107660Y+138007X0200Y         S0      
327m3738            PU12  -35         A01X+122809Y+140868X0070Y0260R180 S1      
317m3739            VIA   -    M      A01X+123370Y+139560X0300Y         S1      
017m3739            VIA   -    M      A18X+123370Y+139560X0200Y         S1      
017m3739                  -    MD0100PA00X+123370Y+139560                       
317m3739            VIA   -    MD0100PA00X+110920Y+138007X0200Y         S0      
327m3739            PU19  -38         A01X+111088Y+137644X0090Y0240     S1      
327m3739            PU12  -36         A01X+122966Y+140868X0070Y0260R180 S1      
317m3740            VIA   -    M      A01X+123490Y+140440X0200Y         S2      
017m3740            VIA   -    M      A18X+123490Y+140440X0260Y         S2      
017m3740                  -    MD0100PA00X+123490Y+140440                       
317m3740            VIA   -    MD0100PA00X+114190Y+138007X0200Y         S0      
327m3740            PU18  -38         A01X+114358Y+137644X0090Y0240     S1      
327m3740            PU12  -37         A01X+123232Y+141134X0070Y0260R270 S1      
317m3741            VIA   -    M      A01X+123850Y+140090X0200Y         S2      
017m3741            VIA   -    M      A18X+123850Y+140090X0260Y         S2      
017m3741                  -    MD0100PA00X+123850Y+140090                       
327m3741            PU17  -38         A01X+117648Y+137644X0090Y0240     S1      
317m3741            VIA   -    MD0100PA00X+117480Y+138007X0200Y         S0      
327m3741            PU12  -38         A01X+123232Y+141291X0070Y0260R270 S1      
327PVDDIO_P0_EN_R   PQ14  -G          A01X+114412Y+145347X0400Y0560R270 S1      
327PVDDIO_P0_EN_R   VIA   -    M      A01X+114310Y+145952X0300Y         S1      
327PVDDIO_P0_EN_R   R8047 -2          A01X+112985Y+145952X0198Y0197R090 S1      
327PVDDIO_P0_EN_R   R6086 -1   M      A01X+113385Y+145952X0198Y0197R270 S1      
327PVDDIO_P0_EN_R   C8066 -1   M      A01X+113785Y+145952X0198Y0197R270 S1      
327PVDDIO_P0_EN_G   VIA   -    M      A01X+115511Y+145630X0300Y         S1      
327PVDDIO_P0_EN_G   PQ14  -D          A01X+115278Y+144973X0400Y0560R270 S1      
327PVDDIO_P0_EN_G   PQ10  -G          A01X+116016Y+144874X0320Y0360R270 S1      
327PVDDIO_P0_EN_G   PR55  -2   M      A01X+116020Y+145423X0198Y0197R180 S1      
317PVDDIO_P0_EN     VIA   -    MD0100PA00X+088356Y+144036X0200Y         S0      
327PVDDIO_P0_EN     R229  -1          A18X+077923Y+041534X0198Y0197     S2      
317PVDDIO_P0_EN     VIA   -    MD0100PA00X+084600Y+041886X0200Y         S0      
317PVDDIO_P0_EN     VIA   -    MD0100PA00X+102444Y+042405X0200Y         S0      
317PVDDIO_P0_EN     VIA   -    MD0100PA00X+091533Y+063917X0200Y         S0      
317PVDDIO_P0_EN     VIA   -    MD0100PA00X+090631Y+082510X0200Y         S0      
327PVDDIO_P0_EN     R8047 -1          A01X+112985Y+145637X0198Y0197R090 S1      
327PVDDIO_P0_EN     VIA   -    M      A01X+112382Y+145637X0300Y         S1      
317PVDDIO_P0        VIA   -    MD0080PA00X+129040Y+090513X0160Y    R180 S0      
317PVDDIO_P0        VIA   -    MD0080PA00X+129225Y+089557X0160Y    R180 S0      
317PVDDIO_P0        VIA   -    MD0080PA00X+129040Y+092427X0160Y    R180 S0      
317PVDDIO_P0        VIA   -    MD0080PA00X+129225Y+091470X0160Y    R180 S0      
317PVDDIO_P0        VIA   -    MD0080PA00X+129040Y+094340X0160Y    R180 S0      
317PVDDIO_P0        VIA   -    MD0080PA00X+129225Y+095297X0160Y    R180 S0      
317PVDDIO_P0        VIA   -    MD0080PA00X+129225Y+093384X0160Y    R180 S0      
317PVDDIO_P0        VIA   -    MD0080PA00X+129040Y+098167X0160Y    R180 S0      
317PVDDIO_P0        VIA   -    MD0080PA00X+129225Y+097210X0160Y    R180 S0      
317PVDDIO_P0        VIA   -    MD0080PA00X+129040Y+096254X0160Y    R180 S0      
317PVDDIO_P0        VIA   -    MD0080PA00X+129343Y+102806X0160Y         S0      
317PVDDIO_P0        VIA   -    MD0080PA00X+129040Y+100080X0160Y    R180 S0      
317PVDDIO_P0        VIA   -    MD0080PA00X+129225Y+099124X0160Y    R180 S0      
317PVDDIO_P0        VIA   -    MD0080PA00X+129343Y+104719X0160Y         S0      
317PVDDIO_P0        VIA   -    MD0080PA00X+129158Y+105676X0160Y         S0      
317PVDDIO_P0        VIA   -    MD0080PA00X+129158Y+103762X0160Y         S0      
317PVDDIO_P0        VIA   -    MD0080PA00X+129158Y+107589X0160Y         S0      
317PVDDIO_P0        VIA   -    MD0080PA00X+129343Y+108546X0160Y         S0      
317PVDDIO_P0        VIA   -    MD0080PA00X+129343Y+106632X0160Y         S0      
317PVDDIO_P0        VIA   -    MD0080PA00X+129158Y+109502X0160Y         S0      
317PVDDIO_P0        VIA   -    MD0080PA00X+129343Y+110459X0160Y         S0      
317PVDDIO_P0        VIA   -    MD0080PA00X+129343Y+112372X0160Y         S0      
317PVDDIO_P0        VIA   -    MD0080PA00X+129158Y+113329X0160Y         S0      
317PVDDIO_P0        VIA   -    MD0080PA00X+129158Y+111416X0160Y         S0      
317PVDDIO_P0        VIA   -    MD0080PA00X+129158Y+115242X0160Y         S0      
317PVDDIO_P0        VIA   -    MD0080PA00X+129528Y+115880X0160Y         S0      
317PVDDIO_P0        VIA   -    MD0080PA00X+129343Y+114286X0160Y         S0      
317PVDDIO_P0        VIA   -    MD0080PA00X+131815Y+089557X0160Y    R180 S0      
317PVDDIO_P0        VIA   -    MD0080PA00X+131815Y+091470X0160Y    R180 S0      
317PVDDIO_P0        VIA   -    MD0080PA00X+131630Y+092427X0160Y    R180 S0      
317PVDDIO_P0        VIA   -    MD0080PA00X+131630Y+090513X0160Y    R180 S0      
317PVDDIO_P0        VIA   -    MD0080PA00X+131630Y+094340X0160Y    R180 S0      
317PVDDIO_P0        VIA   -    MD0080PA00X+131815Y+095297X0160Y    R180 S0      
317PVDDIO_P0        VIA   -    MD0080PA00X+131815Y+093384X0160Y    R180 S0      
317PVDDIO_P0        VIA   -    MD0080PA00X+131815Y+099124X0160Y    R180 S0      
317PVDDIO_P0        VIA   -    MD0080PA00X+131630Y+100080X0160Y    R180 S0      
317PVDDIO_P0        VIA   -    MD0080PA00X+131815Y+097210X0160Y    R180 S0      
317PVDDIO_P0        VIA   -    MD0080PA00X+131630Y+098167X0160Y    R180 S0      
317PVDDIO_P0        VIA   -    MD0080PA00X+131630Y+096254X0160Y    R180 S0      
317PVDDIO_P0        VIA   -    MD0080PA00X+131748Y+103762X0160Y         S0      
317PVDDIO_P0        VIA   -    MD0080PA00X+131934Y+102806X0160Y         S0      
317PVDDIO_P0        VIA   -    MD0080PA00X+131748Y+107589X0160Y         S0      
317PVDDIO_P0        VIA   -    MD0080PA00X+131934Y+108546X0160Y         S0      
317PVDDIO_P0        VIA   -    MD0080PA00X+131934Y+106632X0160Y         S0      
317PVDDIO_P0        VIA   -    MD0080PA00X+131934Y+104719X0160Y         S0      
317PVDDIO_P0        VIA   -    MD0080PA00X+131748Y+105676X0160Y         S0      
317PVDDIO_P0        VIA   -    MD0080PA00X+131748Y+111416X0160Y         S0      
317PVDDIO_P0        VIA   -    MD0080PA00X+131748Y+109502X0160Y         S0      
317PVDDIO_P0        VIA   -    MD0080PA00X+131934Y+110459X0160Y         S0      
317PVDDIO_P0        VIA   -    MD0080PA00X+131934Y+114286X0160Y         S0      
317PVDDIO_P0        VIA   -    MD0080PA00X+131934Y+112372X0160Y         S0      
317PVDDIO_P0        VIA   -    MD0080PA00X+131748Y+113329X0160Y         S0      
317PVDDIO_P0        VIA   -    MD0080PA00X+131748Y+115242X0160Y         S0      
317PVDDIO_P0        VIA   -    MD0080PA00X+132118Y+115880X0160Y         S0      
317PVDDIO_P0        VIA   -    MD0080PA00X+134221Y+090513X0160Y    R180 S0      
317PVDDIO_P0        VIA   -    MD0080PA00X+134406Y+089557X0160Y    R180 S0      
317PVDDIO_P0        VIA   -    MD0080PA00X+134221Y+092427X0160Y    R180 S0      
317PVDDIO_P0        VIA   -    MD0080PA00X+134406Y+091470X0160Y    R180 S0      
317PVDDIO_P0        VIA   -    MD0080PA00X+134406Y+093384X0160Y    R180 S0      
317PVDDIO_P0        VIA   -    MD0080PA00X+134221Y+096254X0160Y    R180 S0      
317PVDDIO_P0        VIA   -    MD0080PA00X+134406Y+095297X0160Y    R180 S0      
317PVDDIO_P0        VIA   -    MD0080PA00X+134221Y+094340X0160Y    R180 S0      
317PVDDIO_P0        VIA   -    MD0080PA00X+134221Y+100080X0160Y    R180 S0      
317PVDDIO_P0        VIA   -    MD0080PA00X+134406Y+099124X0160Y    R180 S0      
317PVDDIO_P0        VIA   -    MD0080PA00X+134406Y+097210X0160Y    R180 S0      
317PVDDIO_P0        VIA   -    MD0080PA00X+134221Y+098167X0160Y    R180 S0      
317PVDDIO_P0        VIA   -    MD0080PA00X+134524Y+102806X0160Y         S0      
317PVDDIO_P0        VIA   -    MD0080PA00X+134339Y+105676X0160Y         S0      
317PVDDIO_P0        VIA   -    MD0080PA00X+134524Y+104719X0160Y         S0      
317PVDDIO_P0        VIA   -    MD0080PA00X+134339Y+103762X0160Y         S0      
317PVDDIO_P0        VIA   -    MD0080PA00X+134524Y+106632X0160Y         S0      
317PVDDIO_P0        VIA   -    MD0080PA00X+134524Y+108546X0160Y         S0      
317PVDDIO_P0        VIA   -    MD0080PA00X+134339Y+107589X0160Y         S0      
317PVDDIO_P0        VIA   -    MD0080PA00X+134339Y+111416X0160Y         S0      
317PVDDIO_P0        VIA   -    MD0080PA00X+134524Y+110459X0160Y         S0      
317PVDDIO_P0        VIA   -    MD0080PA00X+134339Y+109502X0160Y         S0      
317PVDDIO_P0        VIA   -    MD0080PA00X+134524Y+112372X0160Y         S0      
317PVDDIO_P0        VIA   -    MD0080PA00X+134339Y+113329X0160Y         S0      
317PVDDIO_P0        VIA   -    MD0080PA00X+134339Y+115242X0160Y         S0      
317PVDDIO_P0        VIA   -    MD0080PA00X+134524Y+114286X0160Y         S0      
317PVDDIO_P0        VIA   -    MD0080PA00X+135516Y+090195X0160Y    R180 S0      
317PVDDIO_P0        VIA   -    MD0080PA00X+135516Y+092746X0160Y    R180 S0      
317PVDDIO_P0        VIA   -    MD0080PA00X+135701Y+093702X0160Y    R180 S0      
317PVDDIO_P0        VIA   -    MD0080PA00X+135516Y+091470X0160Y    R180 S0      
317PVDDIO_P0        VIA   -    MD0080PA00X+135516Y+095935X0160Y    R180 S0      
317PVDDIO_P0        VIA   -    MD0080PA00X+135516Y+094659X0160Y    R180 S0      
317PVDDIO_P0        VIA   -    MD0080PA00X+135516Y+097210X0160Y    R180 S0      
317PVDDIO_P0        VIA   -    MD0080PA00X+135819Y+105038X0160Y         S0      
317PVDDIO_P0        VIA   -    MD0080PA00X+136004Y+104719X0160Y         S0      
317PVDDIO_P0        VIA   -    MD0080PA00X+135819Y+104400X0160Y         S0      
317PVDDIO_P0        VIA   -    MD0080PA00X+135819Y+103762X0160Y         S0      
317PVDDIO_P0        VIA   -    MD0080PA00X+136004Y+103443X0160Y         S0      
317PVDDIO_P0        VIA   -    MD0080PA00X+136004Y+104081X0160Y         S0      
317PVDDIO_P0        VIA   -    MD0080PA00X+135819Y+103124X0160Y         S0      
317PVDDIO_P0        VIA   -    MD0080PA00X+136004Y+102806X0160Y         S0      
317PVDDIO_P0        VIA   -    MD0080PA00X+136256Y+101037X0160Y    R180 S0      
317PVDDIO_P0        VIA   -    MD0080PA00X+135516Y+101037X0160Y    R180 S0      
317PVDDIO_P0        VIA   -    MD0080PA00X+135634Y+106632X0160Y         S0      
317PVDDIO_P0        VIA   -    MD0080PA00X+135634Y+107908X0160Y         S0      
317PVDDIO_P0        VIA   -    MD0080PA00X+135819Y+110140X0160Y         S0      
317PVDDIO_P0        VIA   -    MD0080PA00X+135634Y+109184X0160Y         S0      
317PVDDIO_P0        VIA   -    MD0080PA00X+135634Y+111097X0160Y         S0      
317PVDDIO_P0        VIA   -    MD0080PA00X+135634Y+113648X0160Y         S0      
317PVDDIO_P0        VIA   -    MD0080PA00X+135634Y+112372X0160Y         S0      
317PVDDIO_P0        VIA   -    MD0080PA00X+137300Y+103124X0160Y         S0      
317PVDDIO_P0        VIA   -    MD0080PA00X+136560Y+104400X0160Y         S0      
317PVDDIO_P0        VIA   -    MD0080PA00X+136560Y+103762X0160Y         S0      
317PVDDIO_P0        VIA   -    MD0080PA00X+136560Y+103124X0160Y         S0      
317PVDDIO_P0        VIA   -    MD0080PA00X+136744Y+103443X0160Y         S0      
317PVDDIO_P0        VIA   -    MD0080PA00X+136744Y+104081X0160Y         S0      
317PVDDIO_P0        VIA   -    MD0080PA00X+137300Y+104400X0160Y         S0      
317PVDDIO_P0        VIA   -    MD0080PA00X+137300Y+103762X0160Y         S0      
317PVDDIO_P0        VIA   -    MD0080PA00X+136744Y+102806X0160Y         S0      
317PVDDIO_P0        VIA   -    MD0080PA00X+136996Y+101037X0160Y    R180 S0      
317PVDDIO_P0        VIA   -    MD0080PA00X+136744Y+104719X0160Y         S0      
327PVDDIO_P0        C2131 -1          A18X+140116Y+102301X0198Y0197R180 S2      
327PVDDIO_P0        C2136 -1          A01X+139173Y+102108X0198Y0197     S1      
327PVDDIO_P0        C2141 -1          A01X+139173Y+102482X0198Y0197     S1      
327PVDDIO_P0        C2145 -1          A18X+139173Y+102856X0198Y0197R180 S2      
327PVDDIO_P0        C2149 -1          A01X+139173Y+102856X0198Y0197     S1      
327PVDDIO_P0        C2597 -1   M      A18X+137225Y+103749X0198Y0197     S2      
327PVDDIO_P0        C2598 -1          A18X+140116Y+101888X0198Y0197R180 S2      
327PVDDIO_P0        C2599 -1          A01X+139173Y+101734X0198Y0197     S1      
327PVDDIO_P0        C2604 -1   M      A18X+136525Y+103749X0198Y0197     S2      
327PVDDIO_P0        C2605 -1   M      A18X+136525Y+103099X0198Y0197     S2      
327PVDDIO_P0        C2606 -1          A01X+139173Y+101360X0198Y0197     S1      
327PVDDIO_P0        C2611 -1          A18X+137763Y+102256X0198Y0197R180 S2      
327PVDDIO_P0        C2612 -1   M      A18X+136525Y+104349X0198Y0197     S2      
327PVDDIO_P0        C2613 -1          A18X+139173Y+102482X0198Y0197R180 S2      
327PVDDIO_P0        C2618 -1   M      A18X+136267Y+101547X0198Y0197R180 S2      
327PVDDIO_P0        C2619 -1   M      A18X+137023Y+101076X0198Y0197R180 S2      
327PVDDIO_P0        C2620 -1          A18X+139173Y+102108X0198Y0197R180 S2      
327PVDDIO_P0        C2625 -1   M      A18X+136273Y+101076X0198Y0197R180 S2      
327PVDDIO_P0        C2626 -1   M      A18X+137225Y+104349X0198Y0197     S2      
327PVDDIO_P0        C2631 -1   M      A18X+137015Y+102256X0198Y0197R180 S2      
327PVDDIO_P0        C2632 -1   M      A18X+137015Y+101902X0198Y0197R180 S2      
327PVDDIO_P0        C2637 -1          A18X+137763Y+101547X0198Y0197R180 S2      
327PVDDIO_P0        C2638 -1          A18X+139173Y+101734X0198Y0197R180 S2      
327PVDDIO_P0        C2643 -1   M      A18X+137015Y+101547X0198Y0197R180 S2      
327PVDDIO_P0        C2644 -1          A18X+139173Y+101360X0198Y0197R180 S2      
327PVDDIO_P0        C2649 -1          A18X+137763Y+101902X0198Y0197R180 S2      
327PVDDIO_P0        C2650 -1          A18X+137225Y+103099X0198Y0197     S2      
327PVDDIO_P0        C2654 -1   M      A18X+136267Y+101902X0198Y0197R180 S2      
327PVDDIO_P0        C2655 -1   M      A18X+136267Y+102256X0198Y0197R180 S2      
327PVDDIO_P0        C3898 -1          A01X+140116Y+102301X0198Y0197     S1      
327PVDDIO_P0        C3899 -1          A01X+140116Y+101888X0198Y0197     S1      
327PVDDIO_P0        U25   -AD54       A01X+135700Y+094764X0177Y    R180 S1      
327PVDDIO_P0        U25   -AA54       A01X+135885Y+093807X0177Y    R180 S1      
327PVDDIO_P0        U25   -V54        A01X+135700Y+092850X0177Y    R180 S1      
327PVDDIO_P0        U25   -P54        A01X+135700Y+091575X0177Y    R180 S1      
327PVDDIO_P0        U25   -K54        A01X+135700Y+090299X0177Y    R180 S1      
327PVDDIO_P0        PR52  -2          A01X+106072Y+130720X0198Y0197     S1      
327PVDDIO_P0        PC107 -1          A01X+106492Y+130791X0198Y0197R090 S1      
327PVDDIO_P0        U25   -AC58       A01X+134405Y+094445X0177Y    R180 S1      
327PVDDIO_P0        U25   -AC65       A01X+131814Y+094445X0177Y    R180 S1      
327PVDDIO_P0        U25   -AC72       A01X+129224Y+094445X0177Y    R180 S1      
327PVDDIO_P0        U25   -AF57       A01X+134590Y+095402X0177Y    R180 S1      
327PVDDIO_P0        U25   -AF64       A01X+131999Y+095402X0177Y    R180 S1      
327PVDDIO_P0        U25   -AF71       A01X+129409Y+095402X0177Y    R180 S1      
327PVDDIO_P0        U25   -AH54       A01X+135700Y+096039X0177Y    R180 S1      
327PVDDIO_P0        U25   -AJ58       A01X+134405Y+096358X0177Y    R180 S1      
327PVDDIO_P0        U25   -AJ65       A01X+131814Y+096358X0177Y    R180 S1      
327PVDDIO_P0        U25   -AJ72       A01X+129224Y+096358X0177Y    R180 S1      
327PVDDIO_P0        U25   -AM54       A01X+135700Y+097315X0177Y    R180 S1      
327PVDDIO_P0        U25   -AM57       A01X+134590Y+097315X0177Y    R180 S1      
327PVDDIO_P0        U25   -AM64       A01X+131999Y+097315X0177Y    R180 S1      
327PVDDIO_P0        U25   -AM71       A01X+129409Y+097315X0177Y    R180 S1      
327PVDDIO_P0        U25   -AR58       A01X+134405Y+098272X0177Y    R180 S1      
327PVDDIO_P0        U25   -AR65       A01X+131814Y+098272X0177Y    R180 S1      
327PVDDIO_P0        U25   -AR72       A01X+129224Y+098272X0177Y    R180 S1      
327PVDDIO_P0        U25   -AV57       A01X+134590Y+099228X0177Y    R180 S1      
327PVDDIO_P0        U25   -AV64       A01X+131999Y+099228X0177Y    R180 S1      
327PVDDIO_P0        U25   -AV71       A01X+129409Y+099228X0177Y    R180 S1      
327PVDDIO_P0        U25   -BA58       A01X+134405Y+100185X0177Y    R180 S1      
327PVDDIO_P0        U25   -BA65       A01X+131814Y+100185X0177Y    R180 S1      
327PVDDIO_P0        U25   -BA72       A01X+129224Y+100185X0177Y    R180 S1      
327PVDDIO_P0        U25   -BD50       A01X+137180Y+101142X0177Y    R180 S1      
327PVDDIO_P0        U25   -BD52       A01X+136440Y+101142X0177Y    R180 S1      
327PVDDIO_P0        U25   -BD54       A01X+135700Y+101142X0177Y    R180 S1      
327PVDDIO_P0        U25   -BF51       A01X+136928Y+102701X0177Y    R180 S1      
327PVDDIO_P0        U25   -BF53       A01X+136188Y+102701X0177Y    R180 S1      
327PVDDIO_P0        U25   -BF57       A01X+134708Y+102701X0177Y    R180 S1      
327PVDDIO_P0        U25   -BF64       A01X+132117Y+102701X0177Y    R180 S1      
327PVDDIO_P0        U25   -BF71       A01X+129527Y+102701X0177Y    R180 S1      
327PVDDIO_P0        U25   -BG50       A01X+137484Y+103020X0177Y    R180 S1      
327PVDDIO_P0        U25   -BG52       A01X+136743Y+103020X0177Y    R180 S1      
327PVDDIO_P0        U25   -BG54       A01X+136003Y+103020X0177Y    R180 S1      
327PVDDIO_P0        U25   -BH51       A01X+136928Y+103339X0177Y    R180 S1      
327PVDDIO_P0        U25   -BH53       A01X+136188Y+103339X0177Y    R180 S1      
327PVDDIO_P0        U25   -BJ50       A01X+137484Y+103658X0177Y    R180 S1      
327PVDDIO_P0        U25   -BJ52       A01X+136743Y+103658X0177Y    R180 S1      
327PVDDIO_P0        U25   -BJ54       A01X+136003Y+103658X0177Y    R180 S1      
327PVDDIO_P0        U25   -BJ58       A01X+134523Y+103658X0177Y    R180 S1      
327PVDDIO_P0        U25   -BJ65       A01X+131932Y+103658X0177Y    R180 S1      
327PVDDIO_P0        U25   -BJ72       A01X+129342Y+103658X0177Y    R180 S1      
327PVDDIO_P0        U25   -BK51       A01X+136928Y+103976X0177Y    R180 S1      
327PVDDIO_P0        U25   -BK53       A01X+136188Y+103976X0177Y    R180 S1      
327PVDDIO_P0        U25   -BL50       A01X+137484Y+104295X0177Y    R180 S1      
327PVDDIO_P0        U25   -BL52       A01X+136743Y+104295X0177Y    R180 S1      
327PVDDIO_P0        U25   -BL54       A01X+136003Y+104295X0177Y    R180 S1      
327PVDDIO_P0        U25   -BM51       A01X+136928Y+104614X0177Y    R180 S1      
327PVDDIO_P0        U25   -BM53       A01X+136188Y+104614X0177Y    R180 S1      
327PVDDIO_P0        U25   -BM57       A01X+134708Y+104614X0177Y    R180 S1      
327PVDDIO_P0        U25   -BM64       A01X+132117Y+104614X0177Y    R180 S1      
327PVDDIO_P0        U25   -BM71       A01X+129527Y+104614X0177Y    R180 S1      
327PVDDIO_P0        U25   -BN54       A01X+136003Y+104933X0177Y    R180 S1      
327PVDDIO_P0        U25   -BR58       A01X+134523Y+105571X0177Y    R180 S1      
327PVDDIO_P0        U25   -BR65       A01X+131932Y+105571X0177Y    R180 S1      
327PVDDIO_P0        U25   -BR72       A01X+129342Y+105571X0177Y    R180 S1      
327PVDDIO_P0        U25   -BV54       A01X+135818Y+106528X0177Y    R180 S1      
327PVDDIO_P0        U25   -BV57       A01X+134708Y+106528X0177Y    R180 S1      
327PVDDIO_P0        U25   -BV64       A01X+132117Y+106528X0177Y    R180 S1      
327PVDDIO_P0        U25   -BV71       A01X+129527Y+106528X0177Y    R180 S1      
327PVDDIO_P0        U25   -CA58       A01X+134523Y+107484X0177Y    R180 S1      
327PVDDIO_P0        U25   -CA65       A01X+131932Y+107484X0177Y    R180 S1      
327PVDDIO_P0        U25   -CA72       A01X+129342Y+107484X0177Y    R180 S1      
327PVDDIO_P0        U25   -CB54       A01X+135818Y+107803X0177Y    R180 S1      
327PVDDIO_P0        U25   -CD57       A01X+134708Y+108441X0177Y    R180 S1      
327PVDDIO_P0        U25   -CD64       A01X+132117Y+108441X0177Y    R180 S1      
327PVDDIO_P0        U25   -CD71       A01X+129527Y+108441X0177Y    R180 S1      
327PVDDIO_P0        U25   -CF54       A01X+135818Y+109079X0177Y    R180 S1      
327PVDDIO_P0        U25   -CG58       A01X+134523Y+109398X0177Y    R180 S1      
327PVDDIO_P0        U25   -CG65       A01X+131932Y+109398X0177Y    R180 S1      
327PVDDIO_P0        U25   -CG72       A01X+129342Y+109398X0177Y    R180 S1      
327PVDDIO_P0        U25   -CJ54       A01X+136003Y+110036X0177Y    R180 S1      
327PVDDIO_P0        U25   -CK57       A01X+134708Y+110354X0177Y    R180 S1      
327PVDDIO_P0        U25   -CK64       A01X+132117Y+110354X0177Y    R180 S1      
327PVDDIO_P0        U25   -CK71       A01X+129527Y+110354X0177Y    R180 S1      
327PVDDIO_P0        U25   -CM54       A01X+135818Y+110992X0177Y    R180 S1      
327PVDDIO_P0        U25   -CN58       A01X+134523Y+111311X0177Y    R180 S1      
327PVDDIO_P0        U25   -CN65       A01X+131932Y+111311X0177Y    R180 S1      
327PVDDIO_P0        U25   -CN72       A01X+129342Y+111311X0177Y    R180 S1      
327PVDDIO_P0        U25   -CT54       A01X+135818Y+112268X0177Y    R180 S1      
327PVDDIO_P0        U25   -CT57       A01X+134708Y+112268X0177Y    R180 S1      
327PVDDIO_P0        U25   -CT64       A01X+132117Y+112268X0177Y    R180 S1      
327PVDDIO_P0        U25   -CT71       A01X+129527Y+112268X0177Y    R180 S1      
327PVDDIO_P0        U25   -CW58       A01X+134523Y+113224X0177Y    R180 S1      
327PVDDIO_P0        U25   -CW65       A01X+131932Y+113224X0177Y    R180 S1      
327PVDDIO_P0        U25   -CW72       A01X+129342Y+113224X0177Y    R180 S1      
327PVDDIO_P0        U25   -CY54       A01X+135818Y+113543X0177Y    R180 S1      
327PVDDIO_P0        U25   -DB57       A01X+134708Y+114181X0177Y    R180 S1      
327PVDDIO_P0        U25   -DB64       A01X+132117Y+114181X0177Y    R180 S1      
327PVDDIO_P0        U25   -DB71       A01X+129527Y+114181X0177Y    R180 S1      
327PVDDIO_P0        U25   -DE58       A01X+134523Y+115138X0177Y    R180 S1      
327PVDDIO_P0        U25   -DE65       A01X+131932Y+115138X0177Y    R180 S1      
327PVDDIO_P0        U25   -DE72       A01X+129342Y+115138X0177Y    R180 S1      
327PVDDIO_P0        U25   -DG64       A01X+132302Y+115776X0177Y    R180 S1      
327PVDDIO_P0        U25   -DG71       A01X+129712Y+115776X0177Y    R180 S1      
327PVDDIO_P0        U25   -H57        A01X+134590Y+089662X0177Y    R180 S1      
327PVDDIO_P0        U25   -H64        A01X+131999Y+089662X0177Y    R180 S1      
327PVDDIO_P0        U25   -H71        A01X+129409Y+089662X0177Y    R180 S1      
327PVDDIO_P0        U25   -L58        A01X+134405Y+090618X0177Y    R180 S1      
327PVDDIO_P0        U25   -L65        A01X+131814Y+090618X0177Y    R180 S1      
327PVDDIO_P0        U25   -L72        A01X+129224Y+090618X0177Y    R180 S1      
327PVDDIO_P0        U25   -P57        A01X+134590Y+091575X0177Y    R180 S1      
327PVDDIO_P0        U25   -P64        A01X+131999Y+091575X0177Y    R180 S1      
327PVDDIO_P0        U25   -P71        A01X+129409Y+091575X0177Y    R180 S1      
327PVDDIO_P0        U25   -U58        A01X+134405Y+092532X0177Y    R180 S1      
327PVDDIO_P0        U25   -U65        A01X+131814Y+092532X0177Y    R180 S1      
327PVDDIO_P0        U25   -U72        A01X+129224Y+092532X0177Y    R180 S1      
327PVDDIO_P0        U25   -Y57        A01X+134590Y+093488X0177Y    R180 S1      
327PVDDIO_P0        U25   -Y64        A01X+131999Y+093488X0177Y    R180 S1      
327PVDDIO_P0        U25   -Y71        A01X+129409Y+093488X0177Y    R180 S1      
327PVDDIO_P0        VIA   -           A18X+108680Y+129738X0260Y    R180 S2      
327PVDDIO_P0        VIA   -           A18X+113630Y+129738X0260Y    R180 S2      
327PVDDIO_P0        PR410 -1          A18X+106397Y+132963X0198Y0197R270 S2      
327PVDDIO_P0        PC162 -1          A18X+118073Y+132553X0950Y1110R270 S2      
327PVDDIO_P0        PC166_-1          A18X+116623Y+132713X0400Y0500R090 S2      
327PVDDIO_P0        PC168_-1          A18X+114901Y+132715X0400Y0500R090 S2      
327PVDDIO_P0        PC169_-1          A18X+115672Y+132715X0400Y0500R090 S2      
327PVDDIO_P0        PC170_-1          A18X+114130Y+132715X0400Y0500R090 S2      
327PVDDIO_P0        PC190_-1          A18X+113360Y+132715X0400Y0500R090 S2      
327PVDDIO_P0        PC165 -1          A18X+111963Y+132563X0950Y1110R270 S2      
327PVDDIO_P0        PC192_-1          A18X+110573Y+132723X0400Y0500R090 S2      
327PVDDIO_P0        PC189_-1          A18X+109730Y+132715X0400Y0500R090 S2      
327PVDDIO_P0        PC160 -1          A18X+108353Y+132543X0950Y1110R270 S2      
327PVDDIO_P0        PC191_-1          A18X+106973Y+132713X0400Y0500R090 S2      
327PVDDIO_P0        VIA   -           A18X+118500Y+129738X0260Y    R180 S2      
317PVDDIO_P0        VIA   -    MD0100PA00X+119340Y+131536X0200Y         S0      
317PVDDIO_P0        VIA   -    MD0100PA00X+119340Y+131786X0200Y         S0      
317PVDDIO_P0        VIA   -    MD0100PA00X+119090Y+131786X0200Y         S0      
317PVDDIO_P0        VIA   -    MD0100PA00X+118840Y+131786X0200Y         S0      
317PVDDIO_P0        VIA   -    MD0100PA00X+117760Y+131786X0200Y         S0      
317PVDDIO_P0        VIA   -    MD0100PA00X+117510Y+131786X0200Y         S0      
317PVDDIO_P0        VIA   -    MD0100PA00X+117260Y+131536X0200Y         S0      
317PVDDIO_P0        VIA   -    MD0100PA00X+117260Y+131786X0200Y         S0      
317PVDDIO_P0        VIA   -    MD0100PA00X+116953Y+137991X0200Y    R180 S0      
327PVDDIO_P0        PR103 -2          A18X+116812Y+137709X0198Y0197R270 S2      
317PVDDIO_P0        VIA   -    MD0100PA00X+116050Y+131536X0200Y         S0      
317PVDDIO_P0        VIA   -    MD0100PA00X+116050Y+131786X0200Y         S0      
317PVDDIO_P0        VIA   -    MD0100PA00X+115550Y+131786X0200Y         S0      
317PVDDIO_P0        VIA   -    MD0100PA00X+115800Y+131786X0200Y         S0      
317PVDDIO_P0        VIA   -    MD0100PA00X+113970Y+131536X0200Y         S0      
317PVDDIO_P0        VIA   -    MD0100PA00X+113663Y+137991X0200Y    R180 S0      
327PVDDIO_P0        PR104 -2          A18X+113522Y+137709X0198Y0197R270 S2      
317PVDDIO_P0        VIA   -    MD0100PA00X+113970Y+131786X0200Y         S0      
317PVDDIO_P0        VIA   -    MD0100PA00X+114470Y+131786X0200Y         S0      
317PVDDIO_P0        VIA   -    MD0100PA00X+114220Y+131786X0200Y         S0      
317PVDDIO_P0        VIA   -    MD0100PA00X+112780Y+131536X0200Y         S0      
317PVDDIO_P0        VIA   -    MD0100PA00X+112780Y+131786X0200Y         S0      
317PVDDIO_P0        VIA   -    MD0100PA00X+112280Y+131786X0200Y         S0      
317PVDDIO_P0        VIA   -    MD0100PA00X+112530Y+131786X0200Y         S0      
317PVDDIO_P0        VIA   -    MD0100PA00X+110700Y+131536X0200Y         S0      
317PVDDIO_P0        VIA   -    MD0100PA00X+110393Y+137991X0200Y    R180 S0      
317PVDDIO_P0        VIA   -    MD0100PA00X+110700Y+131786X0200Y         S0      
327PVDDIO_P0        PR111 -2          A18X+110252Y+137709X0198Y0197R270 S2      
317PVDDIO_P0        VIA   -    MD0100PA00X+111200Y+131786X0200Y         S0      
317PVDDIO_P0        VIA   -    MD0100PA00X+110950Y+131786X0200Y         S0      
317PVDDIO_P0        VIA   -    MD0100PA00X+109520Y+131536X0200Y         S0      
317PVDDIO_P0        VIA   -    MD0100PA00X+109520Y+131786X0200Y         S0      
317PVDDIO_P0        VIA   -    MD0100PA00X+109020Y+131786X0200Y         S0      
317PVDDIO_P0        VIA   -    MD0100PA00X+109270Y+131786X0200Y         S0      
317PVDDIO_P0        VIA   -    MD0100PA00X+107440Y+131536X0200Y         S0      
317PVDDIO_P0        VIA   -    MD0100PA00X+107133Y+137991X0200Y    R180 S0      
317PVDDIO_P0        VIA   -    MD0100PA00X+107440Y+131786X0200Y         S0      
327PVDDIO_P0        PR112 -2          A18X+106992Y+137709X0198Y0197R270 S2      
317PVDDIO_P0        VIA   -    MD0100PA00X+107940Y+131786X0200Y         S0      
317PVDDIO_P0        VIA   -    MD0100PA00X+107690Y+131786X0200Y         S0      
317PVDDIO_P0        VIA   -    MD0100PA00X+119340Y+131286X0200Y         S0      
317PVDDIO_P0        VIA   -    MD0100PA00X+119340Y+131036X0200Y         S0      
317PVDDIO_P0        VIA   -    MD0100PA00X+119340Y+130786X0200Y         S0      
317PVDDIO_P0        VIA   -    MD0100PA00X+119340Y+130536X0200Y         S0      
317PVDDIO_P0        VIA   -    MD0100PA00X+119090Y+130536X0200Y         S0      
317PVDDIO_P0        VIA   -    MD0100PA00X+119340Y+130036X0200Y         S0      
317PVDDIO_P0        VIA   -    MD0100PA00X+119340Y+130286X0200Y         S0      
317PVDDIO_P0        VIA   -    MD0100PA00X+119090Y+130286X0200Y         S0      
317PVDDIO_P0        VIA   -    MD0100PA00X+119090Y+130036X0200Y         S0      
317PVDDIO_P0        VIA   -    MD0100PA00X+118840Y+130536X0200Y         S0      
317PVDDIO_P0        VIA   -    MD0100PA00X+118840Y+130036X0200Y         S0      
317PVDDIO_P0        VIA   -    MD0100PA00X+118840Y+130286X0200Y         S0      
317PVDDIO_P0        VIA   -    MD0100PA00X+117760Y+131536X0200Y         S0      
317PVDDIO_P0        VIA   -    MD0100PA00X+117510Y+131536X0200Y         S0      
317PVDDIO_P0        VIA   -    MD0100PA00X+118840Y+131536X0200Y         S0      
317PVDDIO_P0        VIA   -    MD0100PA00X+117760Y+130786X0200Y         S0      
317PVDDIO_P0        VIA   -    MD0100PA00X+117760Y+131036X0200Y         S0      
317PVDDIO_P0        VIA   -    MD0100PA00X+117760Y+131286X0200Y         S0      
317PVDDIO_P0        VIA   -    MD0100PA00X+117510Y+131286X0200Y         S0      
317PVDDIO_P0        VIA   -    MD0100PA00X+117510Y+131036X0200Y         S0      
317PVDDIO_P0        VIA   -    MD0100PA00X+117510Y+130786X0200Y         S0      
317PVDDIO_P0        VIA   -    MD0100PA00X+118840Y+130786X0200Y         S0      
317PVDDIO_P0        VIA   -    MD0100PA00X+118840Y+131036X0200Y         S0      
317PVDDIO_P0        VIA   -    MD0100PA00X+118840Y+131286X0200Y         S0      
317PVDDIO_P0        VIA   -    MD0100PA00X+119090Y+131536X0200Y         S0      
317PVDDIO_P0        VIA   -    MD0100PA00X+119090Y+131286X0200Y         S0      
317PVDDIO_P0        VIA   -    MD0100PA00X+119090Y+131036X0200Y         S0      
317PVDDIO_P0        VIA   -    MD0100PA00X+119090Y+130786X0200Y         S0      
327PVDDIO_P0        PL17  -4   M      A01X+118300Y+131161X0950Y1780R270 S1      
317PVDDIO_P0        VIA   -    MD0100PA00X+117760Y+130536X0200Y         S0      
317PVDDIO_P0        VIA   -    MD0100PA00X+117510Y+130536X0200Y         S0      
317PVDDIO_P0        VIA   -    MD0100PA00X+117760Y+130036X0200Y         S0      
317PVDDIO_P0        VIA   -    MD0100PA00X+117760Y+130286X0200Y         S0      
317PVDDIO_P0        VIA   -    MD0100PA00X+117510Y+130286X0200Y         S0      
317PVDDIO_P0        VIA   -    MD0100PA00X+117510Y+130036X0200Y         S0      
317PVDDIO_P0        VIA   -    MD0100PA00X+117260Y+131286X0200Y         S0      
317PVDDIO_P0        VIA   -    MD0100PA00X+117260Y+131036X0200Y         S0      
317PVDDIO_P0        VIA   -    MD0100PA00X+117260Y+130786X0200Y         S0      
317PVDDIO_P0        VIA   -    MD0100PA00X+117260Y+130536X0200Y         S0      
317PVDDIO_P0        VIA   -    MD0100PA00X+117260Y+130036X0200Y         S0      
317PVDDIO_P0        VIA   -    MD0100PA00X+117260Y+130286X0200Y         S0      
317PVDDIO_P0        VIA   -    MD0100PA00X+116050Y+131286X0200Y         S0      
317PVDDIO_P0        VIA   -    MD0100PA00X+116050Y+131036X0200Y         S0      
317PVDDIO_P0        VIA   -    MD0100PA00X+116050Y+130786X0200Y         S0      
317PVDDIO_P0        VIA   -    MD0100PA00X+116050Y+130536X0200Y         S0      
317PVDDIO_P0        VIA   -    MD0100PA00X+116050Y+130036X0200Y         S0      
317PVDDIO_P0        VIA   -    MD0100PA00X+116050Y+130286X0200Y         S0      
317PVDDIO_P0        VIA   -    MD0100PA00X+115550Y+130536X0200Y         S0      
317PVDDIO_P0        VIA   -    MD0100PA00X+115800Y+130536X0200Y         S0      
317PVDDIO_P0        VIA   -    MD0100PA00X+115550Y+130036X0200Y         S0      
317PVDDIO_P0        VIA   -    MD0100PA00X+115550Y+130286X0200Y         S0      
317PVDDIO_P0        VIA   -    MD0100PA00X+115800Y+130286X0200Y         S0      
317PVDDIO_P0        VIA   -    MD0100PA00X+115800Y+130036X0200Y         S0      
317PVDDIO_P0        VIA   -    MD0100PA00X+114470Y+131536X0200Y         S0      
317PVDDIO_P0        VIA   -    MD0100PA00X+114220Y+131536X0200Y         S0      
317PVDDIO_P0        VIA   -    MD0100PA00X+114470Y+130786X0200Y         S0      
317PVDDIO_P0        VIA   -    MD0100PA00X+114470Y+131036X0200Y         S0      
317PVDDIO_P0        VIA   -    MD0100PA00X+114470Y+131286X0200Y         S0      
317PVDDIO_P0        VIA   -    MD0100PA00X+114220Y+131286X0200Y         S0      
317PVDDIO_P0        VIA   -    MD0100PA00X+114220Y+131036X0200Y         S0      
317PVDDIO_P0        VIA   -    MD0100PA00X+114220Y+130786X0200Y         S0      
317PVDDIO_P0        VIA   -    MD0100PA00X+115550Y+131536X0200Y         S0      
317PVDDIO_P0        VIA   -    MD0100PA00X+115800Y+131536X0200Y         S0      
317PVDDIO_P0        VIA   -    MD0100PA00X+115550Y+130786X0200Y         S0      
317PVDDIO_P0        VIA   -    MD0100PA00X+115550Y+131036X0200Y         S0      
317PVDDIO_P0        VIA   -    MD0100PA00X+115550Y+131286X0200Y         S0      
317PVDDIO_P0        VIA   -    MD0100PA00X+115800Y+131286X0200Y         S0      
317PVDDIO_P0        VIA   -    MD0100PA00X+115800Y+131036X0200Y         S0      
317PVDDIO_P0        VIA   -    MD0100PA00X+115800Y+130786X0200Y         S0      
327PVDDIO_P0        PL18  -4   M      A01X+115010Y+131161X0950Y1780R270 S1      
317PVDDIO_P0        VIA   -    MD0100PA00X+113970Y+131286X0200Y         S0      
317PVDDIO_P0        VIA   -    MD0100PA00X+113970Y+131036X0200Y         S0      
317PVDDIO_P0        VIA   -    MD0100PA00X+113970Y+130786X0200Y         S0      
317PVDDIO_P0        VIA   -    MD0100PA00X+113970Y+130536X0200Y         S0      
317PVDDIO_P0        VIA   -    MD0100PA00X+114470Y+130536X0200Y         S0      
317PVDDIO_P0        VIA   -    MD0100PA00X+114220Y+130536X0200Y         S0      
317PVDDIO_P0        VIA   -    MD0100PA00X+113970Y+130036X0200Y         S0      
317PVDDIO_P0        VIA   -    MD0100PA00X+113970Y+130286X0200Y         S0      
317PVDDIO_P0        VIA   -    MD0100PA00X+114470Y+130036X0200Y         S0      
317PVDDIO_P0        VIA   -    MD0100PA00X+114470Y+130286X0200Y         S0      
317PVDDIO_P0        VIA   -    MD0100PA00X+114220Y+130286X0200Y         S0      
317PVDDIO_P0        VIA   -    MD0100PA00X+114220Y+130036X0200Y         S0      
317PVDDIO_P0        VIA   -    MD0100PA00X+112780Y+131286X0200Y         S0      
317PVDDIO_P0        VIA   -    MD0100PA00X+112780Y+131036X0200Y         S0      
317PVDDIO_P0        VIA   -    MD0100PA00X+112780Y+130786X0200Y         S0      
317PVDDIO_P0        VIA   -    MD0100PA00X+112780Y+130536X0200Y         S0      
317PVDDIO_P0        VIA   -    MD0100PA00X+112280Y+130536X0200Y         S0      
317PVDDIO_P0        VIA   -    MD0100PA00X+112530Y+130536X0200Y         S0      
317PVDDIO_P0        VIA   -    MD0100PA00X+112780Y+130036X0200Y         S0      
317PVDDIO_P0        VIA   -    MD0100PA00X+112780Y+130286X0200Y         S0      
317PVDDIO_P0        VIA   -    MD0100PA00X+112280Y+130036X0200Y         S0      
317PVDDIO_P0        VIA   -    MD0100PA00X+112280Y+130286X0200Y         S0      
317PVDDIO_P0        VIA   -    MD0100PA00X+112530Y+130286X0200Y         S0      
317PVDDIO_P0        VIA   -    MD0100PA00X+112530Y+130036X0200Y         S0      
317PVDDIO_P0        VIA   -    MD0100PA00X+110950Y+130036X0200Y         S0      
317PVDDIO_P0        VIA   -    MD0100PA00X+111200Y+130786X0200Y         S0      
317PVDDIO_P0        VIA   -    MD0100PA00X+111200Y+131036X0200Y         S0      
317PVDDIO_P0        VIA   -    MD0100PA00X+111200Y+131286X0200Y         S0      
317PVDDIO_P0        VIA   -    MD0100PA00X+110950Y+131286X0200Y         S0      
317PVDDIO_P0        VIA   -    MD0100PA00X+110950Y+131036X0200Y         S0      
317PVDDIO_P0        VIA   -    MD0100PA00X+110950Y+130786X0200Y         S0      
317PVDDIO_P0        VIA   -    MD0100PA00X+111200Y+131536X0200Y         S0      
317PVDDIO_P0        VIA   -    MD0100PA00X+110950Y+131536X0200Y         S0      
317PVDDIO_P0        VIA   -    MD0100PA00X+112280Y+131036X0200Y         S0      
317PVDDIO_P0        VIA   -    MD0100PA00X+112280Y+131286X0200Y         S0      
317PVDDIO_P0        VIA   -    MD0100PA00X+112530Y+131286X0200Y         S0      
317PVDDIO_P0        VIA   -    MD0100PA00X+112530Y+131036X0200Y         S0      
317PVDDIO_P0        VIA   -    MD0100PA00X+112530Y+130786X0200Y         S0      
317PVDDIO_P0        VIA   -    MD0100PA00X+112280Y+131536X0200Y         S0      
317PVDDIO_P0        VIA   -    MD0100PA00X+112530Y+131536X0200Y         S0      
317PVDDIO_P0        VIA   -    MD0100PA00X+112280Y+130786X0200Y         S0      
327PVDDIO_P0        PL21  -4   M      A01X+111740Y+131161X0950Y1780R270 S1      
317PVDDIO_P0        VIA   -    MD0100PA00X+110700Y+131286X0200Y         S0      
317PVDDIO_P0        VIA   -    MD0100PA00X+110700Y+131036X0200Y         S0      
317PVDDIO_P0        VIA   -    MD0100PA00X+110700Y+130786X0200Y         S0      
317PVDDIO_P0        VIA   -    MD0100PA00X+110700Y+130536X0200Y         S0      
317PVDDIO_P0        VIA   -    MD0100PA00X+111200Y+130536X0200Y         S0      
317PVDDIO_P0        VIA   -    MD0100PA00X+110950Y+130536X0200Y         S0      
317PVDDIO_P0        VIA   -    MD0100PA00X+110700Y+130036X0200Y         S0      
317PVDDIO_P0        VIA   -    MD0100PA00X+110700Y+130286X0200Y         S0      
317PVDDIO_P0        VIA   -    MD0100PA00X+111200Y+130036X0200Y         S0      
317PVDDIO_P0        VIA   -    MD0100PA00X+111200Y+130286X0200Y         S0      
317PVDDIO_P0        VIA   -    MD0100PA00X+110950Y+130286X0200Y         S0      
317PVDDIO_P0        VIA   -    MD0100PA00X+109520Y+131286X0200Y         S0      
317PVDDIO_P0        VIA   -    MD0100PA00X+109520Y+131036X0200Y         S0      
317PVDDIO_P0        VIA   -    MD0100PA00X+109520Y+130786X0200Y         S0      
317PVDDIO_P0        VIA   -    MD0100PA00X+109520Y+130536X0200Y         S0      
317PVDDIO_P0        VIA   -    MD0100PA00X+109020Y+130536X0200Y         S0      
317PVDDIO_P0        VIA   -    MD0100PA00X+109270Y+130536X0200Y         S0      
317PVDDIO_P0        VIA   -    MD0100PA00X+109520Y+130036X0200Y         S0      
317PVDDIO_P0        VIA   -    MD0100PA00X+109520Y+130286X0200Y         S0      
317PVDDIO_P0        VIA   -    MD0100PA00X+109020Y+130036X0200Y         S0      
317PVDDIO_P0        VIA   -    MD0100PA00X+109020Y+130286X0200Y         S0      
317PVDDIO_P0        VIA   -    MD0100PA00X+109270Y+130286X0200Y         S0      
317PVDDIO_P0        VIA   -    MD0100PA00X+109270Y+130036X0200Y         S0      
317PVDDIO_P0        VIA   -    MD0100PA00X+107690Y+130786X0200Y         S0      
317PVDDIO_P0        VIA   -    MD0100PA00X+107690Y+131036X0200Y         S0      
317PVDDIO_P0        VIA   -    MD0100PA00X+107690Y+131286X0200Y         S0      
317PVDDIO_P0        VIA   -    MD0100PA00X+107940Y+131286X0200Y         S0      
317PVDDIO_P0        VIA   -    MD0100PA00X+107940Y+131036X0200Y         S0      
317PVDDIO_P0        VIA   -    MD0100PA00X+107940Y+130786X0200Y         S0      
317PVDDIO_P0        VIA   -    MD0100PA00X+107690Y+131536X0200Y         S0      
317PVDDIO_P0        VIA   -    MD0100PA00X+107940Y+131536X0200Y         S0      
317PVDDIO_P0        VIA   -    MD0100PA00X+109270Y+131536X0200Y         S0      
317PVDDIO_P0        VIA   -    MD0100PA00X+109020Y+131536X0200Y         S0      
317PVDDIO_P0        VIA   -    MD0100PA00X+109270Y+130786X0200Y         S0      
317PVDDIO_P0        VIA   -    MD0100PA00X+109270Y+131036X0200Y         S0      
317PVDDIO_P0        VIA   -    MD0100PA00X+109270Y+131286X0200Y         S0      
317PVDDIO_P0        VIA   -    MD0100PA00X+109020Y+131286X0200Y         S0      
317PVDDIO_P0        VIA   -    MD0100PA00X+109020Y+131036X0200Y         S0      
317PVDDIO_P0        VIA   -    MD0100PA00X+109020Y+130786X0200Y         S0      
327PVDDIO_P0        PL20  -4   M      A01X+108480Y+131161X0950Y1780R270 S1      
317PVDDIO_P0        VIA   -    MD0100PA00X+107440Y+131286X0200Y         S0      
317PVDDIO_P0        VIA   -    MD0100PA00X+107440Y+131036X0200Y         S0      
317PVDDIO_P0        VIA   -    MD0100PA00X+107440Y+130786X0200Y         S0      
317PVDDIO_P0        VIA   -    MD0100PA00X+107440Y+130536X0200Y         S0      
317PVDDIO_P0        VIA   -    MD0100PA00X+107940Y+130536X0200Y         S0      
317PVDDIO_P0        VIA   -    MD0100PA00X+107690Y+130536X0200Y         S0      
317PVDDIO_P0        VIA   -    MD0100PA00X+107440Y+130036X0200Y         S0      
317PVDDIO_P0        VIA   -    MD0100PA00X+107440Y+130286X0200Y         S0      
317PVDDIO_P0        VIA   -    MD0100PA00X+107940Y+130036X0200Y         S0      
317PVDDIO_P0        VIA   -    MD0100PA00X+107940Y+130286X0200Y         S0      
317PVDDIO_P0        VIA   -    MD0100PA00X+107690Y+130286X0200Y         S0      
317PVDDIO_P0        VIA   -    MD0100PA00X+107690Y+130036X0200Y         S0      
317PVDDIO_P0        VIA   -    MD0100PA00X+140102Y+101888X0190Y    R180 S0      
317PVDDIO_P0        VIA   -    MD0100PA00X+140102Y+102301X0190Y    R180 S0      
317PVDDIO_P0        VIA   -    MD0100PA00X+139146Y+101724X0190Y    R270 S0      
317PVDDIO_P0        VIA   -    MD0100PA00X+139146Y+102846X0190Y    R270 S0      
317PVDDIO_P0        VIA   -    MD0100PA00X+139146Y+102472X0190Y    R270 S0      
317PVDDIO_P0        VIA   -    MD0100PA00X+139146Y+102098X0190Y    R270 S0      
317PVDDIO_P0        VIA   -    MD0100PA00X+137000Y+101902X0190Y    R180 S0      
317PVDDIO_P0        VIA   -    MD0100PA00X+137000Y+102256X0190Y    R180 S0      
317PVDDIO_P0        VIA   -    MD0100PA00X+137748Y+101902X0190Y    R180 S0      
317PVDDIO_P0        VIA   -    MD0100PA00X+137748Y+102256X0190Y    R180 S0      
317PVDDIO_P0        VIA   -    MD0100PA00X+136252Y+101902X0190Y    R180 S0      
317PVDDIO_P0        VIA   -    MD0100PA00X+136252Y+102256X0190Y    R180 S0      
317PVDDIO_P0        VIA   -    MD0100PA00X+139146Y+101350X0190Y    R270 S0      
317PVDDIO_P0        VIA   -    MD0100PA00X+137000Y+101547X0190Y    R180 S0      
317PVDDIO_P0        VIA   -    MD0100PA00X+137748Y+101547X0190Y    R180 S0      
317PVDDIO_P0        VIA   -    MD0100PA00X+136252Y+101547X0190Y    R180 S0      
327m3742            PU32  -1          A01X+053080Y+060731X0090Y0240R270 S1      
327m3742            PR216 -1          A18X+053577Y+060735X0198Y0197R090 S2      
317m3742            VIA   -    MD0100PA00X+053208Y+060490X0200Y    R180 S0      
327m3743            PU31  -1          A01X+049750Y+064141X0090Y0240R270 S1      
327m3743            PR212 -1          A18X+050247Y+064145X0198Y0197R090 S2      
317m3743            VIA   -    MD0100PA00X+049878Y+063900X0200Y    R180 S0      
327m3744            PU30  -1          A01X+046490Y+066791X0090Y0240R270 S1      
327m3744            PR211 -1          A18X+046987Y+066795X0198Y0197R090 S2      
317m3744            VIA   -    MD0100PA00X+046618Y+066550X0200Y    R180 S0      
327m3745            VIA   -    M      A18X+052475Y+060494X0260Y         S2      
327m3745            PU32  -3          A01X+053080Y+061085X0090Y0240R270 S1      
327m3745            PC346 -1          A01X+053586Y+060735X0198Y0197R270 S1      
327m3745            PR213 -2   M      A18X+053045Y+061052X0198Y0197R090 S2      
317m3745            VIA   -    MD0100PA00X+053586Y+060975X0200Y    R180 S0      
317m3745            VIA   -    MD0100PA00X+052240Y+060175X0200Y    R180 S0      
327m3745            PU32  -35         A01X+052210Y+060485X0090Y0240R180 S1      
327m3746            VIA   -    M      A18X+049098Y+063904X0260Y         S2      
327m3746            PU31  -3          A01X+049750Y+064495X0090Y0240R270 S1      
327m3746            PC320 -1          A01X+050256Y+064145X0198Y0197R270 S1      
327m3746            PR206 -2   M      A18X+049715Y+064462X0198Y0197R090 S2      
317m3746            VIA   -    MD0100PA00X+050256Y+064385X0200Y    R180 S0      
317m3746            VIA   -    MD0100PA00X+048910Y+063585X0200Y    R180 S0      
327m3746            PU31  -35         A01X+048880Y+063895X0090Y0240R180 S1      
327m3747            VIA   -    M      A18X+045736Y+066554X0260Y         S2      
327m3747            PC319 -1          A01X+046996Y+066795X0198Y0197R270 S1      
327m3747            PU30  -3          A01X+046490Y+067145X0090Y0240R270 S1      
327m3747            PU30  -35         A01X+045620Y+066545X0090Y0240R180 S1      
327m3747            PR205 -2   M      A18X+046455Y+067112X0198Y0197R090 S2      
317m3747            VIA   -    MD0100PA00X+045650Y+066235X0200Y    R180 S0      
317m3747            VIA   -    MD0100PA00X+046996Y+067035X0200Y    R180 S0      
317m3748            VIA   -    MD0100PA00X+045924Y+066138X0200Y         S0      
317m3748            VIA   -    M      A01X+039417Y+056848X0200Y    R180 S2      
017m3748            VIA   -    M      A18X+039417Y+056848X0260Y    R180 S2      
017m3748                  -    MD0100PA00X+039417Y+056848                       
327m3748            PU30  -36         A01X+045798Y+066545X0090Y0240R180 S1      
327m3748            PU31  -36         A01X+049058Y+063895X0090Y0240R180 S1      
317m3748            VIA   -    MD0100PA00X+049184Y+063488X0200Y         S0      
327m3748            PU32  -36         A01X+052388Y+060485X0090Y0240R180 S1      
317m3748            VIA   -    MD0100PA00X+052514Y+060078X0200Y         S0      
327m3748            PC253 -1          A18X+039758Y+056942X0198Y0197R180 S2      
327m3748            PU25  -43         A18X+038798Y+056913X0070Y0260R270 S2      
327m3749            PU32  -34         A01X+052033Y+060485X0090Y0240R180 S1      
317m3749            VIA   -    MD0100PA00X+052165Y+059918X0200Y    R180 S0      
317m3749            VIA   -    MD0100PA00X+038016Y+055309X0200Y    R180 S0      
327m3749            PU25  -3          A18X+038217Y+055860X0070Y0260     S2      
317m3750            VIA   -    MD0100PA00X+038307Y+055374X0200Y    R180 S0      
327m3750            PU25  -2          A18X+038374Y+055860X0070Y0260     S2      
327m3750            PU31  -34         A01X+048703Y+063895X0090Y0240R180 S1      
317m3750            VIA   -    MD0100PA00X+048835Y+063328X0200Y    R180 S0      
327m3751            PU25  -1          A18X+038532Y+055860X0070Y0260     S2      
317m3751            VIA   -    MD0100PA00X+038532Y+055524X0200Y    R180 S0      
327m3751            PU30  -34         A01X+045443Y+066545X0090Y0240R180 S1      
317m3751            VIA   -    MD0100PA00X+045575Y+065978X0200Y    R180 S0      
327m3752            PR214 -2          A01X+052807Y+059575X0198Y0197     S1      
327m3752            PU32  -37         A01X+052565Y+060485X0090Y0240R180 S1      
327m3752            VIA   -    M      A01X+052711Y+060008X0160Y0041R090 S1      
327m3753            PR208 -2          A01X+049477Y+062985X0198Y0197     S1      
327m3753            PU31  -37         A01X+049235Y+063895X0090Y0240R180 S1      
327m3753            VIA   -    M      A01X+049381Y+063433X0160Y0041R090 S1      
327m3754            PU30  -37         A01X+045975Y+066545X0090Y0240R180 S1      
327m3754            PR207 -2          A01X+046217Y+065635X0198Y0197     S1      
327m3754            VIA   -    M      A01X+046121Y+066076X0160Y0041R090 S1      
317m3755            VIA   -    MD0100PA00X+052924Y+060154X0200Y    R180 S0      
327m3755            PU32  -38         A01X+052742Y+060485X0090Y0240R180 S1      
317m3755            VIA   -    M      A01X+038710Y+058451X0300Y    R180 S1      
017m3755            VIA   -    M      A18X+038710Y+058451X0200Y    R180 S1      
017m3755                  -    MD0100PA00X+038710Y+058451                       
327m3755            PU25  -36         A18X+038532Y+058123X0070Y0260     S2      
327m3756            PU25  -37         A18X+038798Y+057858X0070Y0260R270 S2      
317m3756            VIA   -    MD0100PA00X+039102Y+058879X0200Y    R180 S0      
317m3756            VIA   -    MD0100PA00X+049584Y+063532X0200Y         S2      
327m3756            PU31  -38         A01X+049412Y+063895X0090Y0240R180 S1      
327m3757            PU25  -38         A18X+038798Y+057700X0070Y0260R270 S2      
317m3757            VIA   -    MD0100PA00X+039247Y+059699X0200Y    R180 S0      
317m3757            VIA   -    MD0100PA00X+046319Y+066182X0200Y         S2      
327m3757            PU30  -38         A01X+046152Y+066545X0090Y0240R180 S1      
327m3758            R6087 -1   M      A01X+038077Y+053721X0198Y0197R270 S1      
327m3758            PQ15  -G          A01X+038744Y+053988X0400Y0560R270 S1      
327m3758            VIA   -    M      A01X+038077Y+054214X0300Y         S1      
327m3758            C242  -1   M      A01X+037594Y+053727X0198Y0197R270 S1      
327m3758            R149  -2          A01X+037196Y+053724X0198Y0197R090 S1      
327m3759            PR152 -2   M      A01X+041277Y+053421X0198Y0197R090 S1      
327m3759            PQ11  -G          A01X+041853Y+053270X0320Y0360     S1      
327m3759            PQ15  -D          A01X+039610Y+053614X0400Y0560R270 S1      
327m3759            VIA   -    M      A01X+040651Y+053421X0300Y    R180 S1      
317m3760            VIA   -    MD0100PA00X+039348Y+057124X0200Y    R180 S0      
327m3760            PU25  -42         A18X+038798Y+057070X0070Y0260R270 S2      
327m3760            PR159 -1   M      A01X+039053Y+057112X0198Y0197R180 S1      
327m3760            PQ11  -D          A01X+042227Y+054058X0320Y0360     S1      
327m3760            VIA   -    M      A01X+039360Y+057947X0300Y    R180 S1      
317m3761            VIA   -    M      A01X+037196Y+052495X0300Y         S1      
017m3761            VIA   -    M      A18X+037196Y+052495X0200Y         S1      
017m3761                  -    MD0100PA00X+037196Y+052495                       
327m3761            R149  -1          A01X+037196Y+053409X0198Y0197R090 S1      
327m3761            U18   -C15        A01X+070363Y+046399X0160Y    R090 S1      
317m3761            VIA   -    MD0100PA00X+070210Y+046552X0180Y    R090 S0      
317m3761            VIA   -    MD0100PA00X+054775Y+047268X0200Y         S0      
317PVDDCR_SOC_P1    VIA   -    MD0080PA00X+040308Y+100718X0160Y    R180 S0      
317PVDDCR_SOC_P1    VIA   -    MD0080PA00X+040676Y+100718X0160Y    R180 S0      
317PVDDCR_SOC_P1    VIA   -    MD0080PA00X+039752Y+100399X0160Y    R180 S0      
317PVDDCR_SOC_P1    VIA   -    MD0080PA00X+040308Y+100080X0160Y    R180 S0      
317PVDDCR_SOC_P1    VIA   -    MD0080PA00X+040308Y+099443X0160Y    R180 S0      
317PVDDCR_SOC_P1    VIA   -    MD0080PA00X+039752Y+099762X0160Y    R180 S0      
317PVDDCR_SOC_P1    VIA   -    MD0080PA00X+040492Y+099124X0160Y    R180 S0      
317PVDDCR_SOC_P1    VIA   -    MD0080PA00X+040241Y+103443X0160Y         S0      
317PVDDCR_SOC_P1    VIA   -    MD0080PA00X+040426Y+103124X0160Y         S0      
317PVDDCR_SOC_P1    VIA   -    MD0080PA00X+040426Y+103762X0160Y         S0      
317PVDDCR_SOC_P1    VIA   -    MD0080PA00X+040609Y+103444X0160Y         S0      
317PVDDCR_SOC_P1    VIA   -    MD0080PA00X+040241Y+102806X0160Y         S0      
317PVDDCR_SOC_P1    VIA   -    MD0080PA00X+040609Y+102806X0160Y         S0      
317PVDDCR_SOC_P1    VIA   -    MD0080PA00X+040122Y+101037X0160Y    R180 S0      
317PVDDCR_SOC_P1    VIA   -    MD0080PA00X+041973Y+099124X0160Y    R180 S0      
317PVDDCR_SOC_P1    VIA   -    MD0080PA00X+041972Y+099761X0160Y    R180 S0      
317PVDDCR_SOC_P1    VIA   -    MD0080PA00X+041233Y+099124X0160Y    R180 S0      
317PVDDCR_SOC_P1    VIA   -    MD0080PA00X+041232Y+099761X0160Y    R180 S0      
317PVDDCR_SOC_P1    VIA   -    MD0080PA00X+043452Y+099761X0160Y    R180 S0      
317PVDDCR_SOC_P1    VIA   -    MD0080PA00X+042713Y+099124X0160Y    R180 S0      
317PVDDCR_SOC_P1    VIA   -    MD0080PA00X+042712Y+099761X0160Y    R180 S0      
317PVDDCR_SOC_P1    VIA   -    MD0080PA00X+043453Y+099124X0160Y    R180 S0      
317PVDDCR_SOC_P1    VIA   -    MD0080PA00X+043268Y+098805X0160Y    R180 S0      
317PVDDCR_SOC_P1    VIA   -    MD0080PA00X+044931Y+099124X0160Y    R180 S0      
317PVDDCR_SOC_P1    VIA   -    MD0080PA00X+045116Y+098805X0160Y    R180 S0      
317PVDDCR_SOC_P1    VIA   -    MD0080PA00X+044932Y+099761X0160Y    R180 S0      
317PVDDCR_SOC_P1    VIA   -    MD0080PA00X+046411Y+099124X0160Y    R180 S0      
317PVDDCR_SOC_P1    VIA   -    MD0080PA00X+046596Y+098805X0160Y    R180 S0      
317PVDDCR_SOC_P1    VIA   -    MD0080PA00X+046413Y+099761X0160Y    R180 S0      
317PVDDCR_SOC_P1    VIA   -    MD0080PA00X+045671Y+099124X0160Y    R180 S0      
317PVDDCR_SOC_P1    VIA   -    MD0080PA00X+045672Y+099761X0160Y    R180 S0      
317PVDDCR_SOC_P1    VIA   -    MD0080PA00X+048077Y+100718X0160Y    R180 S0      
317PVDDCR_SOC_P1    VIA   -    MD0080PA00X+047892Y+101037X0160Y    R180 S0      
317PVDDCR_SOC_P1    VIA   -    MD0080PA00X+047892Y+100399X0160Y    R180 S0      
317PVDDCR_SOC_P1    VIA   -    MD0080PA00X+048077Y+100080X0160Y    R180 S0      
317PVDDCR_SOC_P1    VIA   -    MD0080PA00X+048077Y+098805X0160Y    R180 S0      
317PVDDCR_SOC_P1    VIA   -    MD0080PA00X+048077Y+099443X0160Y    R180 S0      
317PVDDCR_SOC_P1    VIA   -    MD0080PA00X+047892Y+099124X0160Y    R180 S0      
317PVDDCR_SOC_P1    VIA   -    MD0080PA00X+047892Y+099762X0160Y    R180 S0      
317PVDDCR_SOC_P1    VIA   -    MD0080PA00X+047152Y+099124X0160Y    R180 S0      
317PVDDCR_SOC_P1    VIA   -    MD0080PA00X+047153Y+099761X0160Y    R180 S0      
317PVDDCR_SOC_P1    VIA   -    MD0080PA00X+047825Y+103124X0160Y         S0      
317PVDDCR_SOC_P1    VIA   -    MD0080PA00X+048380Y+102806X0160Y         S0      
317PVDDCR_SOC_P1    VIA   -    MD0080PA00X+049927Y+093702X0160Y    R180 S0      
317PVDDCR_SOC_P1    VIA   -    MD0080PA00X+049557Y+100080X0160Y    R180 S0      
317PVDDCR_SOC_P1    VIA   -    MD0080PA00X+049557Y+098805X0160Y    R180 S0      
317PVDDCR_SOC_P1    VIA   -    MD0080PA00X+049557Y+099443X0160Y    R180 S0      
317PVDDCR_SOC_P1    VIA   -    MD0080PA00X+048817Y+100080X0160Y    R180 S0      
317PVDDCR_SOC_P1    VIA   -    MD0080PA00X+049372Y+099124X0160Y    R180 S0      
317PVDDCR_SOC_P1    VIA   -    MD0080PA00X+048632Y+099124X0160Y    R180 S0      
317PVDDCR_SOC_P1    VIA   -    MD0080PA00X+049372Y+099762X0160Y    R180 S0      
317PVDDCR_SOC_P1    VIA   -    MD0080PA00X+048632Y+099762X0160Y    R180 S0      
317PVDDCR_SOC_P1    VIA   -    MD0080PA00X+048817Y+099443X0160Y    R180 S0      
317PVDDCR_SOC_P1    VIA   -    MD0080PA00X+049860Y+103443X0160Y         S0      
317PVDDCR_SOC_P1    VIA   -    MD0080PA00X+049120Y+103443X0160Y         S0      
317PVDDCR_SOC_P1    VIA   -    MD0080PA00X+049305Y+103124X0160Y         S0      
317PVDDCR_SOC_P1    VIA   -    MD0080PA00X+048565Y+103124X0160Y         S0      
317PVDDCR_SOC_P1    VIA   -    MD0080PA00X+049860Y+102806X0160Y         S0      
317PVDDCR_SOC_P1    VIA   -    MD0080PA00X+049120Y+102806X0160Y         S0      
317PVDDCR_SOC_P1    VIA   -    MD0080PA00X+049557Y+100718X0160Y    R180 S0      
317PVDDCR_SOC_P1    VIA   -    MD0080PA00X+049372Y+101037X0160Y    R180 S0      
317PVDDCR_SOC_P1    VIA   -    MD0080PA00X+049372Y+100399X0160Y    R180 S0      
317PVDDCR_SOC_P1    VIA   -    MD0080PA00X+048632Y+101037X0160Y    R180 S0      
317PVDDCR_SOC_P1    VIA   -    MD0080PA00X+048632Y+100399X0160Y    R180 S0      
317PVDDCR_SOC_P1    VIA   -    MD0080PA00X+048817Y+100718X0160Y    R180 S0      
317PVDDCR_SOC_P1    VIA   -    MD0080PA00X+051222Y+089557X0160Y    R180 S0      
317PVDDCR_SOC_P1    VIA   -    MD0080PA00X+050112Y+091470X0160Y    R180 S0      
317PVDDCR_SOC_P1    VIA   -    MD0080PA00X+051407Y+092427X0160Y    R180 S0      
317PVDDCR_SOC_P1    VIA   -    MD0080PA00X+051222Y+091470X0160Y    R180 S0      
317PVDDCR_SOC_P1    VIA   -    MD0080PA00X+050112Y+090195X0160Y    R180 S0      
317PVDDCR_SOC_P1    VIA   -    MD0080PA00X+051407Y+090514X0160Y    R180 S0      
317PVDDCR_SOC_P1    VIA   -    MD0080PA00X+050112Y+092746X0160Y    R180 S0      
317PVDDCR_SOC_P1    VIA   -    MD0080PA00X+051222Y+093384X0160Y    R180 S0      
317PVDDCR_SOC_P1    VIA   -    MD0080PA00X+050112Y+094659X0160Y    R180 S0      
317PVDDCR_SOC_P1    VIA   -    MD0080PA00X+051222Y+095297X0160Y    R180 S0      
317PVDDCR_SOC_P1    VIA   -    MD0080PA00X+051407Y+094340X0160Y    R180 S0      
317PVDDCR_SOC_P1    VIA   -    MD0080PA00X+050112Y+098486X0160Y    R180 S0      
317PVDDCR_SOC_P1    VIA   -    MD0080PA00X+050112Y+097210X0160Y    R180 S0      
317PVDDCR_SOC_P1    VIA   -    MD0080PA00X+051222Y+097210X0160Y    R180 S0      
317PVDDCR_SOC_P1    VIA   -    MD0080PA00X+051407Y+098167X0160Y    R180 S0      
317PVDDCR_SOC_P1    VIA   -    MD0080PA00X+050112Y+095935X0160Y    R180 S0      
317PVDDCR_SOC_P1    VIA   -    MD0080PA00X+051407Y+096254X0160Y    R180 S0      
317PVDDCR_SOC_P1    VIA   -    MD0080PA00X+050112Y+100399X0160Y    R180 S0      
317PVDDCR_SOC_P1    VIA   -    MD0080PA00X+051407Y+100080X0160Y    R180 S0      
317PVDDCR_SOC_P1    VIA   -    MD0080PA00X+051222Y+099124X0160Y    R180 S0      
317PVDDCR_SOC_P1    VIA   -    MD0080PA00X+050112Y+099124X0160Y    R180 S0      
317PVDDCR_SOC_P1    VIA   -    MD0080PA00X+050112Y+099762X0160Y    R180 S0      
317PVDDCR_SOC_P1    VIA   -    MD0080PA00X+050045Y+103124X0160Y         S0      
317PVDDCR_SOC_P1    VIA   -    MD0080PA00X+051222Y+101037X0160Y    R180 S0      
317PVDDCR_SOC_P1    VIA   -    MD0080PA00X+050112Y+101037X0160Y    R180 S0      
317PVDDCR_SOC_P1    VIA   -    MD0080PA00X+053813Y+091470X0160Y    R180 S0      
317PVDDCR_SOC_P1    VIA   -    MD0080PA00X+053998Y+092427X0160Y    R180 S0      
317PVDDCR_SOC_P1    VIA   -    MD0080PA00X+053998Y+090514X0160Y    R180 S0      
317PVDDCR_SOC_P1    VIA   -    MD0080PA00X+053998Y+088600X0160Y    R180 S0      
317PVDDCR_SOC_P1    VIA   -    MD0080PA00X+053813Y+089557X0160Y    R180 S0      
317PVDDCR_SOC_P1    VIA   -    MD0080PA00X+053998Y+094340X0160Y    R180 S0      
317PVDDCR_SOC_P1    VIA   -    MD0080PA00X+053813Y+095297X0160Y    R180 S0      
317PVDDCR_SOC_P1    VIA   -    MD0080PA00X+053813Y+093384X0160Y    R180 S0      
317PVDDCR_SOC_P1    VIA   -    MD0080PA00X+053998Y+098167X0160Y    R180 S0      
317PVDDCR_SOC_P1    VIA   -    MD0080PA00X+053813Y+097210X0160Y    R180 S0      
317PVDDCR_SOC_P1    VIA   -    MD0080PA00X+053998Y+096254X0160Y    R180 S0      
317PVDDCR_SOC_P1    VIA   -    MD0080PA00X+053813Y+101037X0160Y    R180 S0      
317PVDDCR_SOC_P1    VIA   -    MD0080PA00X+053813Y+099124X0160Y    R180 S0      
317PVDDCR_SOC_P1    VIA   -    MD0080PA00X+053998Y+100080X0160Y    R180 S0      
317PVDDCR_SOC_P1    VIA   -    MD0080PA00X+054116Y+103762X0160Y         S0      
317PVDDCR_SOC_P1    VIA   -    MD0080PA00X+056588Y+090514X0160Y    R180 S0      
317PVDDCR_SOC_P1    VIA   -    MD0080PA00X+056588Y+088600X0160Y    R180 S0      
317PVDDCR_SOC_P1    VIA   -    MD0080PA00X+056403Y+089557X0160Y    R180 S0      
317PVDDCR_SOC_P1    VIA   -    MD0080PA00X+056403Y+087644X0160Y    R180 S0      
317PVDDCR_SOC_P1    VIA   -    MD0080PA00X+056588Y+087962X0160Y    R180 S0      
317PVDDCR_SOC_P1    VIA   -    MD0080PA00X+056403Y+093384X0160Y    R180 S0      
317PVDDCR_SOC_P1    VIA   -    MD0080PA00X+056403Y+091470X0160Y    R180 S0      
317PVDDCR_SOC_P1    VIA   -    MD0080PA00X+056588Y+092427X0160Y    R180 S0      
317PVDDCR_SOC_P1    VIA   -    MD0080PA00X+056403Y+097210X0160Y    R180 S0      
317PVDDCR_SOC_P1    VIA   -    MD0080PA00X+056588Y+098167X0160Y    R180 S0      
317PVDDCR_SOC_P1    VIA   -    MD0080PA00X+056588Y+096254X0160Y    R180 S0      
317PVDDCR_SOC_P1    VIA   -    MD0080PA00X+056588Y+094340X0160Y    R180 S0      
317PVDDCR_SOC_P1    VIA   -    MD0080PA00X+056403Y+095297X0160Y    R180 S0      
317PVDDCR_SOC_P1    VIA   -    MD0080PA00X+056707Y+103762X0160Y         S0      
317PVDDCR_SOC_P1    VIA   -    MD0080PA00X+056403Y+101037X0160Y    R180 S0      
317PVDDCR_SOC_P1    VIA   -    MD0080PA00X+056403Y+099124X0160Y    R180 S0      
317PVDDCR_SOC_P1    VIA   -    MD0080PA00X+056588Y+100080X0160Y    R180 S0      
317PVDDCR_SOC_P1    VIA   -    MD0080PA00X+056522Y+104719X0160Y         S0      
327PVDDCR_SOC_P1    C2258 -1   M      A18X+042723Y+099777X0198Y0197     S2      
327PVDDCR_SOC_P1    C2259 -1   M      A18X+047123Y+099127X0198Y0197     S2      
327PVDDCR_SOC_P1    C2263 -1   M      A18X+043140Y+100635X0198Y0197R270 S2      
327PVDDCR_SOC_P1    C2264 -1   M      A18X+044372Y+101474X0198Y0197R180 S2      
327PVDDCR_SOC_P1    C2268 -1   M      A18X+043851Y+099377X0198Y0197R180 S2      
327PVDDCR_SOC_P1    C2269 -1          A01X+046573Y+102108X0198Y0197R180 S1      
327PVDDCR_SOC_P1    C2272 -1   M      A18X+043851Y+099777X0198Y0197R180 S2      
327PVDDCR_SOC_P1    C2273 -1          A01X+046573Y+102856X0198Y0197R180 S1      
327PVDDCR_SOC_P1    C2276 -1   M      A18X+044372Y+101888X0198Y0197R180 S2      
327PVDDCR_SOC_P1    C2277 -1   M      A18X+043858Y+098977X0198Y0197R180 S2      
327PVDDCR_SOC_P1    C2280 -1   M      A18X+047123Y+099777X0198Y0197     S2      
327PVDDCR_SOC_P1    C2281 -1   M      A18X+044923Y+099127X0198Y0197     S2      
327PVDDCR_SOC_P1    C2283 -1          A01X+046573Y+100612X0198Y0197R180 S1      
327PVDDCR_SOC_P1    C2284 -1   M      A18X+044923Y+099777X0198Y0197     S2      
327PVDDCR_SOC_P1    C2286 -1          A01X+046573Y+102482X0198Y0197R180 S1      
327PVDDCR_SOC_P1    C2288 -1          A01X+046573Y+101734X0198Y0197R180 S1      
327PVDDCR_SOC_P1    C2290 -1          A01X+046573Y+100986X0198Y0197R180 S1      
327PVDDCR_SOC_P1    C2407 -1   M      A18X+045396Y+101474X0198Y0197R180 S2      
327PVDDCR_SOC_P1    C2408 -1   M      A18X+042392Y+100635X0198Y0197R270 S2      
327PVDDCR_SOC_P1    C2409 -1   M      A18X+040321Y+099441X0198Y0197R060 S2      
327PVDDCR_SOC_P1    C2410 -1          A01X+043140Y+100635X0198Y0197R090 S1      
327PVDDCR_SOC_P1    C2411 -1   M      A18X+041223Y+099127X0198Y0197     S2      
327PVDDCR_SOC_P1    C2412 -1          A01X+042392Y+100635X0198Y0197R090 S1      
327PVDDCR_SOC_P1    C2413 -1   M      A18X+045673Y+099127X0198Y0197     S2      
327PVDDCR_SOC_P1    C2414 -1   M      A18X+046573Y+098777X0198Y0197     S2      
327PVDDCR_SOC_P1    C2415 -1   M      A18X+046373Y+099777X0198Y0197     S2      
327PVDDCR_SOC_P1    C2416 -1   M      A18X+040658Y+103427X0198Y0197R180 S2      
327PVDDCR_SOC_P1    C2417 -1   M      A18X+042766Y+100635X0198Y0197R270 S2      
327PVDDCR_SOC_P1    C2418 -1   M      A18X+045384Y+100635X0198Y0197R270 S2      
327PVDDCR_SOC_P1    C2419 -1   M      A18X+043851Y+100177X0198Y0197R180 S2      
327PVDDCR_SOC_P1    C2420 -1   M      A18X+046573Y+102108X0198Y0197     S2      
327PVDDCR_SOC_P1    C2421 -1   M      A18X+040336Y+100062X0198Y0197R300 S2      
327PVDDCR_SOC_P1    C2422 -1          A01X+046573Y+101360X0198Y0197R180 S1      
327PVDDCR_SOC_P1    C2423 -1          A01X+045396Y+101474X0198Y0197     S1      
327PVDDCR_SOC_P1    C2424 -1   M      A18X+046573Y+100612X0198Y0197     S2      
327PVDDCR_SOC_P1    C2425 -1   M      A18X+049523Y+101902X0198Y0197     S2      
327PVDDCR_SOC_P1    C2426 -1   M      A18X+045673Y+099777X0198Y0197     S2      
327PVDDCR_SOC_P1    C2427 -1          A01X+043487Y+101474X0198Y0197     S1      
327PVDDCR_SOC_P1    C2428 -1          A01X+045396Y+101888X0198Y0197     S1      
327PVDDCR_SOC_P1    C2429 -1   M      A18X+048823Y+099427X0198Y0197     S2      
327PVDDCR_SOC_P1    C2430 -1   M      A18X+046573Y+100986X0198Y0197     S2      
327PVDDCR_SOC_P1    C2431 -1   M      A18X+043514Y+100635X0198Y0197R270 S2      
327PVDDCR_SOC_P1    C2432 -1   M      A18X+048823Y+102256X0198Y0197     S2      
327PVDDCR_SOC_P1    C2433 -1   M      A18X+043487Y+101474X0198Y0197R180 S2      
327PVDDCR_SOC_P1    C2434 -1          A01X+045384Y+100635X0198Y0197R090 S1      
327PVDDCR_SOC_P1    C2435 -1   M      A18X+049268Y+103124X0198Y0197     S2      
327PVDDCR_SOC_P1    C2436 -1   M      A18X+041973Y+099777X0198Y0197     S2      
327PVDDCR_SOC_P1    C2437 -1   M      A18X+046573Y+102856X0198Y0197     S2      
327PVDDCR_SOC_P1    C2438 -1   M      A18X+042723Y+099127X0198Y0197     S2      
327PVDDCR_SOC_P1    C2439 -1          A01X+044636Y+100635X0198Y0197R090 S1      
327PVDDCR_SOC_P1    C2440 -1   M      A18X+040273Y+102827X0198Y0197     S2      
327PVDDCR_SOC_P1    C2441 -1   M      A18X+045396Y+101888X0198Y0197R180 S2      
327PVDDCR_SOC_P1    C2442 -1          A01X+044372Y+101888X0198Y0197     S1      
327PVDDCR_SOC_P1    C2443 -1   M      A18X+049523Y+098777X0198Y0197     S2      
327PVDDCR_SOC_P1    C2444 -1   M      A18X+049123Y+103474X0198Y0197     S2      
327PVDDCR_SOC_P1    C2445 -1          A01X+042766Y+100635X0198Y0197R090 S1      
327PVDDCR_SOC_P1    C2446 -1          A01X+044262Y+100635X0198Y0197R090 S1      
327PVDDCR_SOC_P1    C2447 -1   M      A18X+049523Y+100727X0198Y0197     S2      
327PVDDCR_SOC_P1    C2448 -1   M      A18X+041973Y+099127X0198Y0197     S2      
327PVDDCR_SOC_P1    C2449 -1   M      A18X+048073Y+098777X0198Y0197     S2      
327PVDDCR_SOC_P1    C2450 -1          A01X+044372Y+101474X0198Y0197     S1      
327PVDDCR_SOC_P1    C2451 -1   M      A18X+046373Y+099127X0198Y0197     S2      
327PVDDCR_SOC_P1    C2452 -1   M      A18X+049523Y+100077X0198Y0197     S2      
327PVDDCR_SOC_P1    C2453 -1   M      A18X+040708Y+100727X0198Y0197R180 S2      
327PVDDCR_SOC_P1    C2454 -1   M      A18X+048823Y+100077X0198Y0197     S2      
327PVDDCR_SOC_P1    C2455 -1   M      A18X+041223Y+099777X0198Y0197     S2      
327PVDDCR_SOC_P1    C2456 -1   M      A18X+048528Y+103124X0198Y0197     S2      
327PVDDCR_SOC_P1    C2457 -1   M      A18X+048073Y+100727X0198Y0197     S2      
327PVDDCR_SOC_P1    C2458 -1   M      A18X+045758Y+100635X0198Y0197R270 S2      
327PVDDCR_SOC_P1    C2459 -1   M      A18X+043423Y+099127X0198Y0197     S2      
327PVDDCR_SOC_P1    C2460 -1          A01X+043888Y+100635X0198Y0197R090 S1      
327PVDDCR_SOC_P1    C2461 -1   M      A18X+048823Y+101902X0198Y0197     S2      
327PVDDCR_SOC_P1    C2462 -1   M      A18X+049523Y+102256X0198Y0197     S2      
327PVDDCR_SOC_P1    C2463 -1   M      A18X+046573Y+102482X0198Y0197     S2      
327PVDDCR_SOC_P1    C2464 -1   M      A18X+046573Y+101360X0198Y0197     S2      
327PVDDCR_SOC_P1    C2465 -1   M      A18X+040273Y+103427X0198Y0197     S2      
327PVDDCR_SOC_P1    C2466 -1   M      A18X+043423Y+099777X0198Y0197     S2      
327PVDDCR_SOC_P1    C2467 -1   M      A18X+040658Y+102827X0198Y0197R180 S2      
327PVDDCR_SOC_P1    C2468 -1   M      A18X+048073Y+099427X0198Y0197     S2      
327PVDDCR_SOC_P1    C2469 -1   M      A18X+049523Y+101547X0198Y0197     S2      
327PVDDCR_SOC_P1    C2470 -1   M      A18X+040273Y+100727X0198Y0197     S2      
327PVDDCR_SOC_P1    C2471 -1   M      A18X+049523Y+099427X0198Y0197     S2      
327PVDDCR_SOC_P1    C2472 -1   M      A18X+048073Y+100077X0198Y0197     S2      
327PVDDCR_SOC_P1    C2473 -1   M      A18X+043888Y+100635X0198Y0197R270 S2      
327PVDDCR_SOC_P1    C2474 -1   M      A18X+040158Y+101077X0198Y0197R180 S2      
327PVDDCR_SOC_P1    C2475 -1          A01X+043514Y+100635X0198Y0197R090 S1      
327PVDDCR_SOC_P1    C2476 -1   M      A18X+046573Y+101734X0198Y0197     S2      
327PVDDCR_SOC_P1    C3900 -1          A01X+045758Y+100635X0198Y0197R090 S1      
327PVDDCR_SOC_P1    C3901 -1   M      A18X+044262Y+100635X0198Y0197R270 S2      
327PVDDCR_SOC_P1    C3906 -1          A01X+045010Y+100635X0198Y0197R090 S1      
327PVDDCR_SOC_P1    C3907 -1   M      A18X+045010Y+100635X0198Y0197R270 S2      
327PVDDCR_SOC_P1    C3908 -1   M      A18X+044636Y+100635X0198Y0197R270 S2      
327PVDDCR_SOC_P1    C3912 -1   M      A18X+048065Y+102256X0198Y0197     S2      
327PVDDCR_SOC_P1    C3913 -1   M      A18X+049123Y+102774X0198Y0197     S2      
327PVDDCR_SOC_P1    C3914 -1   M      A18X+048065Y+101547X0198Y0197     S2      
327PVDDCR_SOC_P1    C3915 -1   M      A18X+048823Y+101547X0198Y0197     S2      
327PVDDCR_SOC_P1    C3916 -1   M      A18X+048065Y+101902X0198Y0197     S2      
327PVDDCR_SOC_P1    C3917 -1   M      A18X+048373Y+102774X0198Y0197     S2      
327PVDDCR_SOC_P1    C3918 -1   M      A18X+048823Y+100727X0198Y0197     S2      
327PVDDCR_SOC_P1    U26   -AA22       A01X+049743Y+093807X0177Y    R180 S1      
327PVDDCR_SOC_P1    U26   -AC4        A01X+056405Y+094445X0177Y    R180 S1      
327PVDDCR_SOC_P1    U26   -AC11       A01X+053814Y+094445X0177Y    R180 S1      
327PVDDCR_SOC_P1    U26   -AC18       A01X+051224Y+094445X0177Y    R180 S1      
327PVDDCR_SOC_P1    U26   -AD22       A01X+049928Y+094764X0177Y    R180 S1      
327PVDDCR_SOC_P1    U26   -AF5        A01X+056220Y+095402X0177Y    R180 S1      
327PVDDCR_SOC_P1    U26   -AF12       A01X+053629Y+095402X0177Y    R180 S1      
327PVDDCR_SOC_P1    U26   -AF19       A01X+051038Y+095402X0177Y    R180 S1      
327PVDDCR_SOC_P1    U26   -AH22       A01X+049928Y+096040X0177Y    R180 S1      
327PVDDCR_SOC_P1    U26   -AJ4        A01X+056405Y+096358X0177Y    R180 S1      
327PVDDCR_SOC_P1    U26   -AJ11       A01X+053814Y+096358X0177Y    R180 S1      
327PVDDCR_SOC_P1    U26   -AJ18       A01X+051224Y+096358X0177Y    R180 S1      
327PVDDCR_SOC_P1    U26   -AM5        A01X+056220Y+097315X0177Y    R180 S1      
327PVDDCR_SOC_P1    U26   -AM12       A01X+053629Y+097315X0177Y    R180 S1      
327PVDDCR_SOC_P1    U26   -AM19       A01X+051038Y+097315X0177Y    R180 S1      
327PVDDCR_SOC_P1    U26   -AM22       A01X+049928Y+097315X0177Y    R180 S1      
327PVDDCR_SOC_P1    U26   -AR4        A01X+056405Y+098272X0177Y    R180 S1      
327PVDDCR_SOC_P1    U26   -AR11       A01X+053814Y+098272X0177Y    R180 S1      
327PVDDCR_SOC_P1    U26   -AR18       A01X+051224Y+098272X0177Y    R180 S1      
327PVDDCR_SOC_P1    U26   -AT22       A01X+049928Y+098591X0177Y    R180 S1      
327PVDDCR_SOC_P1    U26   -AU23       A01X+049373Y+098910X0177Y    R180 S1      
327PVDDCR_SOC_P1    U26   -AU27       A01X+047893Y+098910X0177Y    R180 S1      
327PVDDCR_SOC_P1    U26   -AU31       A01X+046413Y+098910X0177Y    R180 S1      
327PVDDCR_SOC_P1    U26   -AU35       A01X+044932Y+098910X0177Y    R180 S1      
327PVDDCR_SOC_P1    U26   -AU40       A01X+043452Y+098910X0177Y    R180 S1      
327PVDDCR_SOC_P1    U26   -AV5        A01X+056220Y+099228X0177Y    R180 S1      
327PVDDCR_SOC_P1    U26   -AV12       A01X+053629Y+099228X0177Y    R180 S1      
327PVDDCR_SOC_P1    U26   -AV19       A01X+051038Y+099228X0177Y    R180 S1      
327PVDDCR_SOC_P1    U26   -AV22       A01X+049928Y+099228X0177Y    R180 S1      
327PVDDCR_SOC_P1    U26   -AV24       A01X+049188Y+099228X0177Y    R180 S1      
327PVDDCR_SOC_P1    U26   -AV26       A01X+048448Y+099228X0177Y    R180 S1      
327PVDDCR_SOC_P1    U26   -AV28       A01X+047708Y+099228X0177Y    R180 S1      
327PVDDCR_SOC_P1    U26   -AV30       A01X+046968Y+099228X0177Y    R180 S1      
327PVDDCR_SOC_P1    U26   -AV32       A01X+046228Y+099228X0177Y    R180 S1      
327PVDDCR_SOC_P1    U26   -AV34       A01X+045487Y+099228X0177Y    R180 S1      
327PVDDCR_SOC_P1    U26   -AV36       A01X+044747Y+099228X0177Y    R180 S1      
327PVDDCR_SOC_P1    U26   -AV39       A01X+043637Y+099228X0177Y    R180 S1      
327PVDDCR_SOC_P1    U26   -AV41       A01X+042897Y+099228X0177Y    R180 S1      
327PVDDCR_SOC_P1    U26   -AV43       A01X+042157Y+099228X0177Y    R180 S1      
327PVDDCR_SOC_P1    U26   -AV45       A01X+041416Y+099228X0177Y    R180 S1      
327PVDDCR_SOC_P1    U26   -AV47       A01X+040676Y+099228X0177Y    R180 S1      
327PVDDCR_SOC_P1    U26   -AW23       A01X+049373Y+099547X0177Y    R180 S1      
327PVDDCR_SOC_P1    U26   -AW25       A01X+048633Y+099547X0177Y    R180 S1      
327PVDDCR_SOC_P1    U26   -AW27       A01X+047893Y+099547X0177Y    R180 S1      
327PVDDCR_SOC_P1    U26   -AW48       A01X+040491Y+099547X0177Y    R180 S1      
327PVDDCR_SOC_P1    U26   -AY22       A01X+049928Y+099866X0177Y    R180 S1      
327PVDDCR_SOC_P1    U26   -AY24       A01X+049188Y+099866X0177Y    R180 S1      
327PVDDCR_SOC_P1    U26   -AY26       A01X+048448Y+099866X0177Y    R180 S1      
327PVDDCR_SOC_P1    U26   -AY28       A01X+047708Y+099866X0177Y    R180 S1      
327PVDDCR_SOC_P1    U26   -AY49       A01X+039936Y+099866X0177Y    R180 S1      
327PVDDCR_SOC_P1    U26   -B5         A01X+056220Y+087748X0177Y    R180 S1      
327PVDDCR_SOC_P1    U26   -BA4        A01X+056405Y+100185X0177Y    R180 S1      
327PVDDCR_SOC_P1    U26   -BA11       A01X+053814Y+100185X0177Y    R180 S1      
327PVDDCR_SOC_P1    U26   -BA18       A01X+051224Y+100185X0177Y    R180 S1      
327PVDDCR_SOC_P1    U26   -BA23       A01X+049373Y+100185X0177Y    R180 S1      
327PVDDCR_SOC_P1    U26   -BA25       A01X+048633Y+100185X0177Y    R180 S1      
327PVDDCR_SOC_P1    U26   -BA27       A01X+047893Y+100185X0177Y    R180 S1      
327PVDDCR_SOC_P1    U26   -BA48       A01X+040491Y+100185X0177Y    R180 S1      
327PVDDCR_SOC_P1    U26   -BB22       A01X+049928Y+100504X0177Y    R180 S1      
327PVDDCR_SOC_P1    U26   -BB24       A01X+049188Y+100504X0177Y    R180 S1      
327PVDDCR_SOC_P1    U26   -BB26       A01X+048448Y+100504X0177Y    R180 S1      
327PVDDCR_SOC_P1    U26   -BB28       A01X+047708Y+100504X0177Y    R180 S1      
327PVDDCR_SOC_P1    U26   -BB49       A01X+039936Y+100504X0177Y    R180 S1      
327PVDDCR_SOC_P1    U26   -BC23       A01X+049373Y+100823X0177Y    R180 S1      
327PVDDCR_SOC_P1    U26   -BC25       A01X+048633Y+100823X0177Y    R180 S1      
327PVDDCR_SOC_P1    U26   -BC27       A01X+047893Y+100823X0177Y    R180 S1      
327PVDDCR_SOC_P1    U26   -BC48       A01X+040491Y+100823X0177Y    R180 S1      
327PVDDCR_SOC_P1    U26   -BD5        A01X+056220Y+101142X0177Y    R180 S1      
327PVDDCR_SOC_P1    U26   -BD12       A01X+053629Y+101142X0177Y    R180 S1      
327PVDDCR_SOC_P1    U26   -BD19       A01X+051038Y+101142X0177Y    R180 S1      
327PVDDCR_SOC_P1    U26   -BD22       A01X+049928Y+101142X0177Y    R180 S1      
327PVDDCR_SOC_P1    U26   -BD24       A01X+049188Y+101142X0177Y    R180 S1      
327PVDDCR_SOC_P1    U26   -BD26       A01X+048448Y+101142X0177Y    R180 S1      
327PVDDCR_SOC_P1    U26   -BD28       A01X+047708Y+101142X0177Y    R180 S1      
327PVDDCR_SOC_P1    U26   -BD48       A01X+040306Y+101142X0177Y    R180 S1      
327PVDDCR_SOC_P1    U26   -BF23       A01X+049676Y+102701X0177Y    R180 S1      
327PVDDCR_SOC_P1    U26   -BF25       A01X+048936Y+102701X0177Y    R180 S1      
327PVDDCR_SOC_P1    U26   -BF27       A01X+048196Y+102701X0177Y    R180 S1      
327PVDDCR_SOC_P1    U26   -BF48       A01X+040424Y+102701X0177Y    R180 S1      
327PVDDCR_SOC_P1    U26   -BG22       A01X+049861Y+103020X0177Y    R180 S1      
327PVDDCR_SOC_P1    U26   -BG24       A01X+049121Y+103020X0177Y    R180 S1      
327PVDDCR_SOC_P1    U26   -BG26       A01X+048381Y+103020X0177Y    R180 S1      
327PVDDCR_SOC_P1    U26   -BG28       A01X+047641Y+103020X0177Y    R180 S1      
327PVDDCR_SOC_P1    U26   -BG48       A01X+040609Y+103020X0177Y    R180 S1      
327PVDDCR_SOC_P1    U26   -BH23       A01X+049676Y+103339X0177Y    R180 S1      
327PVDDCR_SOC_P1    U26   -BH25       A01X+048936Y+103339X0177Y    R180 S1      
327PVDDCR_SOC_P1    U26   -BH48       A01X+040424Y+103339X0177Y    R180 S1      
327PVDDCR_SOC_P1    U26   -BJ4        A01X+056523Y+103658X0177Y    R180 S1      
327PVDDCR_SOC_P1    U26   -BJ11       A01X+053932Y+103658X0177Y    R180 S1      
327PVDDCR_SOC_P1    U26   -BJ48       A01X+040609Y+103658X0177Y    R180 S1      
327PVDDCR_SOC_P1    U26   -BM5        A01X+056338Y+104614X0177Y    R180 S1      
327PVDDCR_SOC_P1    U26   -C4         A01X+056405Y+088067X0177Y    R180 S1      
327PVDDCR_SOC_P1    U26   -E4         A01X+056405Y+088705X0177Y    R180 S1      
327PVDDCR_SOC_P1    U26   -E11        A01X+053814Y+088705X0177Y    R180 S1      
327PVDDCR_SOC_P1    U26   -H5         A01X+056220Y+089662X0177Y    R180 S1      
327PVDDCR_SOC_P1    U26   -H12        A01X+053629Y+089662X0177Y    R180 S1      
327PVDDCR_SOC_P1    U26   -H19        A01X+051038Y+089662X0177Y    R180 S1      
327PVDDCR_SOC_P1    U26   -K22        A01X+049928Y+090299X0177Y    R180 S1      
327PVDDCR_SOC_P1    U26   -L4         A01X+056405Y+090618X0177Y    R180 S1      
327PVDDCR_SOC_P1    U26   -L11        A01X+053814Y+090618X0177Y    R180 S1      
327PVDDCR_SOC_P1    U26   -L18        A01X+051224Y+090618X0177Y    R180 S1      
327PVDDCR_SOC_P1    U26   -P5         A01X+056220Y+091575X0177Y    R180 S1      
327PVDDCR_SOC_P1    U26   -P12        A01X+053629Y+091575X0177Y    R180 S1      
327PVDDCR_SOC_P1    U26   -P19        A01X+051038Y+091575X0177Y    R180 S1      
327PVDDCR_SOC_P1    U26   -P22        A01X+049928Y+091575X0177Y    R180 S1      
327PVDDCR_SOC_P1    U26   -U4         A01X+056405Y+092532X0177Y    R180 S1      
327PVDDCR_SOC_P1    U26   -U11        A01X+053814Y+092532X0177Y    R180 S1      
327PVDDCR_SOC_P1    U26   -U18        A01X+051224Y+092532X0177Y    R180 S1      
327PVDDCR_SOC_P1    U26   -V22        A01X+049928Y+092850X0177Y    R180 S1      
327PVDDCR_SOC_P1    U26   -Y5         A01X+056220Y+093488X0177Y    R180 S1      
327PVDDCR_SOC_P1    U26   -Y12        A01X+053629Y+093488X0177Y    R180 S1      
327PVDDCR_SOC_P1    U26   -Y19        A01X+051038Y+093488X0177Y    R180 S1      
317PVDDCR_SOC_P1    VIA   -    MD0100PA00X+049986Y+070516X0200Y    R180 S0      
317PVDDCR_SOC_P1    VIA   -    MD0100PA00X+049736Y+070503X0200Y         S0      
317PVDDCR_SOC_P1    VIA   -    MD0100PA00X+049986Y+070266X0200Y    R180 S0      
317PVDDCR_SOC_P1    VIA   -    MD0100PA00X+052996Y+067846X0200Y    R180 S0      
317PVDDCR_SOC_P1    VIA   -    MD0100PA00X+053246Y+067596X0200Y    R180 S0      
317PVDDCR_SOC_P1    VIA   -    MD0100PA00X+053496Y+067596X0200Y    R180 S0      
317PVDDCR_SOC_P1    VIA   -    MD0100PA00X+053496Y+067346X0200Y    R180 S0      
317PVDDCR_SOC_P1    VIA   -    MD0100PA00X+053496Y+066346X0200Y    R180 S0      
327PVDDCR_SOC_P1    VIA   -           A18X+046249Y+073453X0260Y         S2      
327PVDDCR_SOC_P1    VIA   -           A18X+047906Y+072066X0260Y         S2      
327PVDDCR_SOC_P1    VIA   -           A18X+044669Y+074466X0260Y         S2      
327PVDDCR_SOC_P1    VIA   -           A18X+049486Y+070803X0260Y         S2      
317PVDDCR_SOC_P1    VIA   -    MD0100PA00X+042381Y+100580X0190Y    R180 S0      
317PVDDCR_SOC_P1    VIA   -    MD0100PA00X+043836Y+099777X0190Y    R180 S0      
317PVDDCR_SOC_P1    VIA   -    MD0100PA00X+043843Y+098977X0190Y    R180 S0      
317PVDDCR_SOC_P1    VIA   -    MD0100PA00X+043836Y+099377X0190Y    R180 S0      
317PVDDCR_SOC_P1    VIA   -    MD0100PA00X+043836Y+100177X0190Y    R180 S0      
317PVDDCR_SOC_P1    VIA   -    MD0100PA00X+043877Y+100580X0190Y    R180 S0      
317PVDDCR_SOC_P1    VIA   -    MD0100PA00X+043503Y+100580X0190Y    R180 S0      
317PVDDCR_SOC_P1    VIA   -    MD0100PA00X+043129Y+100580X0190Y    R180 S0      
317PVDDCR_SOC_P1    VIA   -    MD0100PA00X+043472Y+101474X0190Y    R180 S0      
317PVDDCR_SOC_P1    VIA   -    MD0100PA00X+042755Y+100580X0190Y    R180 S0      
317PVDDCR_SOC_P1    VIA   -    MD0100PA00X+044357Y+101888X0190Y    R180 S0      
317PVDDCR_SOC_P1    VIA   -    MD0100PA00X+045381Y+101888X0190Y    R180 S0      
317PVDDCR_SOC_P1    VIA   -    MD0100PA00X+044251Y+100580X0190Y    R180 S0      
317PVDDCR_SOC_P1    VIA   -    MD0100PA00X+044625Y+100580X0190Y    R180 S0      
317PVDDCR_SOC_P1    VIA   -    MD0100PA00X+044357Y+101474X0190Y    R180 S0      
317PVDDCR_SOC_P1    VIA   -    MD0100PA00X+045373Y+100580X0190Y    R180 S0      
317PVDDCR_SOC_P1    VIA   -    MD0100PA00X+044999Y+100580X0190Y    R180 S0      
317PVDDCR_SOC_P1    VIA   -    MD0100PA00X+045381Y+101474X0190Y    R180 S0      
317PVDDCR_SOC_P1    VIA   -    MD0100PA00X+046596Y+101724X0190Y    R270 S0      
317PVDDCR_SOC_P1    VIA   -    MD0100PA00X+046596Y+102847X0190Y    R270 S0      
317PVDDCR_SOC_P1    VIA   -    MD0100PA00X+046596Y+102473X0190Y    R270 S0      
317PVDDCR_SOC_P1    VIA   -    MD0100PA00X+046596Y+102099X0190Y    R270 S0      
317PVDDCR_SOC_P1    VIA   -    MD0100PA00X+046596Y+101350X0190Y    R270 S0      
317PVDDCR_SOC_P1    VIA   -    MD0100PA00X+046596Y+100602X0190Y    R270 S0      
317PVDDCR_SOC_P1    VIA   -    MD0100PA00X+046596Y+100976X0190Y    R270 S0      
317PVDDCR_SOC_P1    VIA   -    MD0100PA00X+045747Y+100580X0190Y    R180 S0      
317PVDDCR_SOC_P1    VIA   -    MD0100PA00X+048080Y+101547X0190Y         S0      
317PVDDCR_SOC_P1    VIA   -    MD0100PA00X+048080Y+101902X0190Y         S0      
317PVDDCR_SOC_P1    VIA   -    MD0100PA00X+048080Y+102256X0190Y         S0      
317PVDDCR_SOC_P1    VIA   -    MD0100PA00X+049588Y+101902X0190Y         S0      
317PVDDCR_SOC_P1    VIA   -    MD0100PA00X+049588Y+102256X0190Y         S0      
317PVDDCR_SOC_P1    VIA   -    MD0100PA00X+048838Y+101902X0190Y         S0      
317PVDDCR_SOC_P1    VIA   -    MD0100PA00X+048838Y+102256X0190Y         S0      
317PVDDCR_SOC_P1    VIA   -    MD0100PA00X+049588Y+101547X0190Y         S0      
317PVDDCR_SOC_P1    VIA   -    MD0100PA00X+048838Y+101547X0190Y         S0      
317PVDDCR_SOC_P1    VIA   -    MD0100PA00X+046749Y+072666X0200Y    R180 S0      
317PVDDCR_SOC_P1    VIA   -    MD0100PA00X+046249Y+072403X0200Y    R180 S0      
317PVDDCR_SOC_P1    VIA   -    MD0100PA00X+046499Y+072403X0200Y    R180 S0      
317PVDDCR_SOC_P1    VIA   -    MD0100PA00X+046749Y+072403X0200Y    R180 S0      
317PVDDCR_SOC_P1    VIA   -    MD0100PA00X+046499Y+072653X0200Y         S0      
317PVDDCR_SOC_P1    VIA   -    MD0100PA00X+046499Y+072903X0200Y         S0      
317PVDDCR_SOC_P1    VIA   -    MD0100PA00X+046249Y+072903X0200Y         S0      
317PVDDCR_SOC_P1    VIA   -    MD0100PA00X+046249Y+072653X0200Y         S0      
317PVDDCR_SOC_P1    VIA   -    MD0100PA00X+045169Y+072403X0200Y    R180 S0      
317PVDDCR_SOC_P1    VIA   -    MD0100PA00X+044919Y+072403X0200Y    R180 S0      
317PVDDCR_SOC_P1    VIA   -    MD0100PA00X+044669Y+072403X0200Y    R180 S0      
317PVDDCR_SOC_P1    VIA   -    MD0100PA00X+045169Y+072653X0200Y         S0      
317PVDDCR_SOC_P1    VIA   -    MD0100PA00X+045169Y+072903X0200Y         S0      
317PVDDCR_SOC_P1    VIA   -    MD0100PA00X+045169Y+073153X0200Y         S0      
317PVDDCR_SOC_P1    VIA   -    MD0100PA00X+044919Y+073153X0200Y         S0      
317PVDDCR_SOC_P1    VIA   -    MD0100PA00X+044919Y+072903X0200Y         S0      
317PVDDCR_SOC_P1    VIA   -    MD0100PA00X+044919Y+072653X0200Y         S0      
317PVDDCR_SOC_P1    VIA   -    MD0100PA00X+044669Y+073166X0200Y         S0      
317PVDDCR_SOC_P1    VIA   -    MD0100PA00X+044669Y+072916X0200Y         S0      
317PVDDCR_SOC_P1    VIA   -    MD0100PA00X+044669Y+072666X0200Y         S0      
317PVDDCR_SOC_P1    VIA   -    MD0100PA00X+045169Y+073403X0200Y         S0      
317PVDDCR_SOC_P1    VIA   -    MD0100PA00X+044919Y+073403X0200Y         S0      
317PVDDCR_SOC_P1    VIA   -    MD0100PA00X+044669Y+073416X0200Y         S0      
317PVDDCR_SOC_P1    VIA   -    MD0100PA00X+044669Y+073916X0200Y         S0      
317PVDDCR_SOC_P1    VIA   -    MD0100PA00X+044669Y+073666X0200Y         S0      
317PVDDCR_SOC_P1    VIA   -    MD0100PA00X+044669Y+074166X0200Y         S0      
317PVDDCR_SOC_P1    VIA   -    MD0100PA00X+045169Y+073666X0200Y         S0      
317PVDDCR_SOC_P1    VIA   -    MD0100PA00X+045169Y+073916X0200Y         S0      
317PVDDCR_SOC_P1    VIA   -    MD0100PA00X+044919Y+073666X0200Y         S0      
317PVDDCR_SOC_P1    VIA   -    MD0100PA00X+044919Y+073916X0200Y         S0      
317PVDDCR_SOC_P1    VIA   -    MD0100PA00X+044919Y+074166X0200Y         S0      
317PVDDCR_SOC_P1    VIA   -    MD0100PA00X+053436Y+060138X0200Y         S0      
327PVDDCR_SOC_P1    PR216 -2          A18X+053577Y+060420X0198Y0197R090 S2      
317PVDDCR_SOC_P1    VIA   -    MD0100PA00X+052996Y+066343X0200Y    R180 S0      
317PVDDCR_SOC_P1    VIA   -    MD0100PA00X+052746Y+066343X0200Y    R180 S0      
317PVDDCR_SOC_P1    VIA   -    MD0100PA00X+051666Y+066343X0200Y    R180 S0      
317PVDDCR_SOC_P1    VIA   -    MD0100PA00X+051416Y+066343X0200Y    R180 S0      
317PVDDCR_SOC_P1    VIA   -    MD0100PA00X+052746Y+067093X0200Y         S0      
317PVDDCR_SOC_P1    VIA   -    MD0100PA00X+052746Y+066843X0200Y         S0      
317PVDDCR_SOC_P1    VIA   -    MD0100PA00X+052746Y+066593X0200Y         S0      
317PVDDCR_SOC_P1    VIA   -    MD0100PA00X+052746Y+067343X0200Y         S0      
317PVDDCR_SOC_P1    VIA   -    MD0100PA00X+051666Y+066593X0200Y         S0      
317PVDDCR_SOC_P1    VIA   -    MD0100PA00X+051666Y+066843X0200Y         S0      
317PVDDCR_SOC_P1    VIA   -    MD0100PA00X+051666Y+067093X0200Y         S0      
317PVDDCR_SOC_P1    VIA   -    MD0100PA00X+051416Y+067093X0200Y         S0      
317PVDDCR_SOC_P1    VIA   -    MD0100PA00X+051416Y+066843X0200Y         S0      
317PVDDCR_SOC_P1    VIA   -    MD0100PA00X+051416Y+066593X0200Y         S0      
317PVDDCR_SOC_P1    VIA   -    MD0100PA00X+051666Y+067343X0200Y         S0      
317PVDDCR_SOC_P1    VIA   -    MD0100PA00X+051416Y+067343X0200Y         S0      
317PVDDCR_SOC_P1    VIA   -    MD0100PA00X+052996Y+066593X0200Y         S0      
317PVDDCR_SOC_P1    VIA   -    MD0100PA00X+052996Y+066843X0200Y         S0      
317PVDDCR_SOC_P1    VIA   -    MD0100PA00X+052996Y+067093X0200Y         S0      
317PVDDCR_SOC_P1    VIA   -    MD0100PA00X+052996Y+067343X0200Y         S0      
317PVDDCR_SOC_P1    VIA   -    MD0100PA00X+048406Y+069753X0200Y    R180 S0      
317PVDDCR_SOC_P1    VIA   -    MD0100PA00X+048156Y+069753X0200Y    R180 S0      
317PVDDCR_SOC_P1    VIA   -    MD0100PA00X+047906Y+069753X0200Y    R180 S0      
317PVDDCR_SOC_P1    VIA   -    MD0100PA00X+048156Y+070003X0200Y         S0      
317PVDDCR_SOC_P1    VIA   -    MD0100PA00X+048156Y+070253X0200Y         S0      
317PVDDCR_SOC_P1    VIA   -    MD0100PA00X+048156Y+070503X0200Y         S0      
317PVDDCR_SOC_P1    VIA   -    MD0100PA00X+048406Y+070503X0200Y         S0      
317PVDDCR_SOC_P1    VIA   -    MD0100PA00X+048406Y+070253X0200Y         S0      
317PVDDCR_SOC_P1    VIA   -    MD0100PA00X+048406Y+070003X0200Y         S0      
317PVDDCR_SOC_P1    VIA   -    MD0100PA00X+047906Y+070016X0200Y         S0      
317PVDDCR_SOC_P1    VIA   -    MD0100PA00X+047906Y+070266X0200Y         S0      
317PVDDCR_SOC_P1    VIA   -    MD0100PA00X+047906Y+070516X0200Y         S0      
317PVDDCR_SOC_P1    VIA   -    MD0100PA00X+048156Y+070753X0200Y         S0      
317PVDDCR_SOC_P1    VIA   -    MD0100PA00X+048406Y+070753X0200Y         S0      
317PVDDCR_SOC_P1    VIA   -    MD0100PA00X+048156Y+071516X0200Y         S0      
317PVDDCR_SOC_P1    VIA   -    MD0100PA00X+048406Y+071516X0200Y         S0      
317PVDDCR_SOC_P1    VIA   -    MD0100PA00X+048156Y+071266X0200Y         S0      
317PVDDCR_SOC_P1    VIA   -    MD0100PA00X+048156Y+071016X0200Y         S0      
317PVDDCR_SOC_P1    VIA   -    MD0100PA00X+048406Y+071266X0200Y         S0      
317PVDDCR_SOC_P1    VIA   -    MD0100PA00X+048406Y+071016X0200Y         S0      
317PVDDCR_SOC_P1    VIA   -    MD0100PA00X+047906Y+071516X0200Y         S0      
317PVDDCR_SOC_P1    VIA   -    MD0100PA00X+047906Y+071016X0200Y         S0      
317PVDDCR_SOC_P1    VIA   -    MD0100PA00X+047906Y+071266X0200Y         S0      
317PVDDCR_SOC_P1    VIA   -    MD0100PA00X+047906Y+070766X0200Y         S0      
317PVDDCR_SOC_P1    VIA   -    MD0100PA00X+049986Y+070016X0200Y    R180 S0      
317PVDDCR_SOC_P1    VIA   -    MD0100PA00X+049486Y+069753X0200Y    R180 S0      
317PVDDCR_SOC_P1    VIA   -    MD0100PA00X+049736Y+069753X0200Y    R180 S0      
317PVDDCR_SOC_P1    VIA   -    MD0100PA00X+049986Y+069753X0200Y    R180 S0      
317PVDDCR_SOC_P1    VIA   -    MD0100PA00X+049486Y+070003X0200Y         S0      
317PVDDCR_SOC_P1    VIA   -    MD0100PA00X+049486Y+070253X0200Y         S0      
317PVDDCR_SOC_P1    VIA   -    MD0100PA00X+049736Y+070253X0200Y         S0      
317PVDDCR_SOC_P1    VIA   -    MD0100PA00X+049736Y+070003X0200Y         S0      
327PVDDCR_SOC_P1    VIA   -           A18X+052746Y+068146X0260Y         S2      
327PVDDCR_SOC_P1    PL35  -4   M      A01X+045709Y+073028X0950Y1780R090 S1      
327PVDDCR_SOC_P1    PC338 -1          A01X+054011Y+066288X0198Y0197R270 S1      
327PVDDCR_SOC_P1    PR163 -1          A01X+054416Y+066369X0198Y0197     S1      
327PVDDCR_SOC_P1    PL36  -4   M      A01X+048946Y+070378X0950Y1780R090 S1      
327PVDDCR_SOC_P1    PL38  -4   M      A01X+052206Y+066968X0950Y1780R090 S1      
327PVDDCR_SOC_P1    PC341_-1          A18X+044335Y+071295X0400Y0500R270 S2      
327PVDDCR_SOC_P1    PC343 -1          A18X+045715Y+071598X0950Y1110R090 S2      
327PVDDCR_SOC_P1    PC342_-1          A18X+052493Y+065386X0400Y0500R270 S2      
327PVDDCR_SOC_P1    PC354_-1          A18X+053885Y+065368X0400Y0500R270 S2      
327PVDDCR_SOC_P1    PC355_-1          A18X+053195Y+065368X0400Y0500R270 S2      
327PVDDCR_SOC_P1    PR339 -1          A18X+054465Y+065101X0198Y0197R090 S2      
327PVDDCR_SOC_P1    PC340 -1          A18X+050461Y+068949X0950Y1110R090 S2      
327PVDDCR_SOC_P1    PC339_-1          A18X+051793Y+065386X0400Y0500R270 S2      
327PVDDCR_SOC_P1    PC337 -1          A18X+048475Y+068941X0950Y1110R090 S2      
327PVDDCR_SOC_P1    PC344_-1          A18X+047095Y+070038X0400Y0500R270 S2      
317PVDDCR_SOC_P1    VIA   -    MD0100PA00X+053246Y+066346X0200Y    R180 S0      
317PVDDCR_SOC_P1    VIA   -    MD0100PA00X+053246Y+067346X0200Y    R180 S0      
317PVDDCR_SOC_P1    VIA   -    MD0100PA00X+053246Y+067096X0200Y    R180 S0      
317PVDDCR_SOC_P1    VIA   -    MD0100PA00X+052996Y+067596X0200Y    R180 S0      
317PVDDCR_SOC_P1    VIA   -    MD0100PA00X+052746Y+067596X0200Y    R180 S0      
317PVDDCR_SOC_P1    VIA   -    MD0100PA00X+053246Y+066596X0200Y    R180 S0      
317PVDDCR_SOC_P1    VIA   -    MD0100PA00X+053246Y+066846X0200Y    R180 S0      
317PVDDCR_SOC_P1    VIA   -    MD0100PA00X+053496Y+066846X0200Y    R180 S0      
317PVDDCR_SOC_P1    VIA   -    MD0100PA00X+053496Y+066596X0200Y    R180 S0      
317PVDDCR_SOC_P1    VIA   -    MD0100PA00X+053496Y+067096X0200Y    R180 S0      
317PVDDCR_SOC_P1    VIA   -    MD0100PA00X+051416Y+067596X0200Y    R180 S0      
317PVDDCR_SOC_P1    VIA   -    MD0100PA00X+051666Y+067596X0200Y    R180 S0      
317PVDDCR_SOC_P1    VIA   -    MD0100PA00X+052746Y+067846X0200Y    R180 S0      
317PVDDCR_SOC_P1    VIA   -    MD0100PA00X+051416Y+068096X0200Y    R180 S0      
317PVDDCR_SOC_P1    VIA   -    MD0100PA00X+051666Y+068096X0200Y    R180 S0      
317PVDDCR_SOC_P1    VIA   -    MD0100PA00X+051666Y+068346X0200Y    R180 S0      
317PVDDCR_SOC_P1    VIA   -    MD0100PA00X+051416Y+068346X0200Y    R180 S0      
317PVDDCR_SOC_P1    VIA   -    MD0100PA00X+051416Y+067846X0200Y    R180 S0      
317PVDDCR_SOC_P1    VIA   -    MD0100PA00X+051666Y+067846X0200Y    R180 S0      
317PVDDCR_SOC_P1    VIA   -    MD0100PA00X+046846Y+066198X0200Y         S0      
327PVDDCR_SOC_P1    PR211 -2          A18X+046987Y+066480X0198Y0197R090 S2      
317PVDDCR_SOC_P1    VIA   -    MD0100PA00X+050106Y+063548X0200Y         S0      
327PVDDCR_SOC_P1    PR212 -2          A18X+050247Y+063830X0198Y0197R090 S2      
317PVDDCR_SOC_P1    VIA   -    MD0100PA00X+046249Y+073153X0200Y         S0      
317PVDDCR_SOC_P1    VIA   -    MD0100PA00X+047906Y+071766X0200Y         S0      
317PVDDCR_SOC_P1    VIA   -    MD0100PA00X+049486Y+070503X0200Y         S0      
317PVDDCR_SOC_P1    VIA   -    MD0100PA00X+045169Y+074166X0200Y         S0      
327m3762            PU51  -1          A01X+164146Y+063580X0090Y0240R270 S1      
327m3762            PR367 -1          A18X+164642Y+063584X0198Y0197R090 S2      
317m3762            VIA   -    MD0100PA00X+164273Y+063339X0200Y    R180 S0      
327m3763            PU50  -1          A01X+160846Y+065480X0090Y0240R270 S1      
327m3763            PR363 -1          A18X+161342Y+065484X0198Y0197R090 S2      
317m3763            VIA   -    MD0100PA00X+160973Y+065239X0200Y    R180 S0      
327m3764            PU49  -1          A01X+157569Y+068857X0090Y0240R270 S1      
327m3764            PR362 -1          A18X+158065Y+068861X0198Y0197R090 S2      
317m3764            VIA   -    MD0100PA00X+157696Y+068616X0200Y    R180 S0      
327m3765            VIA   -    M      A18X+163931Y+063385X0260Y         S2      
327m3765            PU51  -3          A01X+164146Y+063934X0090Y0240R270 S1      
327m3765            PC606 -1          A01X+164651Y+063584X0198Y0197R270 S1      
327m3765            PU51  -35         A01X+163276Y+063334X0090Y0240R180 S1      
327m3765            PR364 -2   M      A18X+164110Y+063901X0198Y0197R090 S2      
317m3765            VIA   -    MD0100PA00X+164651Y+063824X0200Y    R180 S0      
317m3765            VIA   -    MD0100PA00X+163305Y+063024X0200Y    R180 S0      
327m3766            VIA   -    M      A18X+160631Y+065285X0260Y         S2      
327m3766            PU50  -3          A01X+160846Y+065834X0090Y0240R270 S1      
327m3766            PC580 -1          A01X+161351Y+065484X0198Y0197R270 S1      
327m3766            PU50  -35         A01X+159976Y+065234X0090Y0240R180 S1      
327m3766            PR357 -2   M      A18X+160810Y+065801X0198Y0197R090 S2      
317m3766            VIA   -    MD0100PA00X+161351Y+065724X0200Y    R180 S0      
317m3766            VIA   -    MD0100PA00X+160005Y+064924X0200Y    R180 S0      
327m3767            VIA   -    M      A18X+157375Y+068683X0260Y         S2      
327m3767            PC579 -1          A01X+158074Y+068861X0198Y0197R270 S1      
327m3767            PU49  -3          A01X+157569Y+069211X0090Y0240R270 S1      
327m3767            PU49  -35         A01X+156698Y+068611X0090Y0240R180 S1      
327m3767            PR356 -2   M      A18X+157534Y+069178X0198Y0197R090 S2      
317m3767            VIA   -    MD0100PA00X+158074Y+069101X0200Y    R180 S0      
317m3767            VIA   -    MD0100PA00X+156728Y+068301X0200Y    R180 S0      
327m3768            PU51  -36         A01X+163453Y+063334X0090Y0240R180 S1      
317m3768            VIA   -    MD0100PA00X+163579Y+062927X0200Y    R180 S0      
327m3768            PU50  -36         A01X+160153Y+065234X0090Y0240R180 S1      
317m3768            VIA   -    MD0100PA00X+160279Y+064827X0200Y    R180 S0      
327m3768            PU49  -36         A01X+156876Y+068611X0090Y0240R180 S1      
317m3768            VIA   -    MD0100PA00X+157002Y+068204X0200Y    R180 S2      
327m3768            PC472 -1          A18X+151068Y+055998X0198Y0197R180 S2      
327m3768            PU42  -43         A18X+150108Y+055969X0070Y0260R270 S2      
317m3768            VIA   -    MD0100PA00X+150828Y+055939X0200Y    R180 S0      
317m3769            VIA   -    M      A01X+149251Y+053966X0200Y    R180 S2      
017m3769            VIA   -    M      A18X+149251Y+053966X0260Y    R180 S2      
017m3769                  -    MD0100PA00X+149251Y+053966                       
327m3769            PU42  -3          A18X+149527Y+054916X0070Y0260     S2      
317m3769            VIA   -    MD0100PA00X+163230Y+062767X0200Y    R180 S0      
327m3769            PU51  -34         A01X+163098Y+063334X0090Y0240R180 S1      
317m3770            VIA   -    MD0100PA00X+159930Y+064667X0200Y    R180 S0      
327m3770            PU50  -34         A01X+159798Y+065234X0090Y0240R180 S1      
317m3770            VIA   -    MD0100PA00X+149497Y+054190X0200Y    R180 S0      
327m3770            PU42  -2          A18X+149684Y+054916X0070Y0260     S2      
317m3771            VIA   -    MD0100PA00X+156653Y+068044X0200Y    R180 S0      
327m3771            PU49  -34         A01X+156521Y+068611X0090Y0240R180 S1      
317m3771            VIA   -    MD0100PA00X+149731Y+054396X0200Y    R180 S0      
327m3771            PU42  -1          A18X+149842Y+054916X0070Y0260     S2      
327m3772            PU51  -37         A01X+163630Y+063334X0090Y0240R180 S1      
327m3772            PR365 -2          A01X+163872Y+062424X0198Y0197     S1      
327m3772            VIA   -    M      A01X+163776Y+062872X0160Y0041R090 S1      
327m3773            PU50  -37         A01X+160330Y+065234X0090Y0240R180 S1      
327m3773            PR359 -2          A01X+160572Y+064324X0198Y0197     S1      
327m3773            VIA   -    M      A01X+160476Y+064760X0160Y0041R090 S1      
327m3774            PR358 -2          A01X+157295Y+067701X0198Y0197     S1      
327m3774            PU49  -37         A01X+157053Y+068611X0090Y0240R180 S1      
327m3774            VIA   -    M      A01X+157200Y+068150X0160Y0041R090 S1      
327m3775            PU51  -38         A01X+163807Y+063334X0090Y0240R180 S1      
317m3775            VIA   -    MD0100PA00X+163974Y+062971X0200Y    R180 S0      
317m3775            VIA   -    M      A01X+150182Y+057766X0200Y    R180 S2      
017m3775            VIA   -    M      A18X+150182Y+057766X0260Y    R180 S2      
017m3775                  -    MD0100PA00X+150182Y+057766                       
327m3775            PU42  -36         A18X+149842Y+057180X0070Y0260     S2      
327m3776            PU50  -38         A01X+160507Y+065234X0090Y0240R180 S1      
317m3776            VIA   -    MD0100PA00X+160674Y+064871X0200Y    R180 S0      
317m3776            VIA   -    M      A01X+150276Y+057098X0300Y    R180 S1      
017m3776            VIA   -    M      A18X+150276Y+057098X0200Y    R180 S1      
017m3776                  -    MD0100PA00X+150276Y+057098                       
327m3776            PU42  -37         A18X+150108Y+056914X0070Y0260R270 S2      
317m3777            VIA   -    M      A01X+150976Y+057548X0200Y    R180 S2      
017m3777            VIA   -    M      A18X+150976Y+057548X0260Y    R180 S2      
017m3777                  -    MD0100PA00X+150976Y+057548                       
327m3777            PU49  -38         A01X+157230Y+068611X0090Y0240R180 S1      
317m3777            VIA   -    MD0100PA00X+157398Y+068248X0200Y    R180 S0      
327m3777            PU42  -38         A18X+150108Y+056756X0070Y0260R270 S2      
327m3778            R6089 -1   M      A18X+144910Y+053532X0198Y0197     S2      
327m3778            C461  -1   M      A18X+144910Y+053932X0198Y0197     S2      
327m3778            PQ17  -G          A18X+145097Y+054599X0400Y0560     S2      
327m3778            VIA   -    M      A18X+145356Y+053786X0260Y    R180 S2      
327m3778            R8282 -2          A18X+144910Y+053132X0198Y0197R180 S2      
327m3779            PQ17  -D          A18X+144723Y+055465X0400Y0560     S2      
327m3779            PR285 -2   M      A18X+144860Y+056132X0198Y0197R180 S2      
327m3779            PQ13  -G          A18X+145097Y+056888X0320Y0360     S2      
327m3779            VIA   -    M      A18X+145318Y+056318X0260Y    R180 S2      
317m3780            VIA   -    M      A01X+144190Y+057676X0300Y    R270 S1      
017m3780            VIA   -    M      A18X+144190Y+057676X0200Y    R270 S1      
017m3780                  -    MD0100PA00X+144190Y+057676                       
327m3780            PR292 -1          A01X+150393Y+056168X0198Y0197R180 S1      
327m3780            PU42  -42         A18X+150108Y+056126X0070Y0260R270 S2      
317m3780            VIA   -    MD0100PA00X+150634Y+056168X0200Y    R180 S0      
327m3780            PQ13  -D          A18X+144723Y+057676X0320Y0360     S2      
317m3781            VIA   -    M      A01X+141100Y+046036X0200Y         S2      
017m3781            VIA   -    M      A18X+141100Y+046036X0260Y         S2      
017m3781                  -    MD0100PA00X+141100Y+046036                       
327m3781            R8282 -1          A18X+144595Y+053132X0198Y0197R180 S2      
327m3781            U18   -W3         A01X+075402Y+042619X0160Y    R090 S1      
317m3781            VIA   -    MD0100PA00X+075556Y+042466X0180Y    R090 S0      
317m3781            VIA   -    MD0100PA00X+102583Y+044902X0200Y         S0      
317PVDDCR_SOC_P0    VIA   -    MD0080PA00X+137855Y+103443X0160Y         S0      
317PVDDCR_SOC_P0    VIA   -    MD0080PA00X+137855Y+102806X0160Y         S0      
317PVDDCR_SOC_P0    VIA   -    MD0080PA00X+137367Y+100399X0160Y    R180 S0      
317PVDDCR_SOC_P0    VIA   -    MD0080PA00X+137737Y+101037X0160Y    R180 S0      
317PVDDCR_SOC_P0    VIA   -    MD0080PA00X+137922Y+100718X0160Y    R180 S0      
317PVDDCR_SOC_P0    VIA   -    MD0080PA00X+137922Y+100080X0160Y    R180 S0      
317PVDDCR_SOC_P0    VIA   -    MD0080PA00X+137367Y+099762X0160Y    R180 S0      
317PVDDCR_SOC_P0    VIA   -    MD0080PA00X+137922Y+099443X0160Y    R180 S0      
317PVDDCR_SOC_P0    VIA   -    MD0080PA00X+138847Y+099124X0160Y    R180 S0      
317PVDDCR_SOC_P0    VIA   -    MD0080PA00X+138846Y+099761X0160Y    R180 S0      
317PVDDCR_SOC_P0    VIA   -    MD0080PA00X+138107Y+099124X0160Y    R180 S0      
317PVDDCR_SOC_P0    VIA   -    MD0080PA00X+138040Y+103124X0160Y         S0      
317PVDDCR_SOC_P0    VIA   -    MD0080PA00X+138040Y+103762X0160Y         S0      
317PVDDCR_SOC_P0    VIA   -    MD0080PA00X+138224Y+103444X0160Y         S0      
317PVDDCR_SOC_P0    VIA   -    MD0080PA00X+138224Y+102806X0160Y         S0      
317PVDDCR_SOC_P0    VIA   -    MD0080PA00X+138290Y+100717X0160Y    R180 S0      
317PVDDCR_SOC_P0    VIA   -    MD0080PA00X+140327Y+099124X0160Y    R180 S0      
317PVDDCR_SOC_P0    VIA   -    MD0080PA00X+140882Y+098805X0160Y    R180 S0      
317PVDDCR_SOC_P0    VIA   -    MD0080PA00X+140326Y+099761X0160Y    R180 S0      
317PVDDCR_SOC_P0    VIA   -    MD0080PA00X+139587Y+099124X0160Y    R180 S0      
317PVDDCR_SOC_P0    VIA   -    MD0080PA00X+139586Y+099761X0160Y    R180 S0      
317PVDDCR_SOC_P0    VIA   -    MD0080PA00X+141067Y+099124X0160Y    R180 S0      
317PVDDCR_SOC_P0    VIA   -    MD0080PA00X+141066Y+099761X0160Y    R180 S0      
317PVDDCR_SOC_P0    VIA   -    MD0080PA00X+143285Y+099124X0160Y    R180 S0      
317PVDDCR_SOC_P0    VIA   -    MD0080PA00X+142545Y+099124X0160Y    R180 S0      
317PVDDCR_SOC_P0    VIA   -    MD0080PA00X+142730Y+098805X0160Y    R180 S0      
317PVDDCR_SOC_P0    VIA   -    MD0080PA00X+143287Y+099761X0160Y    R180 S0      
317PVDDCR_SOC_P0    VIA   -    MD0080PA00X+142546Y+099761X0160Y    R180 S0      
317PVDDCR_SOC_P0    VIA   -    MD0080PA00X+144766Y+099124X0160Y    R180 S0      
317PVDDCR_SOC_P0    VIA   -    MD0080PA00X+144026Y+099124X0160Y    R180 S0      
317PVDDCR_SOC_P0    VIA   -    MD0080PA00X+144211Y+098805X0160Y    R180 S0      
317PVDDCR_SOC_P0    VIA   -    MD0080PA00X+144767Y+099761X0160Y    R180 S0      
317PVDDCR_SOC_P0    VIA   -    MD0080PA00X+144027Y+099761X0160Y    R180 S0      
317PVDDCR_SOC_P0    VIA   -    MD0080PA00X+146734Y+102806X0160Y         S0      
317PVDDCR_SOC_P0    VIA   -    MD0080PA00X+145994Y+102806X0160Y         S0      
317PVDDCR_SOC_P0    VIA   -    MD0080PA00X+145506Y+100399X0160Y    R180 S0      
317PVDDCR_SOC_P0    VIA   -    MD0080PA00X+145506Y+101037X0160Y    R180 S0      
317PVDDCR_SOC_P0    VIA   -    MD0080PA00X+146246Y+100399X0160Y    R180 S0      
317PVDDCR_SOC_P0    VIA   -    MD0080PA00X+146246Y+101037X0160Y    R180 S0      
317PVDDCR_SOC_P0    VIA   -    MD0080PA00X+145691Y+100718X0160Y    R180 S0      
317PVDDCR_SOC_P0    VIA   -    MD0080PA00X+146431Y+100718X0160Y    R180 S0      
317PVDDCR_SOC_P0    VIA   -    MD0080PA00X+146431Y+100080X0160Y    R180 S0      
317PVDDCR_SOC_P0    VIA   -    MD0080PA00X+145691Y+100080X0160Y    R180 S0      
317PVDDCR_SOC_P0    VIA   -    MD0080PA00X+145506Y+099124X0160Y    R180 S0      
317PVDDCR_SOC_P0    VIA   -    MD0080PA00X+145506Y+099762X0160Y    R180 S0      
317PVDDCR_SOC_P0    VIA   -    MD0080PA00X+146246Y+099124X0160Y    R180 S0      
317PVDDCR_SOC_P0    VIA   -    MD0080PA00X+146246Y+099762X0160Y    R180 S0      
317PVDDCR_SOC_P0    VIA   -    MD0080PA00X+145691Y+099443X0160Y    R180 S0      
317PVDDCR_SOC_P0    VIA   -    MD0080PA00X+145691Y+098805X0160Y    R180 S0      
317PVDDCR_SOC_P0    VIA   -    MD0080PA00X+146431Y+099443X0160Y    R180 S0      
317PVDDCR_SOC_P0    VIA   -    MD0080PA00X+146734Y+103443X0160Y         S0      
317PVDDCR_SOC_P0    VIA   -    MD0080PA00X+145439Y+103124X0160Y         S0      
317PVDDCR_SOC_P0    VIA   -    MD0080PA00X+146179Y+103124X0160Y         S0      
317PVDDCR_SOC_P0    VIA   -    MD0080PA00X+147726Y+090195X0160Y    R180 S0      
317PVDDCR_SOC_P0    VIA   -    MD0080PA00X+147726Y+091470X0160Y    R180 S0      
317PVDDCR_SOC_P0    VIA   -    MD0080PA00X+147726Y+094659X0160Y    R180 S0      
317PVDDCR_SOC_P0    VIA   -    MD0080PA00X+147541Y+093702X0160Y    R180 S0      
317PVDDCR_SOC_P0    VIA   -    MD0080PA00X+147726Y+092746X0160Y    R180 S0      
317PVDDCR_SOC_P0    VIA   -    MD0080PA00X+147726Y+098486X0160Y    R180 S0      
317PVDDCR_SOC_P0    VIA   -    MD0080PA00X+147726Y+097210X0160Y    R180 S0      
317PVDDCR_SOC_P0    VIA   -    MD0080PA00X+147726Y+095935X0160Y    R180 S0      
317PVDDCR_SOC_P0    VIA   -    MD0080PA00X+146919Y+103124X0160Y         S0      
317PVDDCR_SOC_P0    VIA   -    MD0080PA00X+147659Y+103124X0160Y         S0      
317PVDDCR_SOC_P0    VIA   -    MD0080PA00X+147474Y+103443X0160Y         S0      
317PVDDCR_SOC_P0    VIA   -    MD0080PA00X+147474Y+102806X0160Y         S0      
317PVDDCR_SOC_P0    VIA   -    MD0080PA00X+146986Y+100399X0160Y    R180 S0      
317PVDDCR_SOC_P0    VIA   -    MD0080PA00X+146986Y+101037X0160Y    R180 S0      
317PVDDCR_SOC_P0    VIA   -    MD0080PA00X+147726Y+100399X0160Y    R180 S0      
317PVDDCR_SOC_P0    VIA   -    MD0080PA00X+147726Y+101037X0160Y    R180 S0      
317PVDDCR_SOC_P0    VIA   -    MD0080PA00X+147171Y+100718X0160Y    R180 S0      
317PVDDCR_SOC_P0    VIA   -    MD0080PA00X+147171Y+100080X0160Y    R180 S0      
317PVDDCR_SOC_P0    VIA   -    MD0080PA00X+147726Y+099762X0160Y    R180 S0      
317PVDDCR_SOC_P0    VIA   -    MD0080PA00X+147171Y+099443X0160Y    R180 S0      
317PVDDCR_SOC_P0    VIA   -    MD0080PA00X+147171Y+098805X0160Y    R180 S0      
317PVDDCR_SOC_P0    VIA   -    MD0080PA00X+146986Y+099124X0160Y    R180 S0      
317PVDDCR_SOC_P0    VIA   -    MD0080PA00X+146986Y+099762X0160Y    R180 S0      
317PVDDCR_SOC_P0    VIA   -    MD0080PA00X+147726Y+099124X0160Y    R180 S0      
317PVDDCR_SOC_P0    VIA   -    MD0080PA00X+148836Y+089557X0160Y    R180 S0      
317PVDDCR_SOC_P0    VIA   -    MD0080PA00X+149022Y+090513X0160Y    R180 S0      
317PVDDCR_SOC_P0    VIA   -    MD0080PA00X+148836Y+093384X0160Y    R180 S0      
317PVDDCR_SOC_P0    VIA   -    MD0080PA00X+149022Y+092427X0160Y    R180 S0      
317PVDDCR_SOC_P0    VIA   -    MD0080PA00X+148836Y+091470X0160Y    R180 S0      
317PVDDCR_SOC_P0    VIA   -    MD0080PA00X+148836Y+095297X0160Y    R180 S0      
317PVDDCR_SOC_P0    VIA   -    MD0080PA00X+149022Y+094340X0160Y    R180 S0      
317PVDDCR_SOC_P0    VIA   -    MD0080PA00X+149022Y+096254X0160Y    R180 S0      
317PVDDCR_SOC_P0    VIA   -    MD0080PA00X+148836Y+097210X0160Y    R180 S0      
317PVDDCR_SOC_P0    VIA   -    MD0080PA00X+149022Y+098167X0160Y    R180 S0      
317PVDDCR_SOC_P0    VIA   -    MD0080PA00X+148836Y+101037X0160Y    R180 S0      
317PVDDCR_SOC_P0    VIA   -    MD0080PA00X+149022Y+100080X0160Y    R180 S0      
317PVDDCR_SOC_P0    VIA   -    MD0080PA00X+148836Y+099124X0160Y    R180 S0      
317PVDDCR_SOC_P0    VIA   -    MD0080PA00X+151612Y+090513X0160Y    R180 S0      
317PVDDCR_SOC_P0    VIA   -    MD0080PA00X+151427Y+089557X0160Y    R180 S0      
317PVDDCR_SOC_P0    VIA   -    MD0080PA00X+151612Y+088600X0160Y    R180 S0      
317PVDDCR_SOC_P0    VIA   -    MD0080PA00X+151427Y+093384X0160Y    R180 S0      
317PVDDCR_SOC_P0    VIA   -    MD0080PA00X+151427Y+091470X0160Y    R180 S0      
317PVDDCR_SOC_P0    VIA   -    MD0080PA00X+151612Y+092427X0160Y    R180 S0      
317PVDDCR_SOC_P0    VIA   -    MD0080PA00X+151612Y+096254X0160Y    R180 S0      
317PVDDCR_SOC_P0    VIA   -    MD0080PA00X+151427Y+095297X0160Y    R180 S0      
317PVDDCR_SOC_P0    VIA   -    MD0080PA00X+151612Y+094340X0160Y    R180 S0      
317PVDDCR_SOC_P0    VIA   -    MD0080PA00X+151427Y+099124X0160Y    R180 S0      
317PVDDCR_SOC_P0    VIA   -    MD0080PA00X+151612Y+100080X0160Y    R180 S0      
317PVDDCR_SOC_P0    VIA   -    MD0080PA00X+151427Y+097210X0160Y    R180 S0      
317PVDDCR_SOC_P0    VIA   -    MD0080PA00X+151612Y+098167X0160Y    R180 S0      
317PVDDCR_SOC_P0    VIA   -    MD0080PA00X+151730Y+103762X0160Y         S0      
317PVDDCR_SOC_P0    VIA   -    MD0080PA00X+151427Y+101037X0160Y    R180 S0      
317PVDDCR_SOC_P0    VIA   -    MD0080PA00X+154018Y+087643X0160Y    R180 S0      
317PVDDCR_SOC_P0    VIA   -    MD0080PA00X+154203Y+087962X0160Y    R180 S0      
317PVDDCR_SOC_P0    VIA   -    MD0080PA00X+154203Y+090513X0160Y    R180 S0      
317PVDDCR_SOC_P0    VIA   -    MD0080PA00X+154203Y+088600X0160Y    R180 S0      
317PVDDCR_SOC_P0    VIA   -    MD0080PA00X+154018Y+089557X0160Y    R180 S0      
317PVDDCR_SOC_P0    VIA   -    MD0080PA00X+154018Y+091470X0160Y    R180 S0      
317PVDDCR_SOC_P0    VIA   -    MD0080PA00X+154203Y+092427X0160Y    R180 S0      
317PVDDCR_SOC_P0    VIA   -    MD0080PA00X+154203Y+094340X0160Y    R180 S0      
317PVDDCR_SOC_P0    VIA   -    MD0080PA00X+154018Y+095297X0160Y    R180 S0      
317PVDDCR_SOC_P0    VIA   -    MD0080PA00X+154018Y+093384X0160Y    R180 S0      
317PVDDCR_SOC_P0    VIA   -    MD0080PA00X+154203Y+096254X0160Y    R180 S0      
317PVDDCR_SOC_P0    VIA   -    MD0080PA00X+154018Y+099124X0160Y    R180 S0      
317PVDDCR_SOC_P0    VIA   -    MD0080PA00X+154203Y+100080X0160Y    R180 S0      
317PVDDCR_SOC_P0    VIA   -    MD0080PA00X+154018Y+097210X0160Y    R180 S0      
317PVDDCR_SOC_P0    VIA   -    MD0080PA00X+154203Y+098167X0160Y    R180 S0      
317PVDDCR_SOC_P0    VIA   -    MD0080PA00X+154321Y+103762X0160Y         S0      
317PVDDCR_SOC_P0    VIA   -    MD0080PA00X+154018Y+101037X0160Y    R180 S0      
317PVDDCR_SOC_P0    VIA   -    MD0080PA00X+154136Y+104719X0160Y         S0      
327PVDDCR_SOC_P0    C2129 -1   M      A18X+146438Y+101902X0198Y0197     S2      
327PVDDCR_SOC_P0    C2130 -1   M      A18X+145688Y+100726X0198Y0197     S2      
327PVDDCR_SOC_P0    C2134 -1   M      A18X+145688Y+099426X0198Y0197     S2      
327PVDDCR_SOC_P0    C2135 -1   M      A18X+141876Y+100635X0198Y0197R270 S2      
327PVDDCR_SOC_P0    C2139 -1          A01X+144187Y+102482X0198Y0197R180 S1      
327PVDDCR_SOC_P0    C2140 -1   M      A18X+141465Y+100176X0198Y0197R180 S2      
327PVDDCR_SOC_P0    C2143 -1   M      A18X+144738Y+099776X0198Y0197     S2      
327PVDDCR_SOC_P0    C2144 -1   M      A18X+141465Y+099776X0198Y0197R180 S2      
327PVDDCR_SOC_P0    C2147 -1   M      A18X+144187Y+100986X0198Y0197     S2      
327PVDDCR_SOC_P0    C2148 -1          A01X+142250Y+100635X0198Y0197R090 S1      
327PVDDCR_SOC_P0    C2151 -1   M      A18X+146438Y+099426X0198Y0197     S2      
327PVDDCR_SOC_P0    C2152 -1   M      A18X+144187Y+100612X0198Y0197     S2      
327PVDDCR_SOC_P0    C2154 -1   M      A18X+146438Y+100726X0198Y0197     S2      
327PVDDCR_SOC_P0    C2155 -1   M      A18X+143372Y+100635X0198Y0197R270 S2      
327PVDDCR_SOC_P0    C2157 -1          A01X+144187Y+102108X0198Y0197R180 S1      
327PVDDCR_SOC_P0    C2159 -1          A01X+142624Y+100635X0198Y0197R090 S1      
327PVDDCR_SOC_P0    C2161 -1          A01X+142998Y+100635X0198Y0197R090 S1      
327PVDDCR_SOC_P0    C2527 -1          A01X+141987Y+101888X0198Y0197     S1      
327PVDDCR_SOC_P0    C2528 -1          A01X+143372Y+100635X0198Y0197R090 S1      
327PVDDCR_SOC_P0    C2529 -1   M      A18X+145988Y+102774X0198Y0197     S2      
327PVDDCR_SOC_P0    C2530 -1   M      A18X+146438Y+101547X0198Y0197     S2      
327PVDDCR_SOC_P0    C2531 -1   M      A18X+144187Y+102482X0198Y0197     S2      
327PVDDCR_SOC_P0    C2532 -1   M      A18X+143288Y+099776X0198Y0197     S2      
327PVDDCR_SOC_P0    C2533 -1   M      A18X+138273Y+103426X0198Y0197R180 S2      
327PVDDCR_SOC_P0    C2534 -1   M      A18X+147138Y+100076X0198Y0197     S2      
327PVDDCR_SOC_P0    C2535 -1          A01X+144187Y+100612X0198Y0197R180 S1      
327PVDDCR_SOC_P0    C2536 -1   M      A18X+142538Y+099126X0198Y0197     S2      
327PVDDCR_SOC_P0    C2537 -1   M      A18X+145680Y+101902X0198Y0197     S2      
327PVDDCR_SOC_P0    C2538 -1   M      A18X+146738Y+103474X0198Y0197     S2      
327PVDDCR_SOC_P0    C2539 -1   M      A18X+142998Y+100635X0198Y0197R270 S2      
327PVDDCR_SOC_P0    C2540 -1   M      A18X+141038Y+099776X0198Y0197     S2      
327PVDDCR_SOC_P0    C2541 -1   M      A18X+143988Y+099126X0198Y0197     S2      
327PVDDCR_SOC_P0    C2542 -1   M      A18X+146438Y+102256X0198Y0197     S2      
327PVDDCR_SOC_P0    C2543 -1   M      A18X+142624Y+100635X0198Y0197R270 S2      
327PVDDCR_SOC_P0    C2544 -1   M      A18X+145680Y+101547X0198Y0197     S2      
327PVDDCR_SOC_P0    C2545 -1   M      A18X+147138Y+099426X0198Y0197     S2      
327PVDDCR_SOC_P0    C2546 -1   M      A18X+140754Y+100635X0198Y0197R270 S2      
327PVDDCR_SOC_P0    C2547 -1   M      A18X+140380Y+100635X0198Y0197R270 S2      
327PVDDCR_SOC_P0    C2548 -1   M      A18X+146738Y+102774X0198Y0197     S2      
327PVDDCR_SOC_P0    C2549 -1   M      A18X+140338Y+099776X0198Y0197     S2      
327PVDDCR_SOC_P0    C2550 -1   M      A18X+143288Y+099126X0198Y0197     S2      
327PVDDCR_SOC_P0    C2551 -1          A01X+144187Y+100986X0198Y0197R180 S1      
327PVDDCR_SOC_P0    C2552 -1   M      A18X+144187Y+102108X0198Y0197     S2      
327PVDDCR_SOC_P0    C2553 -1   M      A18X+141128Y+100635X0198Y0197R270 S2      
327PVDDCR_SOC_P0    C2554 -1   M      A18X+137773Y+101076X0198Y0197R180 S2      
327PVDDCR_SOC_P0    C2555 -1          A01X+144187Y+102856X0198Y0197R180 S1      
327PVDDCR_SOC_P0    C2556 -1   M      A18X+142538Y+099776X0198Y0197     S2      
327PVDDCR_SOC_P0    C2557 -1   M      A18X+145688Y+098776X0198Y0197     S2      
327PVDDCR_SOC_P0    C2558 -1   M      A18X+143010Y+101888X0198Y0197R180 S2      
327PVDDCR_SOC_P0    C2559 -1   M      A18X+144187Y+101734X0198Y0197     S2      
327PVDDCR_SOC_P0    C2560 -1   M      A18X+137888Y+100726X0198Y0197     S2      
327PVDDCR_SOC_P0    C2561 -1   M      A18X+137954Y+100063X0198Y0197R300 S2      
327PVDDCR_SOC_P0    C2562 -1          A01X+140006Y+100635X0198Y0197R090 S1      
327PVDDCR_SOC_P0    C2563 -1          A01X+143010Y+101888X0198Y0197     S1      
327PVDDCR_SOC_P0    C2564 -1          A01X+143010Y+101474X0198Y0197     S1      
327PVDDCR_SOC_P0    C2565 -1   M      A18X+143010Y+101474X0198Y0197R180 S2      
327PVDDCR_SOC_P0    C2566 -1   M      A18X+144188Y+098776X0198Y0197     S2      
327PVDDCR_SOC_P0    C2567 -1   M      A18X+137952Y+099437X0198Y0197R060 S2      
327PVDDCR_SOC_P0    C2568 -1   M      A18X+140006Y+100635X0198Y0197R270 S2      
327PVDDCR_SOC_P0    C2569 -1   M      A18X+139588Y+099776X0198Y0197     S2      
327PVDDCR_SOC_P0    C2570 -1   M      A18X+146882Y+103124X0198Y0197     S2      
327PVDDCR_SOC_P0    C2571 -1          A01X+144187Y+101734X0198Y0197R180 S1      
327PVDDCR_SOC_P0    C2572 -1          A01X+141101Y+101474X0198Y0197     S1      
327PVDDCR_SOC_P0    C2573 -1          A01X+141987Y+101474X0198Y0197     S1      
327PVDDCR_SOC_P0    C2574 -1   M      A18X+137888Y+103426X0198Y0197     S2      
327PVDDCR_SOC_P0    C2575 -1   M      A18X+138323Y+100726X0198Y0197R180 S2      
327PVDDCR_SOC_P0    C2576 -1   M      A18X+139588Y+099126X0198Y0197     S2      
327PVDDCR_SOC_P0    C2577 -1   M      A18X+145680Y+102256X0198Y0197     S2      
327PVDDCR_SOC_P0    C2578 -1   M      A18X+147138Y+100726X0198Y0197     S2      
327PVDDCR_SOC_P0    C2579 -1   M      A18X+146438Y+100076X0198Y0197     S2      
327PVDDCR_SOC_P0    C2580 -1   M      A18X+142250Y+100635X0198Y0197R270 S2      
327PVDDCR_SOC_P0    C2581 -1   M      A18X+137888Y+102826X0198Y0197     S2      
327PVDDCR_SOC_P0    C2582 -1   M      A18X+138838Y+099776X0198Y0197     S2      
327PVDDCR_SOC_P0    C2583 -1   M      A18X+147138Y+101547X0198Y0197     S2      
327PVDDCR_SOC_P0    C2584 -1   M      A18X+147138Y+102256X0198Y0197     S2      
327PVDDCR_SOC_P0    C2585 -1   M      A18X+147138Y+101902X0198Y0197     S2      
327PVDDCR_SOC_P0    C2586 -1   M      A18X+145688Y+100076X0198Y0197     S2      
327PVDDCR_SOC_P0    C2587 -1   M      A18X+144187Y+101360X0198Y0197     S2      
327PVDDCR_SOC_P0    C2588 -1   M      A18X+138838Y+099126X0198Y0197     S2      
327PVDDCR_SOC_P0    C2589 -1   M      A18X+140338Y+099126X0198Y0197     S2      
327PVDDCR_SOC_P0    C2590 -1   M      A18X+146142Y+103124X0198Y0197     S2      
327PVDDCR_SOC_P0    C2591 -1          A01X+144187Y+101360X0198Y0197R180 S1      
327PVDDCR_SOC_P0    C2592 -1   M      A18X+147138Y+098776X0198Y0197     S2      
327PVDDCR_SOC_P0    C2593 -1   M      A18X+141038Y+099126X0198Y0197     S2      
327PVDDCR_SOC_P0    C2594 -1   M      A18X+144187Y+102856X0198Y0197     S2      
327PVDDCR_SOC_P0    C2595 -1   M      A18X+141473Y+098976X0198Y0197R180 S2      
327PVDDCR_SOC_P0    C2596 -1   M      A18X+138273Y+102826X0198Y0197R180 S2      
327PVDDCR_SOC_P0    C3888 -1   M      A18X+141987Y+101474X0198Y0197R180 S2      
327PVDDCR_SOC_P0    C3889 -1   M      A18X+141101Y+101474X0198Y0197R180 S2      
327PVDDCR_SOC_P0    C3894 -1   M      A18X+143988Y+099776X0198Y0197     S2      
327PVDDCR_SOC_P0    C3895 -1          A01X+140380Y+100635X0198Y0197R090 S1      
327PVDDCR_SOC_P0    C3896 -1   M      A18X+144738Y+099126X0198Y0197     S2      
327PVDDCR_SOC_P0    C3925 -1   M      A18X+141502Y+100635X0198Y0197R270 S2      
327PVDDCR_SOC_P0    C3926 -1   M      A18X+141987Y+101888X0198Y0197R180 S2      
327PVDDCR_SOC_P0    C3927 -1          A01X+141876Y+100635X0198Y0197R090 S1      
327PVDDCR_SOC_P0    C3928 -1          A01X+141128Y+100635X0198Y0197R090 S1      
327PVDDCR_SOC_P0    C3929 -1          A01X+141502Y+100635X0198Y0197R090 S1      
327PVDDCR_SOC_P0    C3930 -1          A01X+140754Y+100635X0198Y0197R090 S1      
327PVDDCR_SOC_P0    C3931 -1   M      A18X+141465Y+099376X0198Y0197R180 S2      
327PVDDCR_SOC_P0    U25   -AA22       A01X+147358Y+093807X0177Y    R180 S1      
327PVDDCR_SOC_P0    U25   -AC4        A01X+154019Y+094445X0177Y    R180 S1      
327PVDDCR_SOC_P0    U25   -AC11       A01X+151428Y+094445X0177Y    R180 S1      
327PVDDCR_SOC_P0    U25   -AC18       A01X+148838Y+094445X0177Y    R180 S1      
327PVDDCR_SOC_P0    U25   -AD22       A01X+147542Y+094764X0177Y    R180 S1      
327PVDDCR_SOC_P0    U25   -AF5        A01X+153834Y+095402X0177Y    R180 S1      
327PVDDCR_SOC_P0    U25   -AF12       A01X+151243Y+095402X0177Y    R180 S1      
327PVDDCR_SOC_P0    U25   -AF19       A01X+148653Y+095402X0177Y    R180 S1      
327PVDDCR_SOC_P0    U25   -AH22       A01X+147542Y+096039X0177Y    R180 S1      
327PVDDCR_SOC_P0    U25   -AJ4        A01X+154019Y+096358X0177Y    R180 S1      
327PVDDCR_SOC_P0    U25   -AJ11       A01X+151428Y+096358X0177Y    R180 S1      
327PVDDCR_SOC_P0    U25   -AJ18       A01X+148838Y+096358X0177Y    R180 S1      
327PVDDCR_SOC_P0    U25   -AM5        A01X+153834Y+097315X0177Y    R180 S1      
327PVDDCR_SOC_P0    U25   -AM12       A01X+151243Y+097315X0177Y    R180 S1      
327PVDDCR_SOC_P0    U25   -AM19       A01X+148653Y+097315X0177Y    R180 S1      
327PVDDCR_SOC_P0    U25   -AM22       A01X+147542Y+097315X0177Y    R180 S1      
327PVDDCR_SOC_P0    U25   -AR4        A01X+154019Y+098272X0177Y    R180 S1      
327PVDDCR_SOC_P0    U25   -AR11       A01X+151428Y+098272X0177Y    R180 S1      
327PVDDCR_SOC_P0    U25   -AR18       A01X+148838Y+098272X0177Y    R180 S1      
327PVDDCR_SOC_P0    U25   -AT22       A01X+147542Y+098591X0177Y    R180 S1      
327PVDDCR_SOC_P0    U25   -AU23       A01X+146987Y+098910X0177Y    R180 S1      
327PVDDCR_SOC_P0    U25   -AU27       A01X+145507Y+098910X0177Y    R180 S1      
327PVDDCR_SOC_P0    U25   -AU31       A01X+144027Y+098910X0177Y    R180 S1      
327PVDDCR_SOC_P0    U25   -AU35       A01X+142546Y+098910X0177Y    R180 S1      
327PVDDCR_SOC_P0    U25   -AU40       A01X+141066Y+098910X0177Y    R180 S1      
327PVDDCR_SOC_P0    U25   -AV5        A01X+153834Y+099228X0177Y    R180 S1      
327PVDDCR_SOC_P0    U25   -AV12       A01X+151243Y+099228X0177Y    R180 S1      
327PVDDCR_SOC_P0    U25   -AV19       A01X+148653Y+099228X0177Y    R180 S1      
327PVDDCR_SOC_P0    U25   -AV22       A01X+147542Y+099228X0177Y    R180 S1      
327PVDDCR_SOC_P0    U25   -AV24       A01X+146802Y+099228X0177Y    R180 S1      
327PVDDCR_SOC_P0    U25   -AV26       A01X+146062Y+099228X0177Y    R180 S1      
327PVDDCR_SOC_P0    U25   -AV28       A01X+145322Y+099228X0177Y    R180 S1      
327PVDDCR_SOC_P0    U25   -AV30       A01X+144582Y+099228X0177Y    R180 S1      
327PVDDCR_SOC_P0    U25   -AV32       A01X+143842Y+099228X0177Y    R180 S1      
327PVDDCR_SOC_P0    U25   -AV34       A01X+143102Y+099228X0177Y    R180 S1      
327PVDDCR_SOC_P0    U25   -AV36       A01X+142361Y+099228X0177Y    R180 S1      
327PVDDCR_SOC_P0    U25   -AV39       A01X+141251Y+099228X0177Y    R180 S1      
327PVDDCR_SOC_P0    U25   -AV41       A01X+140511Y+099228X0177Y    R180 S1      
327PVDDCR_SOC_P0    U25   -AV43       A01X+139771Y+099228X0177Y    R180 S1      
327PVDDCR_SOC_P0    U25   -AV45       A01X+139031Y+099228X0177Y    R180 S1      
327PVDDCR_SOC_P0    U25   -AV47       A01X+138290Y+099228X0177Y    R180 S1      
327PVDDCR_SOC_P0    U25   -AW23       A01X+146987Y+099547X0177Y    R180 S1      
327PVDDCR_SOC_P0    U25   -AW25       A01X+146247Y+099547X0177Y    R180 S1      
327PVDDCR_SOC_P0    U25   -AW27       A01X+145507Y+099547X0177Y    R180 S1      
327PVDDCR_SOC_P0    U25   -AW48       A01X+138106Y+099547X0177Y    R180 S1      
327PVDDCR_SOC_P0    U25   -AY22       A01X+147542Y+099866X0177Y    R180 S1      
327PVDDCR_SOC_P0    U25   -AY24       A01X+146802Y+099866X0177Y    R180 S1      
327PVDDCR_SOC_P0    U25   -AY26       A01X+146062Y+099866X0177Y    R180 S1      
327PVDDCR_SOC_P0    U25   -AY28       A01X+145322Y+099866X0177Y    R180 S1      
327PVDDCR_SOC_P0    U25   -AY49       A01X+137550Y+099866X0177Y    R180 S1      
327PVDDCR_SOC_P0    U25   -B5         A01X+153834Y+087748X0177Y    R180 S1      
327PVDDCR_SOC_P0    U25   -BA4        A01X+154019Y+100185X0177Y    R180 S1      
327PVDDCR_SOC_P0    U25   -BA11       A01X+151428Y+100185X0177Y    R180 S1      
327PVDDCR_SOC_P0    U25   -BA18       A01X+148838Y+100185X0177Y    R180 S1      
327PVDDCR_SOC_P0    U25   -BA23       A01X+146987Y+100185X0177Y    R180 S1      
327PVDDCR_SOC_P0    U25   -BA25       A01X+146247Y+100185X0177Y    R180 S1      
327PVDDCR_SOC_P0    U25   -BA27       A01X+145507Y+100185X0177Y    R180 S1      
327PVDDCR_SOC_P0    U25   -BA48       A01X+138106Y+100185X0177Y    R180 S1      
327PVDDCR_SOC_P0    U25   -BB22       A01X+147542Y+100504X0177Y    R180 S1      
327PVDDCR_SOC_P0    U25   -BB24       A01X+146802Y+100504X0177Y    R180 S1      
327PVDDCR_SOC_P0    U25   -BB26       A01X+146062Y+100504X0177Y    R180 S1      
327PVDDCR_SOC_P0    U25   -BB28       A01X+145322Y+100504X0177Y    R180 S1      
327PVDDCR_SOC_P0    U25   -BB49       A01X+137550Y+100504X0177Y    R180 S1      
327PVDDCR_SOC_P0    U25   -BC23       A01X+146987Y+100823X0177Y    R180 S1      
327PVDDCR_SOC_P0    U25   -BC25       A01X+146247Y+100823X0177Y    R180 S1      
327PVDDCR_SOC_P0    U25   -BC27       A01X+145507Y+100823X0177Y    R180 S1      
327PVDDCR_SOC_P0    U25   -BC48       A01X+138106Y+100823X0177Y    R180 S1      
327PVDDCR_SOC_P0    U25   -BD5        A01X+153834Y+101142X0177Y    R180 S1      
327PVDDCR_SOC_P0    U25   -BD12       A01X+151243Y+101142X0177Y    R180 S1      
327PVDDCR_SOC_P0    U25   -BD19       A01X+148653Y+101142X0177Y    R180 S1      
327PVDDCR_SOC_P0    U25   -BD22       A01X+147542Y+101142X0177Y    R180 S1      
327PVDDCR_SOC_P0    U25   -BD24       A01X+146802Y+101142X0177Y    R180 S1      
327PVDDCR_SOC_P0    U25   -BD26       A01X+146062Y+101142X0177Y    R180 S1      
327PVDDCR_SOC_P0    U25   -BD28       A01X+145322Y+101142X0177Y    R180 S1      
327PVDDCR_SOC_P0    U25   -BD48       A01X+137920Y+101142X0177Y    R180 S1      
327PVDDCR_SOC_P0    U25   -BF23       A01X+147290Y+102701X0177Y    R180 S1      
327PVDDCR_SOC_P0    U25   -BF25       A01X+146550Y+102701X0177Y    R180 S1      
327PVDDCR_SOC_P0    U25   -BF27       A01X+145810Y+102701X0177Y    R180 S1      
327PVDDCR_SOC_P0    U25   -BF48       A01X+138039Y+102701X0177Y    R180 S1      
327PVDDCR_SOC_P0    U25   -BG22       A01X+147476Y+103020X0177Y    R180 S1      
327PVDDCR_SOC_P0    U25   -BG24       A01X+146735Y+103020X0177Y    R180 S1      
327PVDDCR_SOC_P0    U25   -BG26       A01X+145995Y+103020X0177Y    R180 S1      
327PVDDCR_SOC_P0    U25   -BG28       A01X+145255Y+103020X0177Y    R180 S1      
327PVDDCR_SOC_P0    U25   -BG48       A01X+138224Y+103020X0177Y    R180 S1      
327PVDDCR_SOC_P0    U25   -BH23       A01X+147290Y+103339X0177Y    R180 S1      
327PVDDCR_SOC_P0    U25   -BH25       A01X+146550Y+103339X0177Y    R180 S1      
327PVDDCR_SOC_P0    U25   -BH48       A01X+138039Y+103339X0177Y    R180 S1      
327PVDDCR_SOC_P0    U25   -BJ4        A01X+154137Y+103658X0177Y    R180 S1      
327PVDDCR_SOC_P0    U25   -BJ11       A01X+151546Y+103658X0177Y    R180 S1      
327PVDDCR_SOC_P0    U25   -BJ48       A01X+138224Y+103658X0177Y    R180 S1      
327PVDDCR_SOC_P0    U25   -BM5        A01X+153952Y+104614X0177Y    R180 S1      
327PVDDCR_SOC_P0    U25   -C4         A01X+154019Y+088067X0177Y    R180 S1      
327PVDDCR_SOC_P0    U25   -E4         A01X+154019Y+088705X0177Y    R180 S1      
327PVDDCR_SOC_P0    U25   -E11        A01X+151428Y+088705X0177Y    R180 S1      
327PVDDCR_SOC_P0    U25   -H5         A01X+153834Y+089662X0177Y    R180 S1      
327PVDDCR_SOC_P0    U25   -H12        A01X+151243Y+089662X0177Y    R180 S1      
327PVDDCR_SOC_P0    U25   -H19        A01X+148653Y+089662X0177Y    R180 S1      
327PVDDCR_SOC_P0    U25   -K22        A01X+147542Y+090299X0177Y    R180 S1      
327PVDDCR_SOC_P0    U25   -L4         A01X+154019Y+090618X0177Y    R180 S1      
327PVDDCR_SOC_P0    U25   -L11        A01X+151428Y+090618X0177Y    R180 S1      
327PVDDCR_SOC_P0    U25   -L18        A01X+148838Y+090618X0177Y    R180 S1      
327PVDDCR_SOC_P0    U25   -P5         A01X+153834Y+091575X0177Y    R180 S1      
327PVDDCR_SOC_P0    U25   -P12        A01X+151243Y+091575X0177Y    R180 S1      
327PVDDCR_SOC_P0    U25   -P19        A01X+148653Y+091575X0177Y    R180 S1      
327PVDDCR_SOC_P0    U25   -P22        A01X+147542Y+091575X0177Y    R180 S1      
327PVDDCR_SOC_P0    U25   -U4         A01X+154019Y+092532X0177Y    R180 S1      
327PVDDCR_SOC_P0    U25   -U11        A01X+151428Y+092532X0177Y    R180 S1      
327PVDDCR_SOC_P0    U25   -U18        A01X+148838Y+092532X0177Y    R180 S1      
327PVDDCR_SOC_P0    U25   -V22        A01X+147542Y+092850X0177Y    R180 S1      
327PVDDCR_SOC_P0    U25   -Y5         A01X+153834Y+093488X0177Y    R180 S1      
327PVDDCR_SOC_P0    U25   -Y12        A01X+151243Y+093488X0177Y    R180 S1      
327PVDDCR_SOC_P0    U25   -Y19        A01X+148653Y+093488X0177Y    R180 S1      
327PVDDCR_SOC_P0    VIA   -           A18X+155671Y+077278X0260Y         S2      
327PVDDCR_SOC_P0    VIA   -           A18X+160562Y+073151X0260Y         S2      
327PVDDCR_SOC_P0    VIA   -           A18X+157259Y+076278X0260Y         S2      
327PVDDCR_SOC_P0    VIA   -           A18X+159219Y+073901X0260Y         S2      
327PVDDCR_SOC_P0    VIA   -           A18X+163838Y+071497X0260Y         S2      
317PVDDCR_SOC_P0    VIA   -    MD0100PA00X+160562Y+072851X0200Y         S0      
317PVDDCR_SOC_P0    VIA   -    MD0100PA00X+161062Y+072351X0200Y         S0      
317PVDDCR_SOC_P0    VIA   -    MD0100PA00X+160562Y+072601X0200Y         S0      
317PVDDCR_SOC_P0    VIA   -    MD0100PA00X+160812Y+072601X0200Y         S0      
317PVDDCR_SOC_P0    VIA   -    MD0100PA00X+160562Y+072351X0200Y         S0      
317PVDDCR_SOC_P0    VIA   -    MD0100PA00X+160812Y+072351X0200Y         S0      
317PVDDCR_SOC_P0    VIA   -    MD0100PA00X+159219Y+073101X0200Y         S0      
317PVDDCR_SOC_P0    VIA   -    MD0100PA00X+159219Y+072851X0200Y         S0      
317PVDDCR_SOC_P0    VIA   -    MD0100PA00X+159219Y+072601X0200Y         S0      
317PVDDCR_SOC_P0    VIA   -    MD0100PA00X+159219Y+072351X0200Y         S0      
317PVDDCR_SOC_P0    VIA   -    MD0100PA00X+159469Y+073101X0200Y         S0      
317PVDDCR_SOC_P0    VIA   -    MD0100PA00X+159469Y+072851X0200Y         S0      
317PVDDCR_SOC_P0    VIA   -    MD0100PA00X+159469Y+072601X0200Y         S0      
317PVDDCR_SOC_P0    VIA   -    MD0100PA00X+159469Y+072351X0200Y         S0      
317PVDDCR_SOC_P0    VIA   -    MD0100PA00X+140743Y+100580X0190Y    R180 S0      
317PVDDCR_SOC_P0    VIA   -    MD0100PA00X+140369Y+100580X0190Y    R180 S0      
317PVDDCR_SOC_P0    VIA   -    MD0100PA00X+139995Y+100580X0190Y    R180 S0      
317PVDDCR_SOC_P0    VIA   -    MD0100PA00X+141972Y+101888X0190Y    R180 S0      
317PVDDCR_SOC_P0    VIA   -    MD0100PA00X+142239Y+100580X0190Y    R180 S0      
317PVDDCR_SOC_P0    VIA   -    MD0100PA00X+141972Y+101474X0190Y    R180 S0      
317PVDDCR_SOC_P0    VIA   -    MD0100PA00X+141450Y+100176X0190Y    R180 S0      
317PVDDCR_SOC_P0    VIA   -    MD0100PA00X+141117Y+100580X0190Y    R180 S0      
317PVDDCR_SOC_P0    VIA   -    MD0100PA00X+141491Y+100580X0190Y    R180 S0      
317PVDDCR_SOC_P0    VIA   -    MD0100PA00X+141865Y+100580X0190Y    R180 S0      
317PVDDCR_SOC_P0    VIA   -    MD0100PA00X+141086Y+101474X0190Y    R180 S0      
317PVDDCR_SOC_P0    VIA   -    MD0100PA00X+141450Y+099776X0190Y    R180 S0      
317PVDDCR_SOC_P0    VIA   -    MD0100PA00X+141450Y+099376X0190Y    R180 S0      
317PVDDCR_SOC_P0    VIA   -    MD0100PA00X+141458Y+098976X0190Y    R180 S0      
317PVDDCR_SOC_P0    VIA   -    MD0100PA00X+142995Y+101888X0190Y    R180 S0      
317PVDDCR_SOC_P0    VIA   -    MD0100PA00X+142987Y+100580X0190Y    R180 S0      
317PVDDCR_SOC_P0    VIA   -    MD0100PA00X+142613Y+100580X0190Y    R180 S0      
317PVDDCR_SOC_P0    VIA   -    MD0100PA00X+143361Y+100580X0190Y    R180 S0      
317PVDDCR_SOC_P0    VIA   -    MD0100PA00X+142995Y+101474X0190Y    R180 S0      
317PVDDCR_SOC_P0    VIA   -    MD0100PA00X+144211Y+101724X0190Y    R270 S0      
317PVDDCR_SOC_P0    VIA   -    MD0100PA00X+144211Y+102846X0190Y    R270 S0      
317PVDDCR_SOC_P0    VIA   -    MD0100PA00X+144211Y+102472X0190Y    R270 S0      
317PVDDCR_SOC_P0    VIA   -    MD0100PA00X+144211Y+102098X0190Y    R270 S0      
317PVDDCR_SOC_P0    VIA   -    MD0100PA00X+144211Y+100602X0190Y    R270 S0      
317PVDDCR_SOC_P0    VIA   -    MD0100PA00X+144211Y+100976X0190Y    R270 S0      
317PVDDCR_SOC_P0    VIA   -    MD0100PA00X+144211Y+101350X0190Y    R270 S0      
317PVDDCR_SOC_P0    VIA   -    MD0100PA00X+146453Y+102256X0190Y         S0      
317PVDDCR_SOC_P0    VIA   -    MD0100PA00X+146453Y+101902X0190Y         S0      
317PVDDCR_SOC_P0    VIA   -    MD0100PA00X+145694Y+102256X0190Y         S0      
317PVDDCR_SOC_P0    VIA   -    MD0100PA00X+145694Y+101902X0190Y         S0      
317PVDDCR_SOC_P0    VIA   -    MD0100PA00X+146453Y+101547X0190Y         S0      
317PVDDCR_SOC_P0    VIA   -    MD0100PA00X+145694Y+101547X0190Y         S0      
317PVDDCR_SOC_P0    VIA   -    MD0100PA00X+147153Y+102256X0190Y         S0      
317PVDDCR_SOC_P0    VIA   -    MD0100PA00X+147153Y+101902X0190Y         S0      
317PVDDCR_SOC_P0    VIA   -    MD0100PA00X+147153Y+101547X0190Y         S0      
317PVDDCR_SOC_P0    VIA   -    MD0100PA00X+155671Y+076728X0200Y    R180 S0      
317PVDDCR_SOC_P0    VIA   -    MD0100PA00X+155671Y+076978X0200Y    R180 S0      
317PVDDCR_SOC_P0    VIA   -    MD0100PA00X+155671Y+076478X0200Y    R180 S0      
317PVDDCR_SOC_P0    VIA   -    MD0100PA00X+155671Y+075978X0200Y    R180 S0      
317PVDDCR_SOC_P0    VIA   -    MD0100PA00X+155671Y+076228X0200Y    R180 S0      
317PVDDCR_SOC_P0    VIA   -    MD0100PA00X+155671Y+075728X0200Y    R180 S0      
317PVDDCR_SOC_P0    VIA   -    MD0100PA00X+155671Y+075228X0200Y    R180 S0      
317PVDDCR_SOC_P0    VIA   -    MD0100PA00X+155671Y+075478X0200Y    R180 S0      
317PVDDCR_SOC_P0    VIA   -    MD0100PA00X+155671Y+074978X0200Y    R180 S0      
317PVDDCR_SOC_P0    VIA   -    MD0100PA00X+155669Y+074469X0200Y    R180 S0      
317PVDDCR_SOC_P0    VIA   -    MD0100PA00X+155671Y+074728X0200Y    R180 S0      
317PVDDCR_SOC_P0    VIA   -    MD0100PA00X+155921Y+076478X0200Y    R180 S0      
317PVDDCR_SOC_P0    VIA   -    MD0100PA00X+156171Y+076478X0200Y    R180 S0      
317PVDDCR_SOC_P0    VIA   -    MD0100PA00X+155921Y+076728X0200Y    R180 S0      
317PVDDCR_SOC_P0    VIA   -    MD0100PA00X+156171Y+076728X0200Y    R180 S0      
317PVDDCR_SOC_P0    VIA   -    MD0100PA00X+155921Y+076978X0200Y    R180 S0      
317PVDDCR_SOC_P0    VIA   -    MD0100PA00X+156171Y+076978X0200Y    R180 S0      
317PVDDCR_SOC_P0    VIA   -    MD0100PA00X+155921Y+075469X0200Y         S0      
317PVDDCR_SOC_P0    VIA   -    MD0100PA00X+156171Y+075469X0200Y         S0      
317PVDDCR_SOC_P0    VIA   -    MD0100PA00X+155921Y+074969X0200Y         S0      
317PVDDCR_SOC_P0    VIA   -    MD0100PA00X+155921Y+075219X0200Y         S0      
317PVDDCR_SOC_P0    VIA   -    MD0100PA00X+156171Y+075219X0200Y         S0      
317PVDDCR_SOC_P0    VIA   -    MD0100PA00X+156171Y+074969X0200Y         S0      
317PVDDCR_SOC_P0    VIA   -    MD0100PA00X+157251Y+075469X0200Y         S0      
317PVDDCR_SOC_P0    VIA   -    MD0100PA00X+157251Y+074969X0200Y         S0      
317PVDDCR_SOC_P0    VIA   -    MD0100PA00X+157251Y+075219X0200Y         S0      
317PVDDCR_SOC_P0    VIA   -    MD0100PA00X+155921Y+076228X0200Y    R180 S0      
317PVDDCR_SOC_P0    VIA   -    MD0100PA00X+156171Y+076228X0200Y    R180 S0      
317PVDDCR_SOC_P0    VIA   -    MD0100PA00X+155921Y+075978X0200Y    R180 S0      
317PVDDCR_SOC_P0    VIA   -    MD0100PA00X+156171Y+075978X0200Y    R180 S0      
317PVDDCR_SOC_P0    VIA   -    MD0100PA00X+155921Y+075728X0200Y    R180 S0      
317PVDDCR_SOC_P0    VIA   -    MD0100PA00X+156171Y+075728X0200Y    R180 S0      
317PVDDCR_SOC_P0    VIA   -    MD0100PA00X+157259Y+075978X0200Y    R180 S0      
317PVDDCR_SOC_P0    VIA   -    MD0100PA00X+157259Y+075728X0200Y    R180 S0      
317PVDDCR_SOC_P0    VIA   -    MD0100PA00X+157250Y+074469X0200Y    R180 S0      
317PVDDCR_SOC_P0    VIA   -    MD0100PA00X+155919Y+074469X0200Y    R180 S0      
317PVDDCR_SOC_P0    VIA   -    MD0100PA00X+156169Y+074469X0200Y    R180 S0      
317PVDDCR_SOC_P0    VIA   -    MD0100PA00X+155921Y+074719X0200Y         S0      
317PVDDCR_SOC_P0    VIA   -    MD0100PA00X+156171Y+074719X0200Y         S0      
317PVDDCR_SOC_P0    VIA   -    MD0100PA00X+157251Y+074719X0200Y         S0      
317PVDDCR_SOC_P0    VIA   -    MD0100PA00X+157501Y+075469X0200Y         S0      
317PVDDCR_SOC_P0    VIA   -    MD0100PA00X+157501Y+075219X0200Y         S0      
317PVDDCR_SOC_P0    VIA   -    MD0100PA00X+157501Y+074969X0200Y         S0      
317PVDDCR_SOC_P0    VIA   -    MD0100PA00X+157759Y+075228X0200Y    R180 S0      
317PVDDCR_SOC_P0    VIA   -    MD0100PA00X+157759Y+075478X0200Y    R180 S0      
317PVDDCR_SOC_P0    VIA   -    MD0100PA00X+157759Y+074978X0200Y    R180 S0      
317PVDDCR_SOC_P0    VIA   -    MD0100PA00X+157509Y+075728X0200Y    R180 S0      
317PVDDCR_SOC_P0    VIA   -    MD0100PA00X+157500Y+074469X0200Y    R180 S0      
317PVDDCR_SOC_P0    VIA   -    MD0100PA00X+157750Y+074469X0200Y    R180 S0      
317PVDDCR_SOC_P0    VIA   -    MD0100PA00X+157501Y+074719X0200Y         S0      
317PVDDCR_SOC_P0    VIA   -    MD0100PA00X+157759Y+074728X0200Y    R180 S0      
317PVDDCR_SOC_P0    VIA   -    MD0100PA00X+159219Y+073351X0200Y         S0      
317PVDDCR_SOC_P0    VIA   -    MD0100PA00X+159469Y+073351X0200Y         S0      
317PVDDCR_SOC_P0    VIA   -    MD0100PA00X+159219Y+073601X0200Y         S0      
317PVDDCR_SOC_P0    VIA   -    MD0100PA00X+159469Y+073601X0200Y         S0      
327PVDDCR_SOC_P0    PC602_-1          A18X+158015Y+073434X0400Y0500R270 S2      
327PVDDCR_SOC_P0    PC604_-1          A18X+155250Y+073434X0400Y0500R270 S2      
317PVDDCR_SOC_P0    VIA   -    MD0100PA00X+157924Y+068264X0200Y    R180 S0      
327PVDDCR_SOC_P0    PR362 -2          A18X+158065Y+068546X0198Y0197R090 S2      
317PVDDCR_SOC_P0    VIA   -    MD0100PA00X+161201Y+064887X0200Y    R180 S0      
327PVDDCR_SOC_P0    PR363 -2          A18X+161342Y+065169X0198Y0197R090 S2      
317PVDDCR_SOC_P0    VIA   -    MD0100PA00X+164501Y+062987X0200Y    R180 S0      
327PVDDCR_SOC_P0    PR367 -2          A18X+164642Y+063269X0198Y0197R090 S2      
317PVDDCR_SOC_P0    VIA   -    MD0100PA00X+163843Y+069192X0200Y    R180 S0      
317PVDDCR_SOC_P0    VIA   -    MD0100PA00X+162512Y+069192X0200Y    R180 S0      
317PVDDCR_SOC_P0    VIA   -    MD0100PA00X+162762Y+069192X0200Y    R180 S0      
317PVDDCR_SOC_P0    VIA   -    MD0100PA00X+164093Y+069192X0200Y    R180 S0      
317PVDDCR_SOC_P0    VIA   -    MD0100PA00X+164343Y+069192X0200Y    R180 S0      
317PVDDCR_SOC_P0    VIA   -    MD0100PA00X+164352Y+069701X0200Y    R180 S0      
317PVDDCR_SOC_P0    VIA   -    MD0100PA00X+164352Y+069451X0200Y    R180 S0      
317PVDDCR_SOC_P0    VIA   -    MD0100PA00X+164352Y+069951X0200Y    R180 S0      
317PVDDCR_SOC_P0    VIA   -    MD0100PA00X+164352Y+070201X0200Y    R180 S0      
317PVDDCR_SOC_P0    VIA   -    MD0100PA00X+161072Y+071601X0200Y    R180 S0      
317PVDDCR_SOC_P0    VIA   -    MD0100PA00X+161072Y+071351X0200Y    R180 S0      
317PVDDCR_SOC_P0    VIA   -    MD0100PA00X+161072Y+071851X0200Y    R180 S0      
317PVDDCR_SOC_P0    VIA   -    MD0100PA00X+161072Y+072101X0200Y    R180 S0      
317PVDDCR_SOC_P0    VIA   -    MD0100PA00X+159482Y+071092X0200Y    R180 S0      
317PVDDCR_SOC_P0    VIA   -    MD0100PA00X+161063Y+071092X0200Y    R180 S0      
317PVDDCR_SOC_P0    VIA   -    MD0100PA00X+160813Y+071092X0200Y    R180 S0      
317PVDDCR_SOC_P0    VIA   -    MD0100PA00X+160563Y+071092X0200Y    R180 S0      
317PVDDCR_SOC_P0    VIA   -    MD0100PA00X+159234Y+072092X0200Y         S0      
317PVDDCR_SOC_P0    VIA   -    MD0100PA00X+159484Y+072092X0200Y         S0      
317PVDDCR_SOC_P0    VIA   -    MD0100PA00X+159234Y+071342X0200Y         S0      
317PVDDCR_SOC_P0    VIA   -    MD0100PA00X+159234Y+071592X0200Y         S0      
317PVDDCR_SOC_P0    VIA   -    MD0100PA00X+159234Y+071842X0200Y         S0      
317PVDDCR_SOC_P0    VIA   -    MD0100PA00X+159484Y+071842X0200Y         S0      
317PVDDCR_SOC_P0    VIA   -    MD0100PA00X+159484Y+071592X0200Y         S0      
317PVDDCR_SOC_P0    VIA   -    MD0100PA00X+159484Y+071342X0200Y         S0      
317PVDDCR_SOC_P0    VIA   -    MD0100PA00X+160814Y+072092X0200Y         S0      
317PVDDCR_SOC_P0    VIA   -    MD0100PA00X+160814Y+071842X0200Y         S0      
317PVDDCR_SOC_P0    VIA   -    MD0100PA00X+160814Y+071592X0200Y         S0      
317PVDDCR_SOC_P0    VIA   -    MD0100PA00X+160814Y+071342X0200Y         S0      
317PVDDCR_SOC_P0    VIA   -    MD0100PA00X+160564Y+072092X0200Y         S0      
317PVDDCR_SOC_P0    VIA   -    MD0100PA00X+160564Y+071342X0200Y         S0      
317PVDDCR_SOC_P0    VIA   -    MD0100PA00X+160564Y+071592X0200Y         S0      
317PVDDCR_SOC_P0    VIA   -    MD0100PA00X+160564Y+071842X0200Y         S0      
317PVDDCR_SOC_P0    VIA   -    MD0100PA00X+162514Y+070192X0200Y         S0      
317PVDDCR_SOC_P0    VIA   -    MD0100PA00X+162764Y+070192X0200Y         S0      
317PVDDCR_SOC_P0    VIA   -    MD0100PA00X+162514Y+069442X0200Y         S0      
317PVDDCR_SOC_P0    VIA   -    MD0100PA00X+162514Y+069692X0200Y         S0      
317PVDDCR_SOC_P0    VIA   -    MD0100PA00X+162514Y+069942X0200Y         S0      
317PVDDCR_SOC_P0    VIA   -    MD0100PA00X+162764Y+069942X0200Y         S0      
317PVDDCR_SOC_P0    VIA   -    MD0100PA00X+162764Y+069692X0200Y         S0      
317PVDDCR_SOC_P0    VIA   -    MD0100PA00X+162764Y+069442X0200Y         S0      
317PVDDCR_SOC_P0    VIA   -    MD0100PA00X+164094Y+070192X0200Y         S0      
317PVDDCR_SOC_P0    VIA   -    MD0100PA00X+164094Y+069942X0200Y         S0      
317PVDDCR_SOC_P0    VIA   -    MD0100PA00X+164094Y+069692X0200Y         S0      
317PVDDCR_SOC_P0    VIA   -    MD0100PA00X+164094Y+069442X0200Y         S0      
317PVDDCR_SOC_P0    VIA   -    MD0100PA00X+163844Y+070192X0200Y         S0      
317PVDDCR_SOC_P0    VIA   -    MD0100PA00X+163844Y+069442X0200Y         S0      
317PVDDCR_SOC_P0    VIA   -    MD0100PA00X+163844Y+069692X0200Y         S0      
317PVDDCR_SOC_P0    VIA   -    MD0100PA00X+163844Y+069942X0200Y         S0      
327PVDDCR_SOC_P0    PC599 -1   M      A01X+165196Y+069582X0198Y0197R270 S1      
327PVDDCR_SOC_P0    PR296 -1          A01X+165659Y+069632X0198Y0197     S1      
327PVDDCR_SOC_P0    PL63  -4   M      A01X+156711Y+075094X0950Y1780R090 S1      
327PVDDCR_SOC_P0    PL64  -4   M      A01X+160024Y+071717X0950Y1780R090 S1      
327PVDDCR_SOC_P0    PL66  -4   M      A01X+163304Y+069817X0950Y1780R090 S1      
327PVDDCR_SOC_P0    PC603_-1          A18X+158732Y+070733X0400Y0500R270 S2      
327PVDDCR_SOC_P0    PC601 -1          A18X+156644Y+073657X0950Y1110R090 S2      
327PVDDCR_SOC_P0    PR334 -1          A18X+165515Y+067988X0198Y0197R090 S2      
327PVDDCR_SOC_P0    PC597 -1          A18X+163610Y+068382X0950Y1110R090 S2      
327PVDDCR_SOC_P0    PC615_-1          A18X+164985Y+068227X0400Y0500R270 S2      
327PVDDCR_SOC_P0    PC600_-1          A18X+161480Y+070124X0400Y0500R270 S2      
327PVDDCR_SOC_P0    PC614_-1          A18X+162230Y+068227X0400Y0500R270 S2      
327PVDDCR_SOC_P0    PC598 -1          A18X+160105Y+070295X0950Y1110R090 S2      
317PVDDCR_SOC_P0    VIA   -    MD0100PA00X+164338Y+071201X0200Y         S0      
317PVDDCR_SOC_P0    VIA   -    MD0100PA00X+162762Y+071201X0200Y         S0      
317PVDDCR_SOC_P0    VIA   -    MD0100PA00X+163838Y+071197X0200Y         S0      
317PVDDCR_SOC_P0    VIA   -    MD0100PA00X+164088Y+071197X0200Y         S0      
317PVDDCR_SOC_P0    VIA   -    MD0100PA00X+164338Y+070701X0200Y         S0      
317PVDDCR_SOC_P0    VIA   -    MD0100PA00X+164338Y+070451X0200Y         S0      
317PVDDCR_SOC_P0    VIA   -    MD0100PA00X+164338Y+070951X0200Y         S0      
317PVDDCR_SOC_P0    VIA   -    MD0100PA00X+164088Y+070447X0200Y         S0      
317PVDDCR_SOC_P0    VIA   -    MD0100PA00X+163838Y+070697X0200Y         S0      
317PVDDCR_SOC_P0    VIA   -    MD0100PA00X+163838Y+070447X0200Y         S0      
317PVDDCR_SOC_P0    VIA   -    MD0100PA00X+163838Y+070947X0200Y         S0      
317PVDDCR_SOC_P0    VIA   -    MD0100PA00X+164088Y+070947X0200Y         S0      
317PVDDCR_SOC_P0    VIA   -    MD0100PA00X+162762Y+070701X0200Y         S0      
317PVDDCR_SOC_P0    VIA   -    MD0100PA00X+162762Y+070451X0200Y         S0      
317PVDDCR_SOC_P0    VIA   -    MD0100PA00X+162762Y+070951X0200Y         S0      
317PVDDCR_SOC_P0    VIA   -    MD0100PA00X+164088Y+070697X0200Y         S0      
317PVDDCR_SOC_P0    VIA   -    MD0100PA00X+162512Y+071201X0200Y         S0      
317PVDDCR_SOC_P0    VIA   -    MD0100PA00X+162512Y+070701X0200Y         S0      
317PVDDCR_SOC_P0    VIA   -    MD0100PA00X+162512Y+070451X0200Y         S0      
317PVDDCR_SOC_P0    VIA   -    MD0100PA00X+162512Y+070951X0200Y         S0      
317m3782            VIA   -    MD0100PA00X+039766Y+134971X0200Y         S0      
327m3782            PR429 -1          A18X+039397Y+134726X0198Y0197R270 S2      
327m3782            PU33  -1          A01X+039893Y+134730X0090Y0240R090 S1      
317m3783            VIA   -    MD0100PA00X+036507Y+133038X0200Y         S0      
327m3783            PU38  -1          A01X+036635Y+132797X0090Y0240R090 S1      
327m3783            PR273 -1          A18X+036139Y+132793X0198Y0197R270 S2      
317m3784            VIA   -    MD0100PA00X+023287Y+137641X0200Y         S0      
327m3784            PR268 -1          A18X+022919Y+137396X0198Y0197R270 S2      
327m3784            PU36  -1          A01X+023415Y+137400X0090Y0240R090 S1      
317m3785            VIA   -    MD0100PA00X+026647Y+133026X0200Y         S0      
327m3785            PR269 -1          A18X+026279Y+132782X0198Y0197R270 S2      
327m3785            PU37  -1          A01X+026775Y+132786X0090Y0240R090 S1      
317m3786            VIA   -    MD0100PA00X+029937Y+133023X0200Y         S0      
327m3786            PR260 -1          A18X+029568Y+132779X0198Y0197R270 S2      
327m3786            PU5   -1          A01X+030065Y+132783X0090Y0240R090 S1      
317m3787            VIA   -    MD0100PA00X+033227Y+133018X0200Y         S0      
327m3787            PR261 -1          A18X+032859Y+132773X0198Y0197R270 S2      
327m3787            PU35  -1          A01X+033355Y+132777X0090Y0240R090 S1      
317m3788            VIA   -    M      A01X+014151Y+143650X0300Y         S1      
017m3788            VIA   -    M      A18X+014151Y+143650X0200Y         S1      
017m3788                  -    MD0100PA00X+014151Y+143650                       
327m3788            PU34  -45         A01X+013132Y+143744X0070Y0260R270 S1      
327m3788            PC357 -1          A01X+014492Y+143750X0198Y0197     S1      
327m3788            PR230 -2          A18X+013742Y+142500X0198Y0197     S2      
327m3788            PR231 -1   M      A18X+013758Y+142900X0198Y0197     S2      
317m3789            VIA   -    M      A01X+013801Y+144049X0200Y         S2      
017m3789            VIA   -    M      A18X+013801Y+144049X0260Y         S2      
017m3789                  -    MD0100PA00X+013801Y+144049                       
327m3789            PU34  -46         A01X+013132Y+143901X0070Y0260R270 S1      
327m3789            PC364 -1   M      A01X+014350Y+144558X0198Y0197R270 S1      
327m3789            PR251 -2          A01X+015100Y+144558X0198Y0197R090 S1      
327m3789            PR603 -1   M      A01X+014700Y+144558X0198Y0197R270 S1      
327m3790            PC93  -1          A01X+013312Y+144908X0198Y0197R090 S1      
327m3790            PC366 -1          A01X+013712Y+144908X0198Y0197R090 S1      
327m3790            PU34  -48         A01X+013132Y+144216X0070Y0260R270 S1      
317m3790            VIA   -    M      A01X+013310Y+144410X0200Y         S2      
017m3790            VIA   -    M      A18X+013310Y+144410X0260Y         S2      
017m3790                  -    MD0100PA00X+013310Y+144410                       
317m3790            VIA   -    MD0100PA00X+013746Y+138259X0200Y         S0      
327m3790            PU52  -39         A01X+013737Y+137646X0090Y0240     S1      
327m3790            PC620_-1   M      A01X+013460Y+138259X0198Y0197R090 S1      
327m3790            PC621_-1   M      A01X+010200Y+138259X0198Y0197R090 S1      
327m3790            PU53  -39         A01X+010477Y+137646X0090Y0240     S1      
317m3790            VIA   -    MD0100PA00X+010486Y+138259X0200Y    R180 S0      
317m3790            VIA   -    MD0100PA00X+023586Y+138259X0200Y         S0      
327m3790            PU36  -39         A01X+023577Y+137646X0090Y0240     S1      
327m3790            PC403_-1   M      A01X+023300Y+138259X0198Y0197R090 S1      
317m3790            VIA   -    MD0100PA00X+017016Y+138259X0200Y    R180 S0      
327m3790            PU40  -39         A01X+017007Y+137646X0090Y0240     S1      
327m3790            PC436_-1   M      A01X+016730Y+138259X0198Y0197R090 S1      
317m3790            VIA   -    MD0100PA00X+026946Y+133645X0200Y         S0      
327m3790            PU37  -39         A01X+026937Y+133032X0090Y0240     S1      
327m3790            PC404_-1   M      A01X+026660Y+133645X0198Y0197R090 S1      
317m3790            VIA   -    MD0100PA00X+040064Y+135589X0200Y         S0      
327m3790            PC136_-1   M      A01X+039778Y+135589X0198Y0197R090 S1      
327m3790            PU33  -39         A01X+040055Y+134976X0090Y0240     S1      
327m3790            PU38  -39         A01X+036797Y+133043X0090Y0240     S1      
327m3790            PC422_-1   M      A01X+036520Y+133656X0198Y0197R090 S1      
317m3790            VIA   -    MD0100PA00X+036806Y+133656X0200Y         S0      
317m3790            VIA   -    MD0100PA00X+020306Y+138259X0200Y         S0      
327m3790            PU39  -39         A01X+020297Y+137646X0090Y0240     S1      
327m3790            PC435_-1   M      A01X+020020Y+138259X0198Y0197R090 S1      
327m3790            PC374_-1   M      A01X+033240Y+133636X0198Y0197R090 S1      
327m3790            PU35  -39         A01X+033517Y+133023X0090Y0240     S1      
317m3790            VIA   -    MD0100PA00X+033526Y+133636X0200Y         S0      
327m3790            PC373_-1   M      A01X+029949Y+133642X0198Y0197R090 S1      
327m3790            PU5   -39         A01X+030226Y+133029X0090Y0240     S1      
317m3790            VIA   -    MD0100PA00X+030236Y+133642X0200Y         S0      
327m3791            PC138 -1          A01X+039388Y+134726X0198Y0197R090 S1      
327m3791            PU33  -3          A01X+039893Y+134376X0090Y0240R090 S1      
317m3791            VIA   -    MD0100PA00X+039388Y+134486X0200Y         S0      
327m3791            VIA   -    M      A18X+040358Y+134910X0260Y    R180 S2      
317m3791            VIA   -    MD0100PA00X+040734Y+135286X0200Y         S0      
327m3791            PR427 -2   M      A18X+039928Y+134409X0198Y0197R270 S2      
327m3791            PU33  -35         A01X+040764Y+134976X0090Y0240     S1      
327m3792            PC421 -1          A01X+036130Y+132793X0198Y0197R090 S1      
327m3792            PU38  -3          A01X+036635Y+132443X0090Y0240R090 S1      
317m3792            VIA   -    MD0100PA00X+036130Y+132553X0200Y         S0      
317m3792            VIA   -    MD0100PA00X+037476Y+133353X0200Y         S0      
327m3792            VIA   -    M      A18X+037109Y+132986X0260Y    R180 S2      
327m3792            PR271 -2   M      A18X+036670Y+132476X0198Y0197R270 S2      
327m3792            PU38  -35         A01X+037505Y+133043X0090Y0240     S1      
317m3793            VIA   -    MD0100PA00X+024256Y+137956X0200Y         S0      
327m3793            VIA   -    M      A18X+023630Y+137595X0260Y    R180 S2      
327m3793            PR264 -2   M      A18X+023450Y+137079X0198Y0197R270 S2      
327m3793            PU36  -35         A01X+024285Y+137646X0090Y0240     S1      
317m3793            VIA   -    MD0100PA00X+022910Y+137156X0200Y         S0      
327m3793            PC399 -1          A01X+022910Y+137396X0198Y0197R090 S1      
327m3793            PU36  -3          A01X+023415Y+137046X0090Y0240R090 S1      
317m3794            VIA   -    MD0100PA00X+027616Y+133342X0200Y         S0      
327m3794            VIA   -    M      A18X+027240Y+132966X0260Y    R180 S2      
327m3794            PC400 -1          A01X+026270Y+132782X0198Y0197R090 S1      
327m3794            PU37  -3          A01X+026775Y+132431X0090Y0240R090 S1      
317m3794            VIA   -    MD0100PA00X+026270Y+132541X0200Y         S0      
327m3794            PR265 -2   M      A18X+026810Y+132464X0198Y0197R270 S2      
327m3794            PU37  -35         A01X+027645Y+133032X0090Y0240     S1      
327m3795            VIA   -    M      A18X+030529Y+132963X0260Y    R180 S2      
327m3795            PU5   -3          A01X+030065Y+132428X0090Y0240R090 S1      
327m3795            PC370 -1          A01X+029560Y+132779X0198Y0197R090 S1      
317m3795            VIA   -    MD0100PA00X+029560Y+132538X0200Y         S0      
317m3795            VIA   -    MD0100PA00X+030905Y+133339X0200Y         S0      
327m3795            PR257 -2   M      A18X+030100Y+132462X0198Y0197R270 S2      
327m3795            PU5   -35         A01X+030935Y+133029X0090Y0240     S1      
327m3796            VIA   -    M      A18X+033820Y+132957X0260Y    R180 S2      
327m3796            PC369 -1          A01X+032850Y+132773X0198Y0197R090 S1      
327m3796            PU35  -3          A01X+033355Y+132423X0090Y0240R090 S1      
317m3796            VIA   -    MD0100PA00X+032850Y+132533X0200Y         S0      
317m3796            VIA   -    MD0100PA00X+034196Y+133333X0200Y         S0      
327m3796            PR256 -2   M      A18X+033390Y+132456X0198Y0197R270 S2      
327m3796            PU35  -35         A01X+034225Y+133023X0090Y0240     S1      
317m3797            VIA   -    M      A01X+013950Y+144600X0200Y         S2      
017m3797            VIA   -    M      A18X+013950Y+144600X0260Y         S2      
017m3797                  -    MD0100PA00X+013950Y+144600                       
327m3797            PR253 -1          A01X+014903Y+144904X0198Y0197R090 S1      
327m3797            PU34  -47         A01X+013132Y+144059X0070Y0260R270 S1      
327m3797            PC29  -1   M      A01X+014103Y+144904X0198Y0197R090 S1      
327m3797            PC365 -1   M      A01X+014503Y+144904X0198Y0197R090 S1      
317m3798            VIA   -    M      A01X+014150Y+143350X0200Y         S2      
017m3798            VIA   -    M      A18X+014150Y+143350X0260Y         S2      
017m3798                  -    MD0100PA00X+014150Y+143350                       
327m3798            PC368 -1          A01X+014492Y+143350X0198Y0197     S1      
327m3798            PU34  -44         A01X+013132Y+143586X0070Y0260R270 S1      
327m3798            PU36  -36         A01X+024108Y+137646X0090Y0240     S1      
317m3798            VIA   -    MD0100PA00X+023982Y+138053X0200Y         S0      
327m3798            PU5   -36         A01X+030758Y+133029X0090Y0240     S1      
317m3798            VIA   -    MD0100PA00X+030631Y+133436X0200Y         S0      
327m3798            PU38  -36         A01X+037328Y+133043X0090Y0240     S1      
317m3798            VIA   -    MD0100PA00X+037202Y+133450X0200Y         S0      
327m3798            PU33  -36         A01X+040586Y+134976X0090Y0240     S1      
317m3798            VIA   -    MD0100PA00X+040460Y+135383X0200Y         S0      
317m3798            VIA   -    MD0100PA00X+033922Y+133430X0200Y         S0      
327m3798            PU35  -36         A01X+034048Y+133023X0090Y0240     S1      
317m3798            VIA   -    MD0100PA00X+027342Y+133438X0200Y         S0      
327m3798            PU37  -36         A01X+027468Y+133032X0090Y0240     S1      
327m3799            R8250 -2          A01X+009008Y+144000X0198Y0197     S1      
327m3799            PU34  -15         A01X+010868Y+143901X0070Y0260R270 S1      
317m3800            VIA   -    MD0100PA00X+071771Y+034610X0200Y         S0      
317m3800            VIA   -    M      A01X+065890Y+034188X0200Y         S2      
017m3800            VIA   -    M      A18X+065890Y+034188X0260Y         S2      
017m3800                  -    MD0100PA00X+065890Y+034188                       
317m3800            VIA   -    MD0100PA00X+072729Y+043411X0180Y    R090 S0      
327m3800            R1188 -1          A01X+072750Y+039644X0198Y0197R270 S1      
327m3800            U18   -L6  M      A01X+072883Y+043564X0160Y    R090 S1      
317m3800            VIA   -    MD0100PA00X+044950Y+047401X0200Y         S0      
327m3800            C5020 -2   M      A01X+008692Y+143550X0198Y0197R180 S1      
327m3800            R8250 -1          A01X+008692Y+144000X0198Y0197     S1      
317m3800            VIA   -    MD0100PA00X+008105Y+142741X0200Y         S0      
317m3801            VIA   -    M      A01X+010164Y+143294X0200Y         S2      
017m3801            VIA   -    M      A18X+010164Y+143294X0260Y         S2      
017m3801                  -    MD0100PA00X+010164Y+143294                       
327m3801            PU34  -18         A01X+010868Y+143429X0070Y0260R270 S1      
327m3801            R240  -2          A18X+009008Y+143050X0198Y0197R180 S2      
327m3801            R8247 -2   M      A18X+009908Y+143050X0198Y0197R180 S2      
317m3802            VIA   -    M      A01X+008344Y+143050X0200Y         S2      
017m3802            VIA   -    M      A18X+008344Y+143050X0260Y         S2      
017m3802                  -    MD0100PA00X+008344Y+143050                       
327m3802            R240  -1          A18X+008692Y+143050X0198Y0197R180 S2      
327m3802            U40   -4          A01X+033093Y+056027X0140Y0440     S1      
317m3802            VIA   -    MD0100PA00X+034675Y+051538X0200Y         S0      
317m3803            VIA   -    M      A01X+011910Y+146030X0200Y         S2      
017m3803            VIA   -    M      A18X+011910Y+146030X0260Y         S2      
017m3803                  -    MD0100PA00X+011910Y+146030                       
317m3803            VIA   -    MD0100PA00X+040809Y+135543X0200Y         S0      
327m3803            PU33  -34         A01X+040941Y+134976X0090Y0240     S1      
327m3803            PU34  -7          A01X+011921Y+144482X0070Y0260R180 S1      
327m3804            VIA   -    M      A01X+011866Y+145546X0300Y         S1      
317m3804            VIA   -    MD0100PA00X+037550Y+133610X0200Y         S0      
327m3804            PU38  -34         A01X+037682Y+133043X0090Y0240     S1      
317m3804            VIA   -    MD0100PA00X+011612Y+145800X0200Y         S0      
327m3804            PU34  -8          A01X+011764Y+144482X0070Y0260R180 S1      
317m3805            VIA   -    M      A01X+011690Y+144900X0200Y         S2      
017m3805            VIA   -    M      A18X+011690Y+144900X0260Y         S2      
017m3805                  -    MD0100PA00X+011690Y+144900                       
327m3805            PU36  -34         A01X+024462Y+137646X0090Y0240     S1      
317m3805            VIA   -    MD0100PA00X+024330Y+138213X0200Y         S0      
327m3805            PU34  -9          A01X+011606Y+144482X0070Y0260R180 S1      
317m3806            VIA   -    MD0100PA00X+011360Y+144910X0200Y         S0      
327m3806            PU34  -10         A01X+011449Y+144482X0070Y0260R180 S1      
317m3806            VIA   -    MD0100PA00X+027690Y+133598X0200Y         S0      
327m3806            PU37  -34         A01X+027822Y+133032X0090Y0240     S1      
317m3807            VIA   -    MD0100PA00X+011248Y+145242X0200Y         S0      
327m3807            PU34  -11         A01X+011291Y+144482X0070Y0260R180 S1      
317m3807            VIA   -    MD0100PA00X+030980Y+133596X0200Y         S0      
327m3807            PU5   -34         A01X+031112Y+133029X0090Y0240     S1      
317m3808            VIA   -    M      A01X+011350Y+145560X0200Y         S2      
017m3808            VIA   -    M      A18X+011350Y+145560X0260Y         S2      
017m3808                  -    MD0100PA00X+011350Y+145560                       
327m3808            PU34  -12         A01X+011134Y+144482X0070Y0260R180 S1      
317m3808            VIA   -    MD0100PA00X+034270Y+133590X0200Y         S0      
327m3808            PU35  -34         A01X+034402Y+133023X0090Y0240     S1      
327m3809            PC402_-1   M      A01X+026270Y+132047X0198Y0197R270 S1      
327m3809            PU37  -4          A01X+026775Y+132254X0090Y0240R090 S1      
317m3809            VIA   -    MD0100PA00X+026270Y+132287X0200Y    R180 S0      
317m3809            VIA   -    MD0100PA00X+029560Y+132284X0200Y    R180 S0      
317m3809            VIA   -    MD0100PA00X+032850Y+132279X0200Y    R180 S0      
327m3809            PR256 -1          A18X+033390Y+132141X0198Y0197R270 S2      
327m3809            PU35  -4          A01X+033355Y+132246X0090Y0240R090 S1      
327m3809            PC371_-1   M      A01X+032850Y+132038X0198Y0197R270 S1      
317m3809            VIA   -    MD0100PA00X+036130Y+132299X0200Y    R180 S0      
317m3809            VIA   -    MD0100PA00X+039388Y+134232X0200Y    R180 S0      
327m3809            PR427 -1          A18X+039928Y+134094X0198Y0197R270 S2      
327m3809            PU33  -4          A01X+039893Y+134199X0090Y0240R090 S1      
327m3809            PC139_-1   M      A01X+039388Y+133991X0198Y0197R270 S1      
327m3809            PR271 -1          A18X+036670Y+132161X0198Y0197R270 S2      
327m3809            PU38  -4          A01X+036635Y+132266X0090Y0240R090 S1      
327m3809            PC423_-1   M      A01X+036130Y+132058X0198Y0197R270 S1      
327m3809            PR257 -1          A18X+030100Y+132146X0198Y0197R270 S2      
327m3809            PU5   -4          A01X+030065Y+132251X0090Y0240R090 S1      
327m3809            PC372_-1   M      A01X+029560Y+132044X0198Y0197R270 S1      
327m3809            PR265 -1          A18X+026810Y+132149X0198Y0197R270 S2      
317m3809            VIA   -    MD0100PA00X+022910Y+136902X0200Y    R180 S0      
327m3809            PC401_-1   M      A01X+022910Y+136661X0198Y0197R270 S1      
327m3809            PU36  -4          A01X+023415Y+136869X0090Y0240R090 S1      
327m3809            PR264 -1          A18X+023450Y+136764X0198Y0197R270 S2      
317m3809            VIA   -    MD0100PA00X+019630Y+136902X0200Y    R180 S0      
327m3809            PC437_-1   M      A01X+019630Y+136661X0198Y0197R270 S1      
327m3809            PU39  -4          A01X+020135Y+136869X0090Y0240R090 S1      
327m3809            PR277 -1          A18X+020170Y+136764X0198Y0197R270 S2      
317m3809            VIA   -    MD0100PA00X+016340Y+136902X0200Y    R180 S0      
327m3809            PC434_-1   M      A01X+016340Y+136661X0198Y0197R270 S1      
327m3809            PU40  -4          A01X+016845Y+136869X0090Y0240R090 S1      
327m3809            PR276 -1          A18X+016880Y+136764X0198Y0197R270 S2      
327m3809            PR370 -1          A18X+010350Y+136764X0198Y0197R270 S2      
327m3809            PR371 -1          A18X+013610Y+136764X0198Y0197R270 S2      
327m3809            PC619_-1   M      A01X+013070Y+136661X0198Y0197R270 S1      
327m3809            PU52  -4          A01X+013575Y+136869X0090Y0240R090 S1      
317m3809            VIA   -    MD0100PA00X+013070Y+136902X0200Y    R180 S0      
317m3809            VIA   -    MD0100PA00X+009810Y+136902X0200Y    R180 S0      
327m3809            PC618_-1   M      A01X+009810Y+136661X0198Y0197R270 S1      
327m3809            PU53  -4          A01X+010315Y+136869X0090Y0240R090 S1      
327m3809            VIA   -           A01X+009319Y+137776X0300Y    R180 S1      
327m3809            PR340 -1          A01X+009471Y+138276X0198Y0197R090 S1      
327m3809            PR341 -1          A01X+009060Y+138271X0198Y0197R090 S1      
327m3810            PU34  -41         A01X+013132Y+143114X0070Y0260R270 S1      
327m3810            R8241 -2          A01X+014492Y+142150X0198Y0197R180 S1      
327m3810            R8252 -2   M      A01X+014492Y+142550X0198Y0197R180 S1      
327m3811            R8241 -1          A01X+014808Y+142150X0198Y0197R180 S1      
317m3811            VIA   -    M      A01X+045327Y+047839X0200Y         S2      
017m3811            VIA   -    M      A18X+045327Y+047839X0260Y         S2      
017m3811                  -    MD0100PA00X+045327Y+047839                       
317m3811            VIA   -    MD0100PA00X+066655Y+034612X0200Y         S0      
327m3811            R141  -1          A18X+070350Y+039329X0198Y0197R270 S2      
317m3811            VIA   -    MD0100PA00X+070370Y+038683X0200Y    R090 S0      
317m3811            VIA   -    MD0100PA00X+015617Y+143540X0200Y         S0      
327m3812            VIA   -    M      A01X+040262Y+135434X0160Y0041R090 S1      
327m3812            PU33  -37         A01X+040409Y+134976X0090Y0240     S1      
327m3812            PR426 -1          A01X+040167Y+135886X0198Y0197     S1      
327m3813            VIA   -    M      A01X+037004Y+133504X0160Y0041R090 S1      
327m3813            PU38  -37         A01X+037151Y+133043X0090Y0240     S1      
327m3813            PR270 -1          A01X+036909Y+133953X0198Y0197     S1      
327m3814            VIA   -    M      A01X+023784Y+138100X0160Y0041R090 S1      
327m3814            PR262 -1          A01X+023689Y+138556X0198Y0197     S1      
327m3814            PU36  -37         A01X+023931Y+137646X0090Y0240     S1      
327m3815            VIA   -    M      A01X+027144Y+133500X0160Y0041R090 S1      
327m3815            PU37  -37         A01X+027291Y+133032X0090Y0240     S1      
327m3815            PR263 -1          A01X+027049Y+133942X0198Y0197     S1      
327m3816            VIA   -    M      A01X+030434Y+133500X0160Y0041R090 S1      
327m3816            PU5   -37         A01X+030581Y+133029X0090Y0240     S1      
327m3816            PR254 -1          A01X+030339Y+133939X0198Y0197     S1      
327m3817            VIA   -    M      A01X+033724Y+133486X0160Y0041R090 S1      
327m3817            PU35  -37         A01X+033871Y+133023X0090Y0240     S1      
327m3817            PR255 -1          A01X+033629Y+133933X0198Y0197     S1      
317m3818            VIA   -    M      A01X+012070Y+140810X0300Y         S1      
017m3818            VIA   -    M      A18X+012070Y+140810X0200Y         S1      
017m3818                  -    MD0100PA00X+012070Y+140810                       
317m3818            VIA   -    MD0100PA00X+040064Y+135338X0200Y    R180 S0      
327m3818            PU33  -38         A01X+040232Y+134976X0090Y0240     S1      
327m3818            PU34  -32         A01X+012236Y+142218X0070Y0260R180 S1      
317m3819            VIA   -    M      A01X+012205Y+140375X0200Y         S2      
017m3819            VIA   -    M      A18X+012205Y+140375X0260Y         S2      
017m3819                  -    MD0100PA00X+012205Y+140375                       
317m3819            VIA   -    MD0100PA00X+036806Y+133405X0200Y         S0      
327m3819            PU38  -38         A01X+036974Y+133043X0090Y0240     S1      
327m3819            PU34  -31         A01X+012079Y+142218X0070Y0260R180 S1      
317m3820            VIA   -    M      A01X+011670Y+141050X0200Y         S2      
017m3820            VIA   -    M      A18X+011670Y+141050X0260Y         S2      
017m3820                  -    MD0100PA00X+011670Y+141050                       
327m3820            PU36  -38         A01X+023754Y+137646X0090Y0240     S1      
317m3820            VIA   -    MD0100PA00X+023586Y+138008X0200Y         S0      
327m3820            PU34  -30         A01X+011921Y+142218X0070Y0260R180 S1      
317m3821            VIA   -    M      A01X+011670Y+141570X0200Y         S2      
017m3821            VIA   -    M      A18X+011670Y+141570X0260Y         S2      
017m3821                  -    MD0100PA00X+011670Y+141570                       
327m3821            PU34  -29         A01X+011764Y+142218X0070Y0260R180 S1      
317m3821            VIA   -    MD0100PA00X+026946Y+133394X0200Y         S0      
327m3821            PU37  -38         A01X+027114Y+133032X0090Y0240     S1      
317m3822            VIA   -    M      A01X+011350Y+139860X0300Y         S1      
017m3822            VIA   -    M      A18X+011350Y+139860X0200Y         S1      
017m3822                  -    MD0100PA00X+011350Y+139860                       
327m3822            PU5   -38         A01X+030403Y+133029X0090Y0240     S1      
317m3822            VIA   -    MD0100PA00X+030236Y+133391X0200Y         S0      
327m3822            PU34  -28         A01X+011606Y+142218X0070Y0260R180 S1      
317m3823            VIA   -    M      A01X+011160Y+140310X0200Y         S2      
017m3823            VIA   -    M      A18X+011160Y+140310X0260Y         S2      
017m3823                  -    MD0100PA00X+011160Y+140310                       
327m3823            PU34  -27         A01X+011449Y+142218X0070Y0260R180 S1      
327m3823            PU35  -38         A01X+033694Y+133023X0090Y0240     S1      
317m3823            VIA   -    MD0100PA00X+033526Y+133385X0200Y    R180 S0      
327m3824            VIA   -    M      A01X+010395Y+143600X0160Y0041R180 S1      
317m3824            VIA   -    MD0100PA00X+010150Y+143600X0200Y         S0      
327m3824            PU34  -17         A01X+010868Y+143586X0070Y0260R270 S1      
327m3824            C8359 -1          A01X+009908Y+143550X0198Y0197R180 S1      
327m3824            R8235 -2          A18X+009908Y+143550X0198Y0197R180 S2      
327m3825            VIA   -    M      A18X+013335Y+143465X0260Y         S2      
317m3825            VIA   -    MD0100PA00X+013600Y+143200X0200Y         S0      
317m3825            VIA   -    MD0100PA00X+007382Y+144289X0200Y         S0      
327m3825            PR244 -1          A18X+013008Y+143650X0198Y0197     S2      
327m3825            PU34  -42         A01X+013132Y+143271X0070Y0260R270 S1      
327m3825            PQ12  -D          A01X+007700Y+144744X0320Y0360     S1      
317PVDDCR_CPU1_P1   VIA   -    MD0080PA00X+047640Y+113010X0160Y         S0      
317PVDDCR_CPU1_P1   VIA   -    MD0080PA00X+042461Y+114924X0160Y         S0      
317PVDDCR_CPU1_P1   VIA   -    MD0080PA00X+041351Y+114924X0160Y         S0      
317PVDDCR_CPU1_P1   VIA   -    MD0080PA00X+041721Y+116199X0160Y         S0      
317PVDDCR_CPU1_P1   VIA   -    MD0080PA00X+041351Y+116199X0160Y         S0      
317PVDDCR_CPU1_P1   VIA   -    MD0080PA00X+040241Y+116199X0160Y         S0      
317PVDDCR_CPU1_P1   VIA   -    MD0080PA00X+040611Y+116199X0160Y         S0      
317PVDDCR_CPU1_P1   VIA   -    MD0080PA00X+039315Y+115243X0160Y         S0      
317PVDDCR_CPU1_P1   VIA   -    MD0080PA00X+039500Y+116199X0160Y         S0      
317PVDDCR_CPU1_P1   VIA   -    MD0080PA00X+039130Y+116199X0160Y         S0      
317PVDDCR_CPU1_P1   VIA   -    MD0080PA00X+038390Y+116199X0160Y         S0      
317PVDDCR_CPU1_P1   VIA   -    MD0080PA00X+038020Y+116199X0160Y         S0      
317PVDDCR_CPU1_P1   VIA   -    MD0080PA00X+037280Y+116199X0160Y         S0      
317PVDDCR_CPU1_P1   VIA   -    MD0080PA00X+036910Y+116199X0160Y         S0      
317PVDDCR_CPU1_P1   VIA   -    MD0080PA00X+037095Y+115880X0160Y         S0      
317PVDDCR_CPU1_P1   VIA   -    MD0080PA00X+038020Y+114924X0160Y         S0      
317PVDDCR_CPU1_P1   VIA   -    MD0080PA00X+038945Y+105676X0160Y         S0      
317PVDDCR_CPU1_P1   VIA   -    MD0080PA00X+038760Y+105995X0160Y         S0      
317PVDDCR_CPU1_P1   VIA   -    MD0080PA00X+038390Y+105995X0160Y         S0      
317PVDDCR_CPU1_P1   VIA   -    MD0080PA00X+039500Y+105995X0160Y         S0      
317PVDDCR_CPU1_P1   VIA   -    MD0080PA00X+038760Y+107270X0160Y         S0      
317PVDDCR_CPU1_P1   VIA   -    MD0080PA00X+038390Y+107270X0160Y         S0      
317PVDDCR_CPU1_P1   VIA   -    MD0080PA00X+039500Y+107270X0160Y         S0      
317PVDDCR_CPU1_P1   VIA   -    MD0080PA00X+038760Y+109821X0160Y         S0      
317PVDDCR_CPU1_P1   VIA   -    MD0080PA00X+038390Y+109821X0160Y         S0      
317PVDDCR_CPU1_P1   VIA   -    MD0080PA00X+039500Y+109821X0160Y         S0      
317PVDDCR_CPU1_P1   VIA   -    MD0080PA00X+038760Y+108546X0160Y         S0      
317PVDDCR_CPU1_P1   VIA   -    MD0080PA00X+038390Y+108546X0160Y         S0      
317PVDDCR_CPU1_P1   VIA   -    MD0080PA00X+039500Y+108546X0160Y         S0      
317PVDDCR_CPU1_P1   VIA   -    MD0080PA00X+038390Y+111735X0160Y         S0      
317PVDDCR_CPU1_P1   VIA   -    MD0080PA00X+038760Y+111735X0160Y         S0      
317PVDDCR_CPU1_P1   VIA   -    MD0080PA00X+039500Y+111735X0160Y         S0      
317PVDDCR_CPU1_P1   VIA   -    MD0080PA00X+039130Y+114924X0160Y         S0      
317PVDDCR_CPU1_P1   VIA   -    MD0080PA00X+038390Y+114286X0160Y         S0      
317PVDDCR_CPU1_P1   VIA   -    MD0080PA00X+038760Y+114286X0160Y         S0      
317PVDDCR_CPU1_P1   VIA   -    MD0080PA00X+039500Y+114286X0160Y         S0      
317PVDDCR_CPU1_P1   VIA   -    MD0080PA00X+038390Y+113010X0160Y         S0      
317PVDDCR_CPU1_P1   VIA   -    MD0080PA00X+038760Y+113010X0160Y         S0      
317PVDDCR_CPU1_P1   VIA   -    MD0080PA00X+039500Y+113010X0160Y         S0      
317PVDDCR_CPU1_P1   VIA   -    MD0080PA00X+038205Y+115243X0160Y         S0      
317PVDDCR_CPU1_P1   VIA   -    MD0080PA00X+040426Y+105676X0160Y         S0      
317PVDDCR_CPU1_P1   VIA   -    MD0080PA00X+040611Y+105357X0160Y         S0      
317PVDDCR_CPU1_P1   VIA   -    MD0080PA00X+040611Y+105995X0160Y         S0      
317PVDDCR_CPU1_P1   VIA   -    MD0080PA00X+040981Y+105995X0160Y         S0      
317PVDDCR_CPU1_P1   VIA   -    MD0080PA00X+039686Y+105676X0160Y         S0      
317PVDDCR_CPU1_P1   VIA   -    MD0080PA00X+039686Y+105038X0160Y         S0      
317PVDDCR_CPU1_P1   VIA   -    MD0080PA00X+039870Y+105357X0160Y         S0      
317PVDDCR_CPU1_P1   VIA   -    MD0080PA00X+039870Y+105995X0160Y         S0      
317PVDDCR_CPU1_P1   VIA   -    MD0080PA00X+040981Y+107270X0160Y         S0      
317PVDDCR_CPU1_P1   VIA   -    MD0080PA00X+040611Y+107270X0160Y         S0      
317PVDDCR_CPU1_P1   VIA   -    MD0080PA00X+039870Y+107270X0160Y         S0      
317PVDDCR_CPU1_P1   VIA   -    MD0080PA00X+040981Y+108546X0160Y         S0      
317PVDDCR_CPU1_P1   VIA   -    MD0080PA00X+040611Y+108546X0160Y         S0      
317PVDDCR_CPU1_P1   VIA   -    MD0080PA00X+039870Y+108546X0160Y         S0      
317PVDDCR_CPU1_P1   VIA   -    MD0080PA00X+040981Y+109821X0160Y         S0      
317PVDDCR_CPU1_P1   VIA   -    MD0080PA00X+040611Y+109821X0160Y         S0      
317PVDDCR_CPU1_P1   VIA   -    MD0080PA00X+039870Y+109821X0160Y         S0      
317PVDDCR_CPU1_P1   VIA   -    MD0080PA00X+040981Y+111735X0160Y         S0      
317PVDDCR_CPU1_P1   VIA   -    MD0080PA00X+040611Y+111735X0160Y         S0      
317PVDDCR_CPU1_P1   VIA   -    MD0080PA00X+040796Y+110778X0160Y         S0      
317PVDDCR_CPU1_P1   VIA   -    MD0080PA00X+039870Y+111735X0160Y         S0      
317PVDDCR_CPU1_P1   VIA   -    MD0080PA00X+040981Y+113010X0160Y         S0      
317PVDDCR_CPU1_P1   VIA   -    MD0080PA00X+040611Y+113010X0160Y         S0      
317PVDDCR_CPU1_P1   VIA   -    MD0080PA00X+039870Y+113010X0160Y         S0      
317PVDDCR_CPU1_P1   VIA   -    MD0080PA00X+040426Y+115243X0160Y         S0      
317PVDDCR_CPU1_P1   VIA   -    MD0080PA00X+040241Y+114924X0160Y         S0      
317PVDDCR_CPU1_P1   VIA   -    MD0080PA00X+040981Y+114286X0160Y         S0      
317PVDDCR_CPU1_P1   VIA   -    MD0080PA00X+040611Y+114286X0160Y         S0      
317PVDDCR_CPU1_P1   VIA   -    MD0080PA00X+039870Y+114286X0160Y         S0      
317PVDDCR_CPU1_P1   VIA   -    MD0080PA00X+042091Y+105995X0160Y         S0      
317PVDDCR_CPU1_P1   VIA   -    MD0080PA00X+041721Y+105995X0160Y         S0      
317PVDDCR_CPU1_P1   VIA   -    MD0080PA00X+041906Y+105676X0160Y         S0      
317PVDDCR_CPU1_P1   VIA   -    MD0080PA00X+042091Y+105357X0160Y         S0      
317PVDDCR_CPU1_P1   VIA   -    MD0080PA00X+041166Y+105676X0160Y         S0      
317PVDDCR_CPU1_P1   VIA   -    MD0080PA00X+041351Y+105357X0160Y         S0      
317PVDDCR_CPU1_P1   VIA   -    MD0080PA00X+041166Y+105038X0160Y         S0      
317PVDDCR_CPU1_P1   VIA   -    MD0080PA00X+042091Y+107270X0160Y         S0      
317PVDDCR_CPU1_P1   VIA   -    MD0080PA00X+041721Y+107270X0160Y         S0      
317PVDDCR_CPU1_P1   VIA   -    MD0080PA00X+041721Y+109821X0160Y         S0      
317PVDDCR_CPU1_P1   VIA   -    MD0080PA00X+042091Y+109821X0160Y         S0      
317PVDDCR_CPU1_P1   VIA   -    MD0080PA00X+042091Y+108546X0160Y         S0      
317PVDDCR_CPU1_P1   VIA   -    MD0080PA00X+041721Y+108546X0160Y         S0      
317PVDDCR_CPU1_P1   VIA   -    MD0080PA00X+041721Y+111735X0160Y         S0      
317PVDDCR_CPU1_P1   VIA   -    MD0080PA00X+042091Y+111735X0160Y         S0      
317PVDDCR_CPU1_P1   VIA   -    MD0080PA00X+041906Y+110778X0160Y         S0      
317PVDDCR_CPU1_P1   VIA   -    MD0080PA00X+042276Y+110778X0160Y         S0      
317PVDDCR_CPU1_P1   VIA   -    MD0080PA00X+041166Y+110778X0160Y         S0      
317PVDDCR_CPU1_P1   VIA   -    MD0080PA00X+042091Y+114286X0160Y         S0      
317PVDDCR_CPU1_P1   VIA   -    MD0080PA00X+041721Y+114286X0160Y         S0      
317PVDDCR_CPU1_P1   VIA   -    MD0080PA00X+041721Y+113010X0160Y         S0      
317PVDDCR_CPU1_P1   VIA   -    MD0080PA00X+042091Y+113010X0160Y         S0      
317PVDDCR_CPU1_P1   VIA   -    MD0080PA00X+041536Y+115243X0160Y         S0      
317PVDDCR_CPU1_P1   VIA   -    MD0080PA00X+042461Y+116199X0160Y         S0      
317PVDDCR_CPU1_P1   VIA   -    MD0080PA00X+043571Y+105357X0160Y         S0      
317PVDDCR_CPU1_P1   VIA   -    MD0080PA00X+043386Y+105676X0160Y         S0      
317PVDDCR_CPU1_P1   VIA   -    MD0080PA00X+042831Y+105357X0160Y         S0      
317PVDDCR_CPU1_P1   VIA   -    MD0080PA00X+042646Y+105676X0160Y         S0      
317PVDDCR_CPU1_P1   VIA   -    MD0080PA00X+042646Y+105038X0160Y         S0      
317PVDDCR_CPU1_P1   VIA   -    MD0080PA00X+043386Y+108227X0160Y         S0      
317PVDDCR_CPU1_P1   VIA   -    MD0080PA00X+043016Y+108227X0160Y         S0      
317PVDDCR_CPU1_P1   VIA   -    MD0080PA00X+043386Y+106951X0160Y         S0      
317PVDDCR_CPU1_P1   VIA   -    MD0080PA00X+043016Y+106951X0160Y         S0      
317PVDDCR_CPU1_P1   VIA   -    MD0080PA00X+043386Y+111416X0160Y         S0      
317PVDDCR_CPU1_P1   VIA   -    MD0080PA00X+043016Y+111416X0160Y         S0      
317PVDDCR_CPU1_P1   VIA   -    MD0080PA00X+043201Y+110459X0160Y         S0      
317PVDDCR_CPU1_P1   VIA   -    MD0080PA00X+043386Y+109502X0160Y         S0      
317PVDDCR_CPU1_P1   VIA   -    MD0080PA00X+042831Y+110459X0160Y         S0      
317PVDDCR_CPU1_P1   VIA   -    MD0080PA00X+043016Y+109502X0160Y         S0      
317PVDDCR_CPU1_P1   VIA   -    MD0080PA00X+043386Y+114605X0160Y         S0      
317PVDDCR_CPU1_P1   VIA   -    MD0080PA00X+043386Y+113967X0160Y         S0      
317PVDDCR_CPU1_P1   VIA   -    MD0080PA00X+043016Y+114605X0160Y         S0      
317PVDDCR_CPU1_P1   VIA   -    MD0080PA00X+043016Y+113967X0160Y         S0      
317PVDDCR_CPU1_P1   VIA   -    MD0080PA00X+043386Y+112692X0160Y         S0      
317PVDDCR_CPU1_P1   VIA   -    MD0080PA00X+043016Y+112692X0160Y         S0      
317PVDDCR_CPU1_P1   VIA   -    MD0080PA00X+043016Y+115243X0160Y         S0      
317PVDDCR_CPU1_P1   VIA   -    MD0080PA00X+042646Y+115243X0160Y         S0      
317PVDDCR_CPU1_P1   VIA   -    MD0080PA00X+042831Y+116199X0160Y         S0      
317PVDDCR_CPU1_P1   VIA   -    MD0080PA00X+045234Y+106951X0160Y         S0      
317PVDDCR_CPU1_P1   VIA   -    MD0080PA00X+044864Y+106951X0160Y         S0      
317PVDDCR_CPU1_P1   VIA   -    MD0080PA00X+045234Y+105038X0160Y         S0      
317PVDDCR_CPU1_P1   VIA   -    MD0080PA00X+045049Y+105357X0160Y         S0      
317PVDDCR_CPU1_P1   VIA   -    MD0080PA00X+045234Y+105676X0160Y         S0      
317PVDDCR_CPU1_P1   VIA   -    MD0080PA00X+045419Y+110459X0160Y         S0      
317PVDDCR_CPU1_P1   VIA   -    MD0080PA00X+045049Y+110459X0160Y         S0      
317PVDDCR_CPU1_P1   VIA   -    MD0080PA00X+045234Y+109502X0160Y         S0      
317PVDDCR_CPU1_P1   VIA   -    MD0080PA00X+044864Y+109502X0160Y         S0      
317PVDDCR_CPU1_P1   VIA   -    MD0080PA00X+045234Y+108227X0160Y         S0      
317PVDDCR_CPU1_P1   VIA   -    MD0080PA00X+044864Y+108227X0160Y         S0      
317PVDDCR_CPU1_P1   VIA   -    MD0080PA00X+045234Y+112692X0160Y         S0      
317PVDDCR_CPU1_P1   VIA   -    MD0080PA00X+044864Y+112692X0160Y         S0      
317PVDDCR_CPU1_P1   VIA   -    MD0080PA00X+045234Y+111416X0160Y         S0      
317PVDDCR_CPU1_P1   VIA   -    MD0080PA00X+044864Y+111416X0160Y         S0      
317PVDDCR_CPU1_P1   VIA   -    MD0080PA00X+044864Y+116518X0160Y         S0      
317PVDDCR_CPU1_P1   VIA   -    MD0080PA00X+045234Y+115243X0160Y         S0      
317PVDDCR_CPU1_P1   VIA   -    MD0080PA00X+045419Y+116199X0160Y         S0      
317PVDDCR_CPU1_P1   VIA   -    MD0080PA00X+045234Y+114605X0160Y         S0      
317PVDDCR_CPU1_P1   VIA   -    MD0080PA00X+044864Y+114605X0160Y         S0      
317PVDDCR_CPU1_P1   VIA   -    MD0080PA00X+045234Y+113967X0160Y         S0      
317PVDDCR_CPU1_P1   VIA   -    MD0080PA00X+044864Y+113967X0160Y         S0      
317PVDDCR_CPU1_P1   VIA   -    MD0080PA00X+046529Y+105995X0160Y         S0      
317PVDDCR_CPU1_P1   VIA   -    MD0080PA00X+045974Y+105676X0160Y         S0      
317PVDDCR_CPU1_P1   VIA   -    MD0080PA00X+046159Y+105995X0160Y         S0      
317PVDDCR_CPU1_P1   VIA   -    MD0080PA00X+045789Y+105357X0160Y         S0      
317PVDDCR_CPU1_P1   VIA   -    MD0080PA00X+046529Y+107270X0160Y         S0      
317PVDDCR_CPU1_P1   VIA   -    MD0080PA00X+046159Y+107270X0160Y         S0      
317PVDDCR_CPU1_P1   VIA   -    MD0080PA00X+046714Y+105038X0160Y         S0      
317PVDDCR_CPU1_P1   VIA   -    MD0080PA00X+046714Y+105676X0160Y         S0      
317PVDDCR_CPU1_P1   VIA   -    MD0080PA00X+046529Y+105357X0160Y         S0      
317PVDDCR_CPU1_P1   VIA   -    MD0080PA00X+046529Y+109821X0160Y         S0      
317PVDDCR_CPU1_P1   VIA   -    MD0080PA00X+046159Y+109821X0160Y         S0      
317PVDDCR_CPU1_P1   VIA   -    MD0080PA00X+046529Y+108546X0160Y         S0      
317PVDDCR_CPU1_P1   VIA   -    MD0080PA00X+046159Y+108546X0160Y         S0      
317PVDDCR_CPU1_P1   VIA   -    MD0080PA00X+046529Y+113010X0160Y         S0      
317PVDDCR_CPU1_P1   VIA   -    MD0080PA00X+046159Y+113010X0160Y         S0      
317PVDDCR_CPU1_P1   VIA   -    MD0080PA00X+046529Y+111735X0160Y         S0      
317PVDDCR_CPU1_P1   VIA   -    MD0080PA00X+046344Y+110778X0160Y         S0      
317PVDDCR_CPU1_P1   VIA   -    MD0080PA00X+046159Y+111735X0160Y         S0      
317PVDDCR_CPU1_P1   VIA   -    MD0080PA00X+045974Y+110778X0160Y         S0      
317PVDDCR_CPU1_P1   VIA   -    MD0080PA00X+045604Y+115243X0160Y         S0      
317PVDDCR_CPU1_P1   VIA   -    MD0080PA00X+045789Y+116199X0160Y         S0      
317PVDDCR_CPU1_P1   VIA   -    MD0080PA00X+046714Y+115243X0160Y         S0      
317PVDDCR_CPU1_P1   VIA   -    MD0080PA00X+046529Y+116199X0160Y         S0      
317PVDDCR_CPU1_P1   VIA   -    MD0080PA00X+046900Y+116199X0160Y         S0      
317PVDDCR_CPU1_P1   VIA   -    MD0080PA00X+046900Y+114924X0160Y         S0      
317PVDDCR_CPU1_P1   VIA   -    MD0080PA00X+046529Y+114286X0160Y         S0      
317PVDDCR_CPU1_P1   VIA   -    MD0080PA00X+045789Y+114924X0160Y         S0      
317PVDDCR_CPU1_P1   VIA   -    MD0080PA00X+046159Y+114286X0160Y         S0      
317PVDDCR_CPU1_P1   VIA   -    MD0080PA00X+048195Y+105038X0160Y         S0      
317PVDDCR_CPU1_P1   VIA   -    MD0080PA00X+048010Y+105357X0160Y         S0      
317PVDDCR_CPU1_P1   VIA   -    MD0080PA00X+048195Y+105676X0160Y         S0      
317PVDDCR_CPU1_P1   VIA   -    MD0080PA00X+048380Y+105995X0160Y         S0      
317PVDDCR_CPU1_P1   VIA   -    MD0080PA00X+047640Y+105995X0160Y         S0      
317PVDDCR_CPU1_P1   VIA   -    MD0080PA00X+047270Y+105995X0160Y         S0      
317PVDDCR_CPU1_P1   VIA   -    MD0080PA00X+047270Y+105357X0160Y         S0      
317PVDDCR_CPU1_P1   VIA   -    MD0080PA00X+047455Y+105676X0160Y         S0      
317PVDDCR_CPU1_P1   VIA   -    MD0080PA00X+048380Y+107270X0160Y         S0      
317PVDDCR_CPU1_P1   VIA   -    MD0080PA00X+047270Y+107270X0160Y         S0      
317PVDDCR_CPU1_P1   VIA   -    MD0080PA00X+047640Y+107270X0160Y         S0      
317PVDDCR_CPU1_P1   VIA   -    MD0080PA00X+048380Y+108546X0160Y         S0      
317PVDDCR_CPU1_P1   VIA   -    MD0080PA00X+047640Y+108546X0160Y         S0      
317PVDDCR_CPU1_P1   VIA   -    MD0080PA00X+047270Y+108546X0160Y         S0      
317PVDDCR_CPU1_P1   VIA   -    MD0080PA00X+048380Y+111735X0160Y         S0      
317PVDDCR_CPU1_P1   VIA   -    MD0080PA00X+047270Y+111735X0160Y         S0      
317PVDDCR_CPU1_P1   VIA   -    MD0080PA00X+047640Y+111735X0160Y         S0      
317PVDDCR_CPU1_P1   VIA   -    MD0080PA00X+047455Y+110778X0160Y         S0      
317PVDDCR_CPU1_P1   VIA   -    MD0080PA00X+047084Y+110778X0160Y         S0      
317PVDDCR_CPU1_P1   VIA   -    MD0080PA00X+048380Y+109821X0160Y         S0      
317PVDDCR_CPU1_P1   VIA   -    MD0080PA00X+047640Y+109821X0160Y         S0      
317PVDDCR_CPU1_P1   VIA   -    MD0080PA00X+047270Y+109821X0160Y         S0      
317PVDDCR_CPU1_P1   VIA   -    MD0080PA00X+048380Y+113010X0160Y         S0      
317PVDDCR_CPU1_P1   VIA   -    MD0080PA00X+047270Y+113010X0160Y         S0      
317PVDDCR_CPU1_P1   VIA   -    MD0080PA00X+047085Y+116518X0160Y         S0      
317PVDDCR_CPU1_P1   VIA   -    MD0080PA00X+047825Y+115243X0160Y         S0      
317PVDDCR_CPU1_P1   VIA   -    MD0080PA00X+047640Y+116199X0160Y         S0      
317PVDDCR_CPU1_P1   VIA   -    MD0080PA00X+048010Y+116199X0160Y         S0      
317PVDDCR_CPU1_P1   VIA   -    MD0080PA00X+048010Y+114924X0160Y         S0      
317PVDDCR_CPU1_P1   VIA   -    MD0080PA00X+048380Y+114286X0160Y         S0      
317PVDDCR_CPU1_P1   VIA   -    MD0080PA00X+047640Y+114286X0160Y         S0      
317PVDDCR_CPU1_P1   VIA   -    MD0080PA00X+047270Y+114286X0160Y         S0      
317PVDDCR_CPU1_P1   VIA   -    MD0080PA00X+049860Y+105995X0160Y         S0      
317PVDDCR_CPU1_P1   VIA   -    MD0080PA00X+049675Y+105676X0160Y         S0      
317PVDDCR_CPU1_P1   VIA   -    MD0080PA00X+048750Y+105357X0160Y         S0      
317PVDDCR_CPU1_P1   VIA   -    MD0080PA00X+048935Y+105676X0160Y         S0      
317PVDDCR_CPU1_P1   VIA   -    MD0080PA00X+048750Y+105995X0160Y         S0      
317PVDDCR_CPU1_P1   VIA   -    MD0080PA00X+049490Y+105357X0160Y         S0      
317PVDDCR_CPU1_P1   VIA   -    MD0080PA00X+049490Y+105995X0160Y         S0      
317PVDDCR_CPU1_P1   VIA   -    MD0080PA00X+049860Y+107270X0160Y         S0      
317PVDDCR_CPU1_P1   VIA   -    MD0080PA00X+048750Y+107270X0160Y         S0      
317PVDDCR_CPU1_P1   VIA   -    MD0080PA00X+049490Y+107270X0160Y         S0      
317PVDDCR_CPU1_P1   VIA   -    MD0080PA00X+049860Y+109821X0160Y         S0      
317PVDDCR_CPU1_P1   VIA   -    MD0080PA00X+048750Y+109821X0160Y         S0      
317PVDDCR_CPU1_P1   VIA   -    MD0080PA00X+049490Y+109821X0160Y         S0      
317PVDDCR_CPU1_P1   VIA   -    MD0080PA00X+049860Y+108546X0160Y         S0      
317PVDDCR_CPU1_P1   VIA   -    MD0080PA00X+048750Y+108546X0160Y         S0      
317PVDDCR_CPU1_P1   VIA   -    MD0080PA00X+049490Y+108546X0160Y         S0      
317PVDDCR_CPU1_P1   VIA   -    MD0080PA00X+049860Y+113010X0160Y         S0      
317PVDDCR_CPU1_P1   VIA   -    MD0080PA00X+049490Y+113010X0160Y         S0      
317PVDDCR_CPU1_P1   VIA   -    MD0080PA00X+048750Y+113010X0160Y         S0      
317PVDDCR_CPU1_P1   VIA   -    MD0080PA00X+049860Y+111735X0160Y         S0      
317PVDDCR_CPU1_P1   VIA   -    MD0080PA00X+048750Y+111735X0160Y         S0      
317PVDDCR_CPU1_P1   VIA   -    MD0080PA00X+049490Y+111735X0160Y         S0      
317PVDDCR_CPU1_P1   VIA   -    MD0080PA00X+049305Y+116518X0160Y         S0      
317PVDDCR_CPU1_P1   VIA   -    MD0080PA00X+048935Y+115243X0160Y         S0      
317PVDDCR_CPU1_P1   VIA   -    MD0080PA00X+049120Y+116199X0160Y         S0      
317PVDDCR_CPU1_P1   VIA   -    MD0080PA00X+048750Y+116199X0160Y         S0      
317PVDDCR_CPU1_P1   VIA   -    MD0080PA00X+049860Y+116199X0160Y         S0      
317PVDDCR_CPU1_P1   VIA   -    MD0080PA00X+049860Y+114286X0160Y         S0      
317PVDDCR_CPU1_P1   VIA   -    MD0080PA00X+049120Y+114924X0160Y         S0      
317PVDDCR_CPU1_P1   VIA   -    MD0080PA00X+048750Y+114286X0160Y         S0      
317PVDDCR_CPU1_P1   VIA   -    MD0080PA00X+049490Y+114286X0160Y         S0      
317PVDDCR_CPU1_P1   VIA   -    MD0080PA00X+050230Y+114924X0160Y         S0      
317PVDDCR_CPU1_P1   VIA   -    MD0080PA00X+050045Y+115243X0160Y         S0      
317PVDDCR_CPU1_P1   VIA   -    MD0080PA00X+050230Y+116199X0160Y         S0      
317PVDDCR_CPU1_P1   VIA   -    MD0080PA00X+050970Y+116199X0160Y         S0      
317PVDDCR_CPU1_P1   VIA   -    MD0080PA00X+051155Y+115880X0160Y         S0      
317PVDDCR_CPU1_P1   VIA   -    MD0080PA00X+051340Y+116199X0160Y         S0      
327PVDDCR_CPU1_P1   C2350 -1   M      A18X+041173Y+105677X0198Y0197     S2      
327PVDDCR_CPU1_P1   C2351 -1   M      A18X+041723Y+106027X0198Y0197     S2      
327PVDDCR_CPU1_P1   C2352 -1   M      A18X+045800Y+105327X0198Y0197     S2      
327PVDDCR_CPU1_P1   C2353 -1   M      A18X+047708Y+106027X0198Y0197R180 S2      
327PVDDCR_CPU1_P1   C2354 -1   M      A18X+042120Y+107199X0198Y0197R180 S2      
327PVDDCR_CPU1_P1   C2356 -1   M      A18X+046570Y+107199X0198Y0197R180 S2      
327PVDDCR_CPU1_P1   C2357 -1          A18X+043035Y+106849X0198Y0197     S2      
327PVDDCR_CPU1_P1   C2358 -1   M      A18X+039473Y+106027X0198Y0197     S2      
327PVDDCR_CPU1_P1   C2359 -1   M      A18X+043573Y+105327X0198Y0197     S2      
327PVDDCR_CPU1_P1   C2360 -1   M      A18X+039873Y+105327X0198Y0197     S2      
327PVDDCR_CPU1_P1   C2362 -1   M      A18X+046558Y+106027X0198Y0197R180 S2      
327PVDDCR_CPU1_P1   C2363 -1   M      A18X+048730Y+106029X0198Y0197R180 S2      
327PVDDCR_CPU1_P1   C2364 -1   M      A18X+048923Y+105677X0198Y0197     S2      
327PVDDCR_CPU1_P1   C2365 -1   M      A18X+046173Y+106027X0198Y0197     S2      
327PVDDCR_CPU1_P1   C2366 -1   M      A18X+040423Y+105677X0198Y0197     S2      
327PVDDCR_CPU1_P1   C2368 -1   M      A18X+047273Y+105314X0198Y0197     S2      
327PVDDCR_CPU1_P1   C2369 -1   M      A18X+046135Y+107199X0198Y0197     S2      
327PVDDCR_CPU1_P1   C2370 -1   M      A18X+048173Y+105677X0198Y0197     S2      
327PVDDCR_CPU1_P1   C2371 -1          A18X+045270Y+106849X0198Y0197R180 S2      
327PVDDCR_CPU1_P1   C2372 -1   M      A18X+048385Y+107199X0198Y0197     S2      
327PVDDCR_CPU1_P1   C2374 -1   M      A18X+042623Y+105677X0198Y0197     S2      
327PVDDCR_CPU1_P1   C2375 -1   M      A18X+046723Y+105677X0198Y0197     S2      
327PVDDCR_CPU1_P1   C2376 -1   M      A18X+049476Y+105985X0198Y0197R060 S2      
327PVDDCR_CPU1_P1   C2377 -1   M      A18X+044116Y+105169X0198Y0197R270 S2      
327PVDDCR_CPU1_P1   C2378 -1   M      A18X+039673Y+105677X0198Y0197     S2      
327PVDDCR_CPU1_P1   C2380 -1   M      A18X+042823Y+105327X0198Y0197     S2      
327PVDDCR_CPU1_P1   C2381 -1   M      A18X+047973Y+105314X0198Y0197     S2      
327PVDDCR_CPU1_P1   C2382 -1   M      A18X+039427Y+107206X0198Y0197R090 S2      
327PVDDCR_CPU1_P1   C2383 -1   M      A18X+041923Y+105677X0198Y0197     S2      
327PVDDCR_CPU1_P1   C2386 -1   M      A18X+048807Y+107186X0198Y0197R090 S2      
327PVDDCR_CPU1_P1   C2387 -1   M      A18X+045223Y+105677X0198Y0197     S2      
327PVDDCR_CPU1_P1   C2388 -1   M      A18X+045052Y+105327X0198Y0197     S2      
327PVDDCR_CPU1_P1   C2389 -1   M      A18X+039870Y+107199X0198Y0197R180 S2      
327PVDDCR_CPU1_P1   C2392 -1   M      A18X+046548Y+105327X0198Y0197     S2      
327PVDDCR_CPU1_P1   C2393 -1   M      A18X+040623Y+106027X0198Y0197     S2      
327PVDDCR_CPU1_P1   C2394 -1   M      A18X+041323Y+105327X0198Y0197     S2      
327PVDDCR_CPU1_P1   C2395 -1   M      A18X+041735Y+107199X0198Y0197     S2      
327PVDDCR_CPU1_P1   C2397 -1   M      A18X+040573Y+105327X0198Y0197     S2      
327PVDDCR_CPU1_P1   C2398 -1   M      A18X+047423Y+105677X0198Y0197     S2      
327PVDDCR_CPU1_P1   C2399 -1   M      A18X+049473Y+105314X0198Y0197     S2      
327PVDDCR_CPU1_P1   C2400 -1   M      A18X+045973Y+105677X0198Y0197     S2      
327PVDDCR_CPU1_P1   C2402 -1   M      A18X+042108Y+106027X0198Y0197R180 S2      
327PVDDCR_CPU1_P1   C2403 -1   M      A18X+042073Y+105327X0198Y0197     S2      
327PVDDCR_CPU1_P1   C2404 -1   M      A18X+043373Y+105677X0198Y0197     S2      
327PVDDCR_CPU1_P1   C2405 -1   M      A18X+048723Y+105314X0198Y0197     S2      
327PVDDCR_CPU1_P1   U26   -CV29       A01X+047456Y+112906X0177Y    R180 S1      
327PVDDCR_CPU1_P1   PR228 -2          A01X+043118Y+128569X0198Y0197R180 S1      
327PVDDCR_CPU1_P1   PC392 -1          A01X+042725Y+128612X0198Y0197R090 S1      
327PVDDCR_CPU1_P1   PC418_-1          A18X+025556Y+132755X0400Y0500R090 S2      
327PVDDCR_CPU1_P1   PC420_-1          A18X+024706Y+132757X0400Y0500R090 S2      
327PVDDCR_CPU1_P1   PC417_-1          A18X+023889Y+132755X0400Y0500R090 S2      
327PVDDCR_CPU1_P1   PC419_-1          A18X+022999Y+132755X0400Y0500R090 S2      
327PVDDCR_CPU1_P1   PR342 -1          A18X+043069Y+130317X0198Y0197R270 S2      
327PVDDCR_CPU1_P1   PC148_-1          A18X+042437Y+130087X0400Y0500R090 S2      
327PVDDCR_CPU1_P1   PC149_-1          A18X+039618Y+130075X0400Y0500R090 S2      
327PVDDCR_CPU1_P1   PC106 -1          A18X+041066Y+129892X0950Y1110R270 S2      
327PVDDCR_CPU1_P1   VIA   -           A18X+025208Y+129004X0260Y    R180 S2      
327PVDDCR_CPU1_P1   PC430_-1          A18X+038970Y+128321X0400Y0500R090 S2      
327PVDDCR_CPU1_P1   PC389 -1          A18X+037598Y+127960X0950Y1110R270 S2      
327PVDDCR_CPU1_P1   PC431_-1          A18X+036220Y+128141X0400Y0500R090 S2      
327PVDDCR_CPU1_P1   PC394_-1          A18X+035531Y+128133X0400Y0500R090 S2      
327PVDDCR_CPU1_P1   PC391 -1          A18X+034158Y+127962X0950Y1110R270 S2      
327PVDDCR_CPU1_P1   PC397_-1          A18X+032783Y+128121X0400Y0500R090 S2      
327PVDDCR_CPU1_P1   PC398_-1          A18X+032095Y+128119X0400Y0500R090 S2      
327PVDDCR_CPU1_P1   PC395_-1          A18X+029322Y+128088X0400Y0500R090 S2      
327PVDDCR_CPU1_P1   PC388 -1          A18X+030698Y+127971X0950Y1110R270 S2      
327PVDDCR_CPU1_P1   PC387 -1          A18X+027756Y+127971X0950Y1110R270 S2      
327PVDDCR_CPU1_P1   VIA   -           A18X+040346Y+126332X0260Y    R180 S2      
327PVDDCR_CPU1_P1   VIA   -           A18X+037058Y+124384X0260Y    R180 S2      
327PVDDCR_CPU1_P1   VIA   -           A18X+030518Y+124379X0260Y    R180 S2      
327PVDDCR_CPU1_P1   U26   -BN27       A01X+048011Y+104933X0177Y    R180 S1      
327PVDDCR_CPU1_P1   U26   -BN31       A01X+046531Y+104933X0177Y    R180 S1      
327PVDDCR_CPU1_P1   U26   -BN35       A01X+045050Y+104933X0177Y    R180 S1      
327PVDDCR_CPU1_P1   U26   -BN42       A01X+042830Y+104933X0177Y    R180 S1      
327PVDDCR_CPU1_P1   U26   -BN46       A01X+041350Y+104933X0177Y    R180 S1      
327PVDDCR_CPU1_P1   U26   -BN50       A01X+039869Y+104933X0177Y    R180 S1      
327PVDDCR_CPU1_P1   U26   -BP24       A01X+049306Y+105252X0177Y    R180 S1      
327PVDDCR_CPU1_P1   U26   -BP26       A01X+048566Y+105252X0177Y    R180 S1      
327PVDDCR_CPU1_P1   U26   -BP28       A01X+047826Y+105252X0177Y    R180 S1      
327PVDDCR_CPU1_P1   U26   -BP30       A01X+047086Y+105252X0177Y    R180 S1      
327PVDDCR_CPU1_P1   U26   -BP32       A01X+046346Y+105252X0177Y    R180 S1      
327PVDDCR_CPU1_P1   U26   -BP34       A01X+045606Y+105252X0177Y    R180 S1      
327PVDDCR_CPU1_P1   U26   -BP36       A01X+044865Y+105252X0177Y    R180 S1      
327PVDDCR_CPU1_P1   U26   -BP39       A01X+043755Y+105252X0177Y    R180 S1      
327PVDDCR_CPU1_P1   U26   -BP41       A01X+043015Y+105252X0177Y    R180 S1      
327PVDDCR_CPU1_P1   U26   -BP43       A01X+042275Y+105252X0177Y    R180 S1      
327PVDDCR_CPU1_P1   U26   -BP45       A01X+041535Y+105252X0177Y    R180 S1      
327PVDDCR_CPU1_P1   U26   -BP47       A01X+040794Y+105252X0177Y    R180 S1      
327PVDDCR_CPU1_P1   U26   -BP49       A01X+040054Y+105252X0177Y    R180 S1      
327PVDDCR_CPU1_P1   U26   -BR23       A01X+049491Y+105571X0177Y    R180 S1      
327PVDDCR_CPU1_P1   U26   -BR25       A01X+048751Y+105571X0177Y    R180 S1      
327PVDDCR_CPU1_P1   U26   -BR27       A01X+048011Y+105571X0177Y    R180 S1      
327PVDDCR_CPU1_P1   U26   -BR29       A01X+047271Y+105571X0177Y    R180 S1      
327PVDDCR_CPU1_P1   U26   -BR31       A01X+046531Y+105571X0177Y    R180 S1      
327PVDDCR_CPU1_P1   U26   -BR33       A01X+045790Y+105571X0177Y    R180 S1      
327PVDDCR_CPU1_P1   U26   -BR35       A01X+045050Y+105571X0177Y    R180 S1      
327PVDDCR_CPU1_P1   U26   -BR40       A01X+043570Y+105571X0177Y    R180 S1      
327PVDDCR_CPU1_P1   U26   -BR42       A01X+042830Y+105571X0177Y    R180 S1      
327PVDDCR_CPU1_P1   U26   -BR44       A01X+042090Y+105571X0177Y    R180 S1      
327PVDDCR_CPU1_P1   U26   -BR46       A01X+041350Y+105571X0177Y    R180 S1      
327PVDDCR_CPU1_P1   U26   -BR48       A01X+040609Y+105571X0177Y    R180 S1      
327PVDDCR_CPU1_P1   U26   -BR50       A01X+039869Y+105571X0177Y    R180 S1      
327PVDDCR_CPU1_P1   U26   -BR52       A01X+039129Y+105571X0177Y    R180 S1      
327PVDDCR_CPU1_P1   U26   -BT23       A01X+049676Y+105890X0177Y    R180 S1      
327PVDDCR_CPU1_P1   U26   -BT24       A01X+049306Y+105890X0177Y    R180 S1      
327PVDDCR_CPU1_P1   U26   -BT26       A01X+048566Y+105890X0177Y    R180 S1      
327PVDDCR_CPU1_P1   U26   -BT27       A01X+048196Y+105890X0177Y    R180 S1      
327PVDDCR_CPU1_P1   U26   -BT29       A01X+047456Y+105890X0177Y    R180 S1      
327PVDDCR_CPU1_P1   U26   -BT30       A01X+047086Y+105890X0177Y    R180 S1      
327PVDDCR_CPU1_P1   U26   -BT32       A01X+046346Y+105890X0177Y    R180 S1      
327PVDDCR_CPU1_P1   U26   -BT33       A01X+045976Y+105890X0177Y    R180 S1      
327PVDDCR_CPU1_P1   U26   -BT43       A01X+042275Y+105890X0177Y    R180 S1      
327PVDDCR_CPU1_P1   U26   -BT44       A01X+041905Y+105890X0177Y    R180 S1      
327PVDDCR_CPU1_P1   U26   -BT46       A01X+041164Y+105890X0177Y    R180 S1      
327PVDDCR_CPU1_P1   U26   -BT47       A01X+040794Y+105890X0177Y    R180 S1      
327PVDDCR_CPU1_P1   U26   -BT49       A01X+040054Y+105890X0177Y    R180 S1      
327PVDDCR_CPU1_P1   U26   -BT50       A01X+039684Y+105890X0177Y    R180 S1      
327PVDDCR_CPU1_P1   U26   -BT52       A01X+038944Y+105890X0177Y    R180 S1      
327PVDDCR_CPU1_P1   U26   -BT53       A01X+038574Y+105890X0177Y    R180 S1      
327PVDDCR_CPU1_P1   U26   -BW35       A01X+045050Y+106847X0177Y    R180 S1      
327PVDDCR_CPU1_P1   U26   -BW36       A01X+044680Y+106847X0177Y    R180 S1      
327PVDDCR_CPU1_P1   U26   -BW40       A01X+043570Y+106847X0177Y    R180 S1      
327PVDDCR_CPU1_P1   U26   -BW41       A01X+043200Y+106847X0177Y    R180 S1      
327PVDDCR_CPU1_P1   U26   -BY23       A01X+049676Y+107166X0177Y    R180 S1      
327PVDDCR_CPU1_P1   U26   -BY24       A01X+049306Y+107166X0177Y    R180 S1      
327PVDDCR_CPU1_P1   U26   -BY26       A01X+048566Y+107166X0177Y    R180 S1      
327PVDDCR_CPU1_P1   U26   -BY27       A01X+048196Y+107166X0177Y    R180 S1      
327PVDDCR_CPU1_P1   U26   -BY29       A01X+047456Y+107166X0177Y    R180 S1      
327PVDDCR_CPU1_P1   U26   -BY30       A01X+047086Y+107166X0177Y    R180 S1      
327PVDDCR_CPU1_P1   U26   -BY32       A01X+046346Y+107166X0177Y    R180 S1      
327PVDDCR_CPU1_P1   U26   -BY33       A01X+045976Y+107166X0177Y    R180 S1      
327PVDDCR_CPU1_P1   U26   -BY43       A01X+042275Y+107166X0177Y    R180 S1      
327PVDDCR_CPU1_P1   U26   -BY44       A01X+041905Y+107166X0177Y    R180 S1      
327PVDDCR_CPU1_P1   U26   -BY46       A01X+041164Y+107166X0177Y    R180 S1      
327PVDDCR_CPU1_P1   U26   -BY47       A01X+040794Y+107166X0177Y    R180 S1      
327PVDDCR_CPU1_P1   U26   -BY49       A01X+040054Y+107166X0177Y    R180 S1      
327PVDDCR_CPU1_P1   U26   -BY50       A01X+039684Y+107166X0177Y    R180 S1      
327PVDDCR_CPU1_P1   U26   -BY52       A01X+038944Y+107166X0177Y    R180 S1      
327PVDDCR_CPU1_P1   U26   -BY53       A01X+038574Y+107166X0177Y    R180 S1      
327PVDDCR_CPU1_P1   U26   -CC35       A01X+045050Y+108122X0177Y    R180 S1      
327PVDDCR_CPU1_P1   U26   -CC36       A01X+044680Y+108122X0177Y    R180 S1      
327PVDDCR_CPU1_P1   U26   -CC40       A01X+043570Y+108122X0177Y    R180 S1      
327PVDDCR_CPU1_P1   U26   -CC41       A01X+043200Y+108122X0177Y    R180 S1      
327PVDDCR_CPU1_P1   U26   -CD23       A01X+049676Y+108441X0177Y    R180 S1      
327PVDDCR_CPU1_P1   U26   -CD24       A01X+049306Y+108441X0177Y    R180 S1      
327PVDDCR_CPU1_P1   U26   -CD26       A01X+048566Y+108441X0177Y    R180 S1      
327PVDDCR_CPU1_P1   U26   -CD27       A01X+048196Y+108441X0177Y    R180 S1      
327PVDDCR_CPU1_P1   U26   -CD29       A01X+047456Y+108441X0177Y    R180 S1      
327PVDDCR_CPU1_P1   U26   -CD30       A01X+047086Y+108441X0177Y    R180 S1      
327PVDDCR_CPU1_P1   U26   -CD32       A01X+046346Y+108441X0177Y    R180 S1      
327PVDDCR_CPU1_P1   U26   -CD33       A01X+045976Y+108441X0177Y    R180 S1      
327PVDDCR_CPU1_P1   U26   -CD43       A01X+042275Y+108441X0177Y    R180 S1      
327PVDDCR_CPU1_P1   U26   -CD44       A01X+041905Y+108441X0177Y    R180 S1      
327PVDDCR_CPU1_P1   U26   -CD46       A01X+041164Y+108441X0177Y    R180 S1      
327PVDDCR_CPU1_P1   U26   -CD47       A01X+040794Y+108441X0177Y    R180 S1      
327PVDDCR_CPU1_P1   U26   -CD49       A01X+040054Y+108441X0177Y    R180 S1      
327PVDDCR_CPU1_P1   U26   -CD50       A01X+039684Y+108441X0177Y    R180 S1      
327PVDDCR_CPU1_P1   U26   -CD52       A01X+038944Y+108441X0177Y    R180 S1      
327PVDDCR_CPU1_P1   U26   -CD53       A01X+038574Y+108441X0177Y    R180 S1      
327PVDDCR_CPU1_P1   U26   -CG35       A01X+045050Y+109398X0177Y    R180 S1      
327PVDDCR_CPU1_P1   U26   -CG36       A01X+044680Y+109398X0177Y    R180 S1      
327PVDDCR_CPU1_P1   U26   -CG40       A01X+043570Y+109398X0177Y    R180 S1      
327PVDDCR_CPU1_P1   U26   -CG41       A01X+043200Y+109398X0177Y    R180 S1      
327PVDDCR_CPU1_P1   U26   -CH23       A01X+049676Y+109717X0177Y    R180 S1      
327PVDDCR_CPU1_P1   U26   -CH24       A01X+049306Y+109717X0177Y    R180 S1      
327PVDDCR_CPU1_P1   U26   -CH26       A01X+048566Y+109717X0177Y    R180 S1      
327PVDDCR_CPU1_P1   U26   -CH27       A01X+048196Y+109717X0177Y    R180 S1      
327PVDDCR_CPU1_P1   U26   -CH29       A01X+047456Y+109717X0177Y    R180 S1      
327PVDDCR_CPU1_P1   U26   -CH30       A01X+047086Y+109717X0177Y    R180 S1      
327PVDDCR_CPU1_P1   U26   -CH32       A01X+046346Y+109717X0177Y    R180 S1      
327PVDDCR_CPU1_P1   U26   -CH33       A01X+045976Y+109717X0177Y    R180 S1      
327PVDDCR_CPU1_P1   U26   -CH43       A01X+042275Y+109717X0177Y    R180 S1      
327PVDDCR_CPU1_P1   U26   -CH44       A01X+041905Y+109717X0177Y    R180 S1      
327PVDDCR_CPU1_P1   U26   -CH46       A01X+041164Y+109717X0177Y    R180 S1      
327PVDDCR_CPU1_P1   U26   -CH47       A01X+040794Y+109717X0177Y    R180 S1      
327PVDDCR_CPU1_P1   U26   -CH49       A01X+040054Y+109717X0177Y    R180 S1      
327PVDDCR_CPU1_P1   U26   -CH50       A01X+039684Y+109717X0177Y    R180 S1      
327PVDDCR_CPU1_P1   U26   -CH52       A01X+038944Y+109717X0177Y    R180 S1      
327PVDDCR_CPU1_P1   U26   -CH53       A01X+038574Y+109717X0177Y    R180 S1      
327PVDDCR_CPU1_P1   U26   -CK35       A01X+045235Y+110354X0177Y    R180 S1      
327PVDDCR_CPU1_P1   U26   -CK36       A01X+044865Y+110354X0177Y    R180 S1      
327PVDDCR_CPU1_P1   U26   -CK40       A01X+043385Y+110354X0177Y    R180 S1      
327PVDDCR_CPU1_P1   U26   -CK41       A01X+043015Y+110354X0177Y    R180 S1      
327PVDDCR_CPU1_P1   U26   -CL29       A01X+047271Y+110673X0177Y    R180 S1      
327PVDDCR_CPU1_P1   U26   -CL30       A01X+046901Y+110673X0177Y    R180 S1      
327PVDDCR_CPU1_P1   U26   -CL32       A01X+046161Y+110673X0177Y    R180 S1      
327PVDDCR_CPU1_P1   U26   -CL33       A01X+045790Y+110673X0177Y    R180 S1      
327PVDDCR_CPU1_P1   U26   -CL43       A01X+042460Y+110673X0177Y    R180 S1      
327PVDDCR_CPU1_P1   U26   -CL44       A01X+042090Y+110673X0177Y    R180 S1      
327PVDDCR_CPU1_P1   U26   -CL46       A01X+041350Y+110673X0177Y    R180 S1      
327PVDDCR_CPU1_P1   U26   -CL47       A01X+040980Y+110673X0177Y    R180 S1      
327PVDDCR_CPU1_P1   U26   -CN35       A01X+045050Y+111311X0177Y    R180 S1      
327PVDDCR_CPU1_P1   U26   -CN36       A01X+044680Y+111311X0177Y    R180 S1      
327PVDDCR_CPU1_P1   U26   -CN40       A01X+043570Y+111311X0177Y    R180 S1      
327PVDDCR_CPU1_P1   U26   -CN41       A01X+043200Y+111311X0177Y    R180 S1      
327PVDDCR_CPU1_P1   U26   -CP23       A01X+049676Y+111630X0177Y    R180 S1      
327PVDDCR_CPU1_P1   U26   -CP24       A01X+049306Y+111630X0177Y    R180 S1      
327PVDDCR_CPU1_P1   U26   -CP26       A01X+048566Y+111630X0177Y    R180 S1      
327PVDDCR_CPU1_P1   U26   -CP27       A01X+048196Y+111630X0177Y    R180 S1      
327PVDDCR_CPU1_P1   U26   -CP29       A01X+047456Y+111630X0177Y    R180 S1      
327PVDDCR_CPU1_P1   U26   -CP30       A01X+047086Y+111630X0177Y    R180 S1      
327PVDDCR_CPU1_P1   U26   -CP32       A01X+046346Y+111630X0177Y    R180 S1      
327PVDDCR_CPU1_P1   U26   -CP33       A01X+045976Y+111630X0177Y    R180 S1      
327PVDDCR_CPU1_P1   U26   -CP43       A01X+042275Y+111630X0177Y    R180 S1      
327PVDDCR_CPU1_P1   U26   -CP44       A01X+041905Y+111630X0177Y    R180 S1      
327PVDDCR_CPU1_P1   U26   -CP46       A01X+041164Y+111630X0177Y    R180 S1      
327PVDDCR_CPU1_P1   U26   -CP47       A01X+040794Y+111630X0177Y    R180 S1      
327PVDDCR_CPU1_P1   U26   -CP49       A01X+040054Y+111630X0177Y    R180 S1      
327PVDDCR_CPU1_P1   U26   -CP50       A01X+039684Y+111630X0177Y    R180 S1      
327PVDDCR_CPU1_P1   U26   -CP52       A01X+038944Y+111630X0177Y    R180 S1      
327PVDDCR_CPU1_P1   U26   -CP53       A01X+038574Y+111630X0177Y    R180 S1      
327PVDDCR_CPU1_P1   U26   -CU35       A01X+045050Y+112587X0177Y    R180 S1      
327PVDDCR_CPU1_P1   U26   -CU36       A01X+044680Y+112587X0177Y    R180 S1      
327PVDDCR_CPU1_P1   U26   -CU40       A01X+043570Y+112587X0177Y    R180 S1      
327PVDDCR_CPU1_P1   U26   -CU41       A01X+043200Y+112587X0177Y    R180 S1      
327PVDDCR_CPU1_P1   U26   -CV23       A01X+049676Y+112906X0177Y    R180 S1      
327PVDDCR_CPU1_P1   U26   -CV24       A01X+049306Y+112906X0177Y    R180 S1      
327PVDDCR_CPU1_P1   U26   -CV26       A01X+048566Y+112906X0177Y    R180 S1      
327PVDDCR_CPU1_P1   U26   -CV27       A01X+048196Y+112906X0177Y    R180 S1      
327PVDDCR_CPU1_P1   U26   -CV30       A01X+047086Y+112906X0177Y    R180 S1      
327PVDDCR_CPU1_P1   U26   -CV32       A01X+046346Y+112906X0177Y    R180 S1      
327PVDDCR_CPU1_P1   U26   -CV33       A01X+045976Y+112906X0177Y    R180 S1      
327PVDDCR_CPU1_P1   U26   -CV43       A01X+042275Y+112906X0177Y    R180 S1      
327PVDDCR_CPU1_P1   U26   -CV44       A01X+041905Y+112906X0177Y    R180 S1      
327PVDDCR_CPU1_P1   U26   -CV46       A01X+041164Y+112906X0177Y    R180 S1      
327PVDDCR_CPU1_P1   U26   -CV47       A01X+040794Y+112906X0177Y    R180 S1      
327PVDDCR_CPU1_P1   U26   -CV49       A01X+040054Y+112906X0177Y    R180 S1      
327PVDDCR_CPU1_P1   U26   -CV50       A01X+039684Y+112906X0177Y    R180 S1      
327PVDDCR_CPU1_P1   U26   -CV52       A01X+038944Y+112906X0177Y    R180 S1      
327PVDDCR_CPU1_P1   U26   -CV53       A01X+038574Y+112906X0177Y    R180 S1      
327PVDDCR_CPU1_P1   U26   -DA35       A01X+045050Y+113862X0177Y    R180 S1      
327PVDDCR_CPU1_P1   U26   -DA36       A01X+044680Y+113862X0177Y    R180 S1      
327PVDDCR_CPU1_P1   U26   -DA40       A01X+043570Y+113862X0177Y    R180 S1      
327PVDDCR_CPU1_P1   U26   -DA41       A01X+043200Y+113862X0177Y    R180 S1      
327PVDDCR_CPU1_P1   U26   -DB23       A01X+049676Y+114181X0177Y    R180 S1      
327PVDDCR_CPU1_P1   U26   -DB24       A01X+049306Y+114181X0177Y    R180 S1      
327PVDDCR_CPU1_P1   U26   -DB26       A01X+048566Y+114181X0177Y    R180 S1      
327PVDDCR_CPU1_P1   U26   -DB27       A01X+048196Y+114181X0177Y    R180 S1      
327PVDDCR_CPU1_P1   U26   -DB29       A01X+047456Y+114181X0177Y    R180 S1      
327PVDDCR_CPU1_P1   U26   -DB30       A01X+047086Y+114181X0177Y    R180 S1      
327PVDDCR_CPU1_P1   U26   -DB32       A01X+046346Y+114181X0177Y    R180 S1      
327PVDDCR_CPU1_P1   U26   -DB33       A01X+045976Y+114181X0177Y    R180 S1      
327PVDDCR_CPU1_P1   U26   -DB43       A01X+042275Y+114181X0177Y    R180 S1      
327PVDDCR_CPU1_P1   U26   -DB44       A01X+041905Y+114181X0177Y    R180 S1      
327PVDDCR_CPU1_P1   U26   -DB46       A01X+041164Y+114181X0177Y    R180 S1      
327PVDDCR_CPU1_P1   U26   -DB47       A01X+040794Y+114181X0177Y    R180 S1      
327PVDDCR_CPU1_P1   U26   -DB49       A01X+040054Y+114181X0177Y    R180 S1      
327PVDDCR_CPU1_P1   U26   -DB50       A01X+039684Y+114181X0177Y    R180 S1      
327PVDDCR_CPU1_P1   U26   -DB52       A01X+038944Y+114181X0177Y    R180 S1      
327PVDDCR_CPU1_P1   U26   -DB53       A01X+038574Y+114181X0177Y    R180 S1      
327PVDDCR_CPU1_P1   U26   -DC35       A01X+045050Y+114500X0177Y    R180 S1      
327PVDDCR_CPU1_P1   U26   -DC36       A01X+044680Y+114500X0177Y    R180 S1      
327PVDDCR_CPU1_P1   U26   -DC40       A01X+043570Y+114500X0177Y    R180 S1      
327PVDDCR_CPU1_P1   U26   -DC41       A01X+043200Y+114500X0177Y    R180 S1      
327PVDDCR_CPU1_P1   U26   -DD22       A01X+050046Y+114819X0177Y    R180 S1      
327PVDDCR_CPU1_P1   U26   -DD25       A01X+048936Y+114819X0177Y    R180 S1      
327PVDDCR_CPU1_P1   U26   -DD28       A01X+047826Y+114819X0177Y    R180 S1      
327PVDDCR_CPU1_P1   U26   -DD31       A01X+046716Y+114819X0177Y    R180 S1      
327PVDDCR_CPU1_P1   U26   -DD34       A01X+045606Y+114819X0177Y    R180 S1      
327PVDDCR_CPU1_P1   U26   -DD42       A01X+042645Y+114819X0177Y    R180 S1      
327PVDDCR_CPU1_P1   U26   -DD45       A01X+041535Y+114819X0177Y    R180 S1      
327PVDDCR_CPU1_P1   U26   -DD48       A01X+040424Y+114819X0177Y    R180 S1      
327PVDDCR_CPU1_P1   U26   -DD51       A01X+039314Y+114819X0177Y    R180 S1      
327PVDDCR_CPU1_P1   U26   -DD54       A01X+038204Y+114819X0177Y    R180 S1      
327PVDDCR_CPU1_P1   U26   -DE22       A01X+049861Y+115138X0177Y    R180 S1      
327PVDDCR_CPU1_P1   U26   -DE25       A01X+048751Y+115138X0177Y    R180 S1      
327PVDDCR_CPU1_P1   U26   -DE28       A01X+047641Y+115138X0177Y    R180 S1      
327PVDDCR_CPU1_P1   U26   -DE31       A01X+046531Y+115138X0177Y    R180 S1      
327PVDDCR_CPU1_P1   U26   -DE34       A01X+045420Y+115138X0177Y    R180 S1      
327PVDDCR_CPU1_P1   U26   -DE35       A01X+045050Y+115138X0177Y    R180 S1      
327PVDDCR_CPU1_P1   U26   -DE41       A01X+043200Y+115138X0177Y    R180 S1      
327PVDDCR_CPU1_P1   U26   -DE42       A01X+042830Y+115138X0177Y    R180 S1      
327PVDDCR_CPU1_P1   U26   -DE45       A01X+041720Y+115138X0177Y    R180 S1      
327PVDDCR_CPU1_P1   U26   -DE48       A01X+040609Y+115138X0177Y    R180 S1      
327PVDDCR_CPU1_P1   U26   -DE51       A01X+039499Y+115138X0177Y    R180 S1      
327PVDDCR_CPU1_P1   U26   -DE54       A01X+038389Y+115138X0177Y    R180 S1      
327PVDDCR_CPU1_P1   U26   -DG19       A01X+050972Y+115776X0177Y    R180 S1      
327PVDDCR_CPU1_P1   U26   -DG57       A01X+037279Y+115776X0177Y    R180 S1      
327PVDDCR_CPU1_P1   U26   -DH19       A01X+051157Y+116095X0177Y    R180 S1      
327PVDDCR_CPU1_P1   U26   -DH20       A01X+050787Y+116095X0177Y    R180 S1      
327PVDDCR_CPU1_P1   U26   -DH22       A01X+050046Y+116095X0177Y    R180 S1      
327PVDDCR_CPU1_P1   U26   -DH23       A01X+049676Y+116095X0177Y    R180 S1      
327PVDDCR_CPU1_P1   U26   -DH25       A01X+048936Y+116095X0177Y    R180 S1      
327PVDDCR_CPU1_P1   U26   -DH26       A01X+048566Y+116095X0177Y    R180 S1      
327PVDDCR_CPU1_P1   U26   -DH28       A01X+047826Y+116095X0177Y    R180 S1      
327PVDDCR_CPU1_P1   U26   -DH29       A01X+047456Y+116095X0177Y    R180 S1      
327PVDDCR_CPU1_P1   U26   -DH31       A01X+046716Y+116095X0177Y    R180 S1      
327PVDDCR_CPU1_P1   U26   -DH32       A01X+046346Y+116095X0177Y    R180 S1      
327PVDDCR_CPU1_P1   U26   -DH34       A01X+045606Y+116095X0177Y    R180 S1      
327PVDDCR_CPU1_P1   U26   -DH35       A01X+045235Y+116095X0177Y    R180 S1      
327PVDDCR_CPU1_P1   U26   -DH41       A01X+043015Y+116095X0177Y    R180 S1      
327PVDDCR_CPU1_P1   U26   -DH42       A01X+042645Y+116095X0177Y    R180 S1      
327PVDDCR_CPU1_P1   U26   -DH44       A01X+041905Y+116095X0177Y    R180 S1      
327PVDDCR_CPU1_P1   U26   -DH45       A01X+041535Y+116095X0177Y    R180 S1      
327PVDDCR_CPU1_P1   U26   -DH47       A01X+040794Y+116095X0177Y    R180 S1      
327PVDDCR_CPU1_P1   U26   -DH48       A01X+040424Y+116095X0177Y    R180 S1      
327PVDDCR_CPU1_P1   U26   -DH50       A01X+039684Y+116095X0177Y    R180 S1      
327PVDDCR_CPU1_P1   U26   -DH51       A01X+039314Y+116095X0177Y    R180 S1      
327PVDDCR_CPU1_P1   U26   -DH53       A01X+038574Y+116095X0177Y    R180 S1      
327PVDDCR_CPU1_P1   U26   -DH54       A01X+038204Y+116095X0177Y    R180 S1      
327PVDDCR_CPU1_P1   U26   -DH56       A01X+037464Y+116095X0177Y    R180 S1      
327PVDDCR_CPU1_P1   U26   -DH57       A01X+037094Y+116095X0177Y    R180 S1      
317PVDDCR_CPU1_P1   VIA   -    MD0100PA00X+041925Y+126866X0200Y         S0      
317PVDDCR_CPU1_P1   VIA   -    MD0100PA00X+041675Y+126866X0200Y         S0      
317PVDDCR_CPU1_P1   VIA   -    MD0100PA00X+041925Y+127116X0200Y         S0      
317PVDDCR_CPU1_P1   VIA   -    MD0100PA00X+032096Y+124663X0200Y         S0      
317PVDDCR_CPU1_P1   VIA   -    MD0100PA00X+033796Y+124663X0200Y         S0      
317PVDDCR_CPU1_P1   VIA   -    MD0100PA00X+037046Y+124669X0200Y         S0      
317PVDDCR_CPU1_P1   VIA   -    MD0100PA00X+038636Y+124669X0200Y         S0      
317PVDDCR_CPU1_P1   VIA   -    MD0100PA00X+024876Y+131788X0200Y         S0      
317PVDDCR_CPU1_P1   VIA   -    MD0100PA00X+025126Y+131788X0200Y         S0      
317PVDDCR_CPU1_P1   VIA   -    MD0100PA00X+023296Y+131538X0200Y         S0      
317PVDDCR_CPU1_P1   VIA   -    MD0100PA00X+025126Y+130038X0200Y         S0      
317PVDDCR_CPU1_P1   VIA   -    MD0100PA00X+025126Y+130288X0200Y         S0      
317PVDDCR_CPU1_P1   VIA   -    MD0100PA00X+024876Y+130288X0200Y         S0      
317PVDDCR_CPU1_P1   VIA   -    MD0100PA00X+024876Y+130038X0200Y         S0      
317PVDDCR_CPU1_P1   VIA   -    MD0100PA00X+025126Y+130538X0200Y         S0      
317PVDDCR_CPU1_P1   VIA   -    MD0100PA00X+024876Y+130538X0200Y         S0      
317PVDDCR_CPU1_P1   VIA   -    MD0100PA00X+023546Y+131538X0200Y         S0      
317PVDDCR_CPU1_P1   VIA   -    MD0100PA00X+023796Y+131538X0200Y         S0      
317PVDDCR_CPU1_P1   VIA   -    MD0100PA00X+023546Y+130788X0200Y         S0      
317PVDDCR_CPU1_P1   VIA   -    MD0100PA00X+023546Y+131038X0200Y         S0      
317PVDDCR_CPU1_P1   VIA   -    MD0100PA00X+023546Y+131288X0200Y         S0      
317PVDDCR_CPU1_P1   VIA   -    MD0100PA00X+023796Y+131288X0200Y         S0      
317PVDDCR_CPU1_P1   VIA   -    MD0100PA00X+023796Y+131038X0200Y         S0      
317PVDDCR_CPU1_P1   VIA   -    MD0100PA00X+023796Y+130788X0200Y         S0      
317PVDDCR_CPU1_P1   VIA   -    MD0100PA00X+025126Y+131538X0200Y         S0      
317PVDDCR_CPU1_P1   VIA   -    MD0100PA00X+024876Y+131538X0200Y         S0      
317PVDDCR_CPU1_P1   VIA   -    MD0100PA00X+025126Y+130788X0200Y         S0      
317PVDDCR_CPU1_P1   VIA   -    MD0100PA00X+025126Y+131038X0200Y         S0      
317PVDDCR_CPU1_P1   VIA   -    MD0100PA00X+025126Y+131288X0200Y         S0      
317PVDDCR_CPU1_P1   VIA   -    MD0100PA00X+024876Y+131288X0200Y         S0      
317PVDDCR_CPU1_P1   VIA   -    MD0100PA00X+024876Y+131038X0200Y         S0      
317PVDDCR_CPU1_P1   VIA   -    MD0100PA00X+024876Y+130788X0200Y         S0      
327PVDDCR_CPU1_P1   PL43  -4   M      A01X+024336Y+131163X0950Y1780R270 S1      
317PVDDCR_CPU1_P1   VIA   -    MD0100PA00X+023296Y+131288X0200Y         S0      
317PVDDCR_CPU1_P1   VIA   -    MD0100PA00X+023296Y+131038X0200Y         S0      
317PVDDCR_CPU1_P1   VIA   -    MD0100PA00X+023296Y+130788X0200Y         S0      
317PVDDCR_CPU1_P1   VIA   -    MD0100PA00X+023296Y+130538X0200Y         S0      
317PVDDCR_CPU1_P1   VIA   -    MD0100PA00X+023296Y+130038X0200Y         S0      
317PVDDCR_CPU1_P1   VIA   -    MD0100PA00X+023296Y+130288X0200Y         S0      
317PVDDCR_CPU1_P1   VIA   -    MD0100PA00X+023796Y+130538X0200Y         S0      
317PVDDCR_CPU1_P1   VIA   -    MD0100PA00X+023546Y+130538X0200Y         S0      
317PVDDCR_CPU1_P1   VIA   -    MD0100PA00X+023796Y+130038X0200Y         S0      
317PVDDCR_CPU1_P1   VIA   -    MD0100PA00X+023796Y+130288X0200Y         S0      
317PVDDCR_CPU1_P1   VIA   -    MD0100PA00X+023546Y+130288X0200Y         S0      
317PVDDCR_CPU1_P1   VIA   -    MD0100PA00X+023546Y+130038X0200Y         S0      
317PVDDCR_CPU1_P1   VIA   -    MD0100PA00X+041936Y+128622X0200Y         S0      
317PVDDCR_CPU1_P1   VIA   -    MD0100PA00X+041686Y+129122X0200Y         S0      
317PVDDCR_CPU1_P1   VIA   -    MD0100PA00X+041436Y+129122X0200Y         S0      
317PVDDCR_CPU1_P1   VIA   -    MD0100PA00X+041936Y+129122X0200Y         S0      
317PVDDCR_CPU1_P1   VIA   -    MD0100PA00X+041936Y+128872X0200Y         S0      
317PVDDCR_CPU1_P1   VIA   -    MD0100PA00X+040096Y+129132X0200Y         S0      
317PVDDCR_CPU1_P1   VIA   -    MD0100PA00X+040346Y+129132X0200Y         S0      
317PVDDCR_CPU1_P1   VIA   -    MD0100PA00X+039538Y+135323X0200Y         S0      
317PVDDCR_CPU1_P1   VIA   -    MD0100PA00X+039846Y+129132X0200Y         S0      
327PVDDCR_CPU1_P1   PR429 -2          A18X+039397Y+135041X0198Y0197R270 S2      
317PVDDCR_CPU1_P1   VIA   -    MD0100PA00X+039845Y+128876X0200Y         S0      
317PVDDCR_CPU1_P1   VIA   -    MD0100PA00X+039845Y+128626X0200Y         S0      
317PVDDCR_CPU1_P1   VIA   -    MD0100PA00X+025126Y+129288X0200Y         S0      
317PVDDCR_CPU1_P1   VIA   -    MD0100PA00X+025126Y+129538X0200Y         S0      
317PVDDCR_CPU1_P1   VIA   -    MD0100PA00X+024876Y+129538X0200Y         S0      
317PVDDCR_CPU1_P1   VIA   -    MD0100PA00X+024876Y+129288X0200Y         S0      
317PVDDCR_CPU1_P1   VIA   -    MD0100PA00X+025126Y+129788X0200Y         S0      
317PVDDCR_CPU1_P1   VIA   -    MD0100PA00X+024876Y+129788X0200Y         S0      
317PVDDCR_CPU1_P1   VIA   -    MD0100PA00X+023546Y+129788X0200Y         S0      
317PVDDCR_CPU1_P1   VIA   -    MD0100PA00X+023796Y+129788X0200Y         S0      
317PVDDCR_CPU1_P1   VIA   -    MD0100PA00X+023296Y+129788X0200Y         S0      
317PVDDCR_CPU1_P1   VIA   -    MD0100PA00X+041936Y+128122X0200Y         S0      
317PVDDCR_CPU1_P1   VIA   -    MD0100PA00X+041936Y+128372X0200Y         S0      
317PVDDCR_CPU1_P1   VIA   -    MD0100PA00X+041425Y+127366X0200Y         S0      
317PVDDCR_CPU1_P1   VIA   -    MD0100PA00X+041425Y+127616X0200Y         S0      
317PVDDCR_CPU1_P1   VIA   -    MD0100PA00X+041425Y+127866X0200Y         S0      
317PVDDCR_CPU1_P1   VIA   -    MD0100PA00X+041675Y+127366X0200Y         S0      
317PVDDCR_CPU1_P1   VIA   -    MD0100PA00X+041925Y+127366X0200Y         S0      
317PVDDCR_CPU1_P1   VIA   -    MD0100PA00X+041925Y+127616X0200Y         S0      
317PVDDCR_CPU1_P1   VIA   -    MD0100PA00X+041925Y+127866X0200Y         S0      
317PVDDCR_CPU1_P1   VIA   -    MD0100PA00X+041675Y+127616X0200Y         S0      
317PVDDCR_CPU1_P1   VIA   -    MD0100PA00X+041675Y+127866X0200Y         S0      
317PVDDCR_CPU1_P1   VIA   -    MD0100PA00X+041425Y+127116X0200Y         S0      
317PVDDCR_CPU1_P1   VIA   -    MD0100PA00X+041675Y+127116X0200Y         S0      
317PVDDCR_CPU1_P1   VIA   -    MD0100PA00X+040345Y+128618X0200Y         S0      
317PVDDCR_CPU1_P1   VIA   -    MD0100PA00X+040095Y+128618X0200Y         S0      
317PVDDCR_CPU1_P1   VIA   -    MD0100PA00X+040345Y+128868X0200Y         S0      
317PVDDCR_CPU1_P1   VIA   -    MD0100PA00X+040095Y+128868X0200Y         S0      
317PVDDCR_CPU1_P1   VIA   -    MD0100PA00X+040345Y+128118X0200Y         S0      
317PVDDCR_CPU1_P1   VIA   -    MD0100PA00X+040345Y+128368X0200Y         S0      
317PVDDCR_CPU1_P1   VIA   -    MD0100PA00X+040095Y+128368X0200Y         S0      
317PVDDCR_CPU1_P1   VIA   -    MD0100PA00X+040095Y+128118X0200Y         S0      
317PVDDCR_CPU1_P1   VIA   -    MD0100PA00X+041675Y+128618X0200Y         S0      
317PVDDCR_CPU1_P1   VIA   -    MD0100PA00X+041425Y+128618X0200Y         S0      
317PVDDCR_CPU1_P1   VIA   -    MD0100PA00X+041675Y+128868X0200Y         S0      
317PVDDCR_CPU1_P1   VIA   -    MD0100PA00X+041425Y+128868X0200Y         S0      
317PVDDCR_CPU1_P1   VIA   -    MD0100PA00X+041675Y+128118X0200Y         S0      
317PVDDCR_CPU1_P1   VIA   -    MD0100PA00X+041675Y+128368X0200Y         S0      
317PVDDCR_CPU1_P1   VIA   -    MD0100PA00X+041425Y+128368X0200Y         S0      
317PVDDCR_CPU1_P1   VIA   -    MD0100PA00X+041425Y+128118X0200Y         S0      
327PVDDCR_CPU1_P1   PL69  -4   M      A01X+040885Y+128493X0950Y1780R270 S1      
317PVDDCR_CPU1_P1   VIA   -    MD0100PA00X+039845Y+128376X0200Y         S0      
317PVDDCR_CPU1_P1   VIA   -    MD0100PA00X+039845Y+128126X0200Y         S0      
317PVDDCR_CPU1_P1   VIA   -    MD0100PA00X+039835Y+127616X0200Y         S0      
317PVDDCR_CPU1_P1   VIA   -    MD0100PA00X+039835Y+127866X0200Y         S0      
317PVDDCR_CPU1_P1   VIA   -    MD0100PA00X+040085Y+127616X0200Y         S0      
317PVDDCR_CPU1_P1   VIA   -    MD0100PA00X+040085Y+127866X0200Y         S0      
317PVDDCR_CPU1_P1   VIA   -    MD0100PA00X+040335Y+127866X0200Y         S0      
317PVDDCR_CPU1_P1   VIA   -    MD0100PA00X+040335Y+127616X0200Y         S0      
317PVDDCR_CPU1_P1   VIA   -    MD0100PA00X+039835Y+127366X0200Y         S0      
317PVDDCR_CPU1_P1   VIA   -    MD0100PA00X+040085Y+127366X0200Y         S0      
317PVDDCR_CPU1_P1   VIA   -    MD0100PA00X+039835Y+127116X0200Y         S0      
317PVDDCR_CPU1_P1   VIA   -    MD0100PA00X+040085Y+127116X0200Y         S0      
317PVDDCR_CPU1_P1   VIA   -    MD0100PA00X+040335Y+127366X0200Y         S0      
317PVDDCR_CPU1_P1   VIA   -    MD0100PA00X+040335Y+127116X0200Y         S0      
317PVDDCR_CPU1_P1   VIA   -    MD0100PA00X+038386Y+127179X0200Y         S0      
317PVDDCR_CPU1_P1   VIA   -    MD0100PA00X+038636Y+127179X0200Y         S0      
317PVDDCR_CPU1_P1   VIA   -    MD0100PA00X+038136Y+127179X0200Y         S0      
317PVDDCR_CPU1_P1   VIA   -    MD0100PA00X+036806Y+127179X0200Y         S0      
317PVDDCR_CPU1_P1   VIA   -    MD0100PA00X+037056Y+127179X0200Y         S0      
317PVDDCR_CPU1_P1   VIA   -    MD0100PA00X+035386Y+127169X0200Y         S0      
317PVDDCR_CPU1_P1   VIA   -    MD0100PA00X+035136Y+127169X0200Y         S0      
317PVDDCR_CPU1_P1   VIA   -    MD0100PA00X+036556Y+127179X0200Y         S0      
317PVDDCR_CPU1_P1   VIA   -    MD0100PA00X+036279Y+133390X0200Y         S0      
327PVDDCR_CPU1_P1   PR273 -2          A18X+036139Y+133108X0198Y0197R270 S2      
317PVDDCR_CPU1_P1   VIA   -    MD0100PA00X+034886Y+127169X0200Y         S0      
317PVDDCR_CPU1_P1   VIA   -    MD0100PA00X+033796Y+127169X0200Y         S0      
317PVDDCR_CPU1_P1   VIA   -    MD0100PA00X+033546Y+127169X0200Y         S0      
317PVDDCR_CPU1_P1   VIA   -    MD0100PA00X+033296Y+127169X0200Y         S0      
317PVDDCR_CPU1_P1   VIA   -    MD0100PA00X+032999Y+133370X0200Y         S0      
327PVDDCR_CPU1_P1   PR261 -2          A18X+032859Y+133088X0198Y0197R270 S2      
317PVDDCR_CPU1_P1   VIA   -    MD0100PA00X+031838Y+127169X0200Y         S0      
317PVDDCR_CPU1_P1   VIA   -    MD0100PA00X+031588Y+127169X0200Y         S0      
317PVDDCR_CPU1_P1   VIA   -    MD0100PA00X+032088Y+127169X0200Y         S0      
317PVDDCR_CPU1_P1   VIA   -    MD0100PA00X+030008Y+127169X0200Y         S0      
317PVDDCR_CPU1_P1   VIA   -    MD0100PA00X+029709Y+133376X0200Y         S0      
327PVDDCR_CPU1_P1   PR260 -2          A18X+029568Y+133094X0198Y0197R270 S2      
317PVDDCR_CPU1_P1   VIA   -    MD0100PA00X+030258Y+127169X0200Y         S0      
317PVDDCR_CPU1_P1   VIA   -    MD0100PA00X+030508Y+127169X0200Y         S0      
317PVDDCR_CPU1_P1   VIA   -    MD0100PA00X+028798Y+127177X0200Y         S0      
317PVDDCR_CPU1_P1   VIA   -    MD0100PA00X+028298Y+127177X0200Y         S0      
317PVDDCR_CPU1_P1   VIA   -    MD0100PA00X+028548Y+127177X0200Y         S0      
317PVDDCR_CPU1_P1   VIA   -    MD0100PA00X+027218Y+127177X0200Y         S0      
317PVDDCR_CPU1_P1   VIA   -    MD0100PA00X+026968Y+127177X0200Y         S0      
317PVDDCR_CPU1_P1   VIA   -    MD0100PA00X+026419Y+133379X0200Y         S0      
327PVDDCR_CPU1_P1   PR269 -2          A18X+026279Y+133097X0198Y0197R270 S2      
317PVDDCR_CPU1_P1   VIA   -    MD0100PA00X+026718Y+127177X0200Y         S0      
317PVDDCR_CPU1_P1   VIA   -    MD0100PA00X+041425Y+126866X0200Y         S0      
317PVDDCR_CPU1_P1   VIA   -    MD0100PA00X+039835Y+126866X0200Y         S0      
317PVDDCR_CPU1_P1   VIA   -    MD0100PA00X+040085Y+126866X0200Y         S0      
317PVDDCR_CPU1_P1   VIA   -    MD0100PA00X+039835Y+126616X0200Y         S0      
317PVDDCR_CPU1_P1   VIA   -    MD0100PA00X+040085Y+126616X0200Y         S0      
317PVDDCR_CPU1_P1   VIA   -    MD0100PA00X+040335Y+126866X0200Y         S0      
317PVDDCR_CPU1_P1   VIA   -    MD0100PA00X+040335Y+126616X0200Y         S0      
317PVDDCR_CPU1_P1   VIA   -    MD0100PA00X+038636Y+126429X0200Y         S0      
317PVDDCR_CPU1_P1   VIA   -    MD0100PA00X+038636Y+126679X0200Y         S0      
317PVDDCR_CPU1_P1   VIA   -    MD0100PA00X+038636Y+126179X0200Y         S0      
317PVDDCR_CPU1_P1   VIA   -    MD0100PA00X+038636Y+126929X0200Y         S0      
317PVDDCR_CPU1_P1   VIA   -    MD0100PA00X+038386Y+125919X0200Y         S0      
317PVDDCR_CPU1_P1   VIA   -    MD0100PA00X+038386Y+125669X0200Y         S0      
317PVDDCR_CPU1_P1   VIA   -    MD0100PA00X+038636Y+125919X0200Y         S0      
317PVDDCR_CPU1_P1   VIA   -    MD0100PA00X+038636Y+125669X0200Y         S0      
317PVDDCR_CPU1_P1   VIA   -    MD0100PA00X+038136Y+125919X0200Y         S0      
317PVDDCR_CPU1_P1   VIA   -    MD0100PA00X+038136Y+125669X0200Y         S0      
317PVDDCR_CPU1_P1   VIA   -    MD0100PA00X+037056Y+126171X0200Y         S0      
317PVDDCR_CPU1_P1   VIA   -    MD0100PA00X+037056Y+126421X0200Y         S0      
317PVDDCR_CPU1_P1   VIA   -    MD0100PA00X+037056Y+126671X0200Y         S0      
317PVDDCR_CPU1_P1   VIA   -    MD0100PA00X+036806Y+126671X0200Y         S0      
317PVDDCR_CPU1_P1   VIA   -    MD0100PA00X+036806Y+126421X0200Y         S0      
317PVDDCR_CPU1_P1   VIA   -    MD0100PA00X+036806Y+126171X0200Y         S0      
317PVDDCR_CPU1_P1   VIA   -    MD0100PA00X+037056Y+126921X0200Y         S0      
317PVDDCR_CPU1_P1   VIA   -    MD0100PA00X+036806Y+126921X0200Y         S0      
317PVDDCR_CPU1_P1   VIA   -    MD0100PA00X+038386Y+126171X0200Y         S0      
317PVDDCR_CPU1_P1   VIA   -    MD0100PA00X+038386Y+126421X0200Y         S0      
317PVDDCR_CPU1_P1   VIA   -    MD0100PA00X+038386Y+126671X0200Y         S0      
317PVDDCR_CPU1_P1   VIA   -    MD0100PA00X+038136Y+126671X0200Y         S0      
317PVDDCR_CPU1_P1   VIA   -    MD0100PA00X+038136Y+126421X0200Y         S0      
317PVDDCR_CPU1_P1   VIA   -    MD0100PA00X+038136Y+126171X0200Y         S0      
317PVDDCR_CPU1_P1   VIA   -    MD0100PA00X+038386Y+126921X0200Y         S0      
317PVDDCR_CPU1_P1   VIA   -    MD0100PA00X+038136Y+126921X0200Y         S0      
327PVDDCR_CPU1_P1   PL45  -4   M      A01X+037596Y+126546X0950Y1780R270 S1      
317PVDDCR_CPU1_P1   VIA   -    MD0100PA00X+037046Y+125669X0200Y         S0      
317PVDDCR_CPU1_P1   VIA   -    MD0100PA00X+037046Y+125919X0200Y         S0      
317PVDDCR_CPU1_P1   VIA   -    MD0100PA00X+036796Y+125919X0200Y         S0      
317PVDDCR_CPU1_P1   VIA   -    MD0100PA00X+036796Y+125669X0200Y         S0      
317PVDDCR_CPU1_P1   VIA   -    MD0100PA00X+036556Y+126179X0200Y         S0      
317PVDDCR_CPU1_P1   VIA   -    MD0100PA00X+036556Y+126679X0200Y         S0      
317PVDDCR_CPU1_P1   VIA   -    MD0100PA00X+036556Y+126429X0200Y         S0      
317PVDDCR_CPU1_P1   VIA   -    MD0100PA00X+036556Y+126929X0200Y         S0      
317PVDDCR_CPU1_P1   VIA   -    MD0100PA00X+035386Y+125663X0200Y         S0      
317PVDDCR_CPU1_P1   VIA   -    MD0100PA00X+035386Y+125913X0200Y         S0      
317PVDDCR_CPU1_P1   VIA   -    MD0100PA00X+035136Y+125663X0200Y         S0      
317PVDDCR_CPU1_P1   VIA   -    MD0100PA00X+035136Y+125913X0200Y         S0      
317PVDDCR_CPU1_P1   VIA   -    MD0100PA00X+035386Y+126913X0200Y         S0      
317PVDDCR_CPU1_P1   VIA   -    MD0100PA00X+035386Y+126163X0200Y         S0      
317PVDDCR_CPU1_P1   VIA   -    MD0100PA00X+035386Y+126413X0200Y         S0      
317PVDDCR_CPU1_P1   VIA   -    MD0100PA00X+035386Y+126663X0200Y         S0      
317PVDDCR_CPU1_P1   VIA   -    MD0100PA00X+036546Y+125919X0200Y         S0      
317PVDDCR_CPU1_P1   VIA   -    MD0100PA00X+036546Y+125669X0200Y         S0      
317PVDDCR_CPU1_P1   VIA   -    MD0100PA00X+034886Y+125663X0200Y         S0      
317PVDDCR_CPU1_P1   VIA   -    MD0100PA00X+034886Y+125913X0200Y         S0      
317PVDDCR_CPU1_P1   VIA   -    MD0100PA00X+033796Y+125913X0200Y         S0      
317PVDDCR_CPU1_P1   VIA   -    MD0100PA00X+033796Y+125663X0200Y         S0      
317PVDDCR_CPU1_P1   VIA   -    MD0100PA00X+033296Y+126419X0200Y         S0      
317PVDDCR_CPU1_P1   VIA   -    MD0100PA00X+033296Y+126169X0200Y         S0      
317PVDDCR_CPU1_P1   VIA   -    MD0100PA00X+033296Y+126669X0200Y         S0      
317PVDDCR_CPU1_P1   VIA   -    MD0100PA00X+033296Y+126919X0200Y         S0      
317PVDDCR_CPU1_P1   VIA   -    MD0100PA00X+033556Y+126665X0200Y         S0      
317PVDDCR_CPU1_P1   VIA   -    MD0100PA00X+033556Y+126415X0200Y         S0      
317PVDDCR_CPU1_P1   VIA   -    MD0100PA00X+033556Y+126165X0200Y         S0      
317PVDDCR_CPU1_P1   VIA   -    MD0100PA00X+033556Y+126915X0200Y         S0      
317PVDDCR_CPU1_P1   VIA   -    MD0100PA00X+033806Y+126165X0200Y         S0      
317PVDDCR_CPU1_P1   VIA   -    MD0100PA00X+033806Y+126415X0200Y         S0      
317PVDDCR_CPU1_P1   VIA   -    MD0100PA00X+033806Y+126665X0200Y         S0      
317PVDDCR_CPU1_P1   VIA   -    MD0100PA00X+033806Y+126915X0200Y         S0      
317PVDDCR_CPU1_P1   VIA   -    MD0100PA00X+034886Y+126665X0200Y         S0      
317PVDDCR_CPU1_P1   VIA   -    MD0100PA00X+034886Y+126415X0200Y         S0      
317PVDDCR_CPU1_P1   VIA   -    MD0100PA00X+034886Y+126165X0200Y         S0      
317PVDDCR_CPU1_P1   VIA   -    MD0100PA00X+034886Y+126915X0200Y         S0      
317PVDDCR_CPU1_P1   VIA   -    MD0100PA00X+035136Y+126165X0200Y         S0      
317PVDDCR_CPU1_P1   VIA   -    MD0100PA00X+035136Y+126415X0200Y         S0      
317PVDDCR_CPU1_P1   VIA   -    MD0100PA00X+035136Y+126665X0200Y         S0      
317PVDDCR_CPU1_P1   VIA   -    MD0100PA00X+035136Y+126915X0200Y         S0      
327PVDDCR_CPU1_P1   PL40  -4   M      A01X+034346Y+126540X0950Y1780R270 S1      
317PVDDCR_CPU1_P1   VIA   -    MD0100PA00X+033296Y+125663X0200Y         S0      
317PVDDCR_CPU1_P1   VIA   -    MD0100PA00X+033296Y+125913X0200Y         S0      
317PVDDCR_CPU1_P1   VIA   -    MD0100PA00X+033546Y+125663X0200Y         S0      
317PVDDCR_CPU1_P1   VIA   -    MD0100PA00X+033546Y+125913X0200Y         S0      
317PVDDCR_CPU1_P1   VIA   -    MD0100PA00X+031596Y+125913X0200Y         S0      
317PVDDCR_CPU1_P1   VIA   -    MD0100PA00X+031596Y+125663X0200Y         S0      
317PVDDCR_CPU1_P1   VIA   -    MD0100PA00X+032096Y+126663X0200Y         S0      
317PVDDCR_CPU1_P1   VIA   -    MD0100PA00X+032096Y+126413X0200Y         S0      
317PVDDCR_CPU1_P1   VIA   -    MD0100PA00X+031846Y+125913X0200Y         S0      
317PVDDCR_CPU1_P1   VIA   -    MD0100PA00X+031846Y+125663X0200Y         S0      
317PVDDCR_CPU1_P1   VIA   -    MD0100PA00X+032096Y+126163X0200Y         S0      
317PVDDCR_CPU1_P1   VIA   -    MD0100PA00X+032096Y+125913X0200Y         S0      
317PVDDCR_CPU1_P1   VIA   -    MD0100PA00X+032096Y+125663X0200Y         S0      
317PVDDCR_CPU1_P1   VIA   -    MD0100PA00X+032096Y+126913X0200Y         S0      
317PVDDCR_CPU1_P1   VIA   -    MD0100PA00X+030256Y+125913X0200Y         S0      
317PVDDCR_CPU1_P1   VIA   -    MD0100PA00X+030256Y+125663X0200Y         S0      
317PVDDCR_CPU1_P1   VIA   -    MD0100PA00X+030006Y+126413X0200Y         S0      
317PVDDCR_CPU1_P1   VIA   -    MD0100PA00X+030006Y+126163X0200Y         S0      
317PVDDCR_CPU1_P1   VIA   -    MD0100PA00X+030006Y+125913X0200Y         S0      
317PVDDCR_CPU1_P1   VIA   -    MD0100PA00X+030006Y+125663X0200Y         S0      
317PVDDCR_CPU1_P1   VIA   -    MD0100PA00X+030506Y+125663X0200Y         S0      
317PVDDCR_CPU1_P1   VIA   -    MD0100PA00X+030506Y+125913X0200Y         S0      
317PVDDCR_CPU1_P1   VIA   -    MD0100PA00X+030006Y+126663X0200Y         S0      
317PVDDCR_CPU1_P1   VIA   -    MD0100PA00X+030006Y+126913X0200Y         S0      
317PVDDCR_CPU1_P1   VIA   -    MD0100PA00X+030516Y+126165X0200Y         S0      
317PVDDCR_CPU1_P1   VIA   -    MD0100PA00X+030516Y+126415X0200Y         S0      
317PVDDCR_CPU1_P1   VIA   -    MD0100PA00X+030516Y+126665X0200Y         S0      
317PVDDCR_CPU1_P1   VIA   -    MD0100PA00X+030266Y+126665X0200Y         S0      
317PVDDCR_CPU1_P1   VIA   -    MD0100PA00X+030266Y+126415X0200Y         S0      
317PVDDCR_CPU1_P1   VIA   -    MD0100PA00X+030266Y+126165X0200Y         S0      
317PVDDCR_CPU1_P1   VIA   -    MD0100PA00X+030516Y+126915X0200Y         S0      
317PVDDCR_CPU1_P1   VIA   -    MD0100PA00X+030266Y+126915X0200Y         S0      
317PVDDCR_CPU1_P1   VIA   -    MD0100PA00X+031846Y+126165X0200Y         S0      
317PVDDCR_CPU1_P1   VIA   -    MD0100PA00X+031846Y+126415X0200Y         S0      
317PVDDCR_CPU1_P1   VIA   -    MD0100PA00X+031846Y+126665X0200Y         S0      
317PVDDCR_CPU1_P1   VIA   -    MD0100PA00X+031596Y+126665X0200Y         S0      
317PVDDCR_CPU1_P1   VIA   -    MD0100PA00X+031596Y+126415X0200Y         S0      
317PVDDCR_CPU1_P1   VIA   -    MD0100PA00X+031596Y+126165X0200Y         S0      
317PVDDCR_CPU1_P1   VIA   -    MD0100PA00X+031846Y+126915X0200Y         S0      
317PVDDCR_CPU1_P1   VIA   -    MD0100PA00X+031596Y+126915X0200Y         S0      
327PVDDCR_CPU1_P1   PL41  -4   M      A01X+031056Y+126540X0950Y1780R270 S1      
317PVDDCR_CPU1_P1   VIA   -    MD0100PA00X+028806Y+126922X0200Y         S0      
317PVDDCR_CPU1_P1   VIA   -    MD0100PA00X+028806Y+126172X0200Y         S0      
317PVDDCR_CPU1_P1   VIA   -    MD0100PA00X+028806Y+126422X0200Y         S0      
317PVDDCR_CPU1_P1   VIA   -    MD0100PA00X+028806Y+126672X0200Y         S0      
317PVDDCR_CPU1_P1   VIA   -    MD0100PA00X+028806Y+125922X0200Y         S0      
317PVDDCR_CPU1_P1   VIA   -    MD0100PA00X+028556Y+125922X0200Y         S0      
317PVDDCR_CPU1_P1   VIA   -    MD0100PA00X+028306Y+125922X0200Y         S0      
317PVDDCR_CPU1_P1   VIA   -    MD0100PA00X+028806Y+125672X0200Y         S0      
317PVDDCR_CPU1_P1   VIA   -    MD0100PA00X+028556Y+125672X0200Y         S0      
317PVDDCR_CPU1_P1   VIA   -    MD0100PA00X+028306Y+125672X0200Y         S0      
317PVDDCR_CPU1_P1   VIA   -    MD0100PA00X+026718Y+126177X0200Y         S0      
317PVDDCR_CPU1_P1   VIA   -    MD0100PA00X+026718Y+126427X0200Y         S0      
317PVDDCR_CPU1_P1   VIA   -    MD0100PA00X+026718Y+126677X0200Y         S0      
317PVDDCR_CPU1_P1   VIA   -    MD0100PA00X+026718Y+126927X0200Y         S0      
317PVDDCR_CPU1_P1   VIA   -    MD0100PA00X+027226Y+126173X0200Y         S0      
317PVDDCR_CPU1_P1   VIA   -    MD0100PA00X+027226Y+126423X0200Y         S0      
317PVDDCR_CPU1_P1   VIA   -    MD0100PA00X+027226Y+126673X0200Y         S0      
317PVDDCR_CPU1_P1   VIA   -    MD0100PA00X+026976Y+126673X0200Y         S0      
317PVDDCR_CPU1_P1   VIA   -    MD0100PA00X+026976Y+126423X0200Y         S0      
317PVDDCR_CPU1_P1   VIA   -    MD0100PA00X+026976Y+126173X0200Y         S0      
317PVDDCR_CPU1_P1   VIA   -    MD0100PA00X+027226Y+126923X0200Y         S0      
317PVDDCR_CPU1_P1   VIA   -    MD0100PA00X+026976Y+126923X0200Y         S0      
317PVDDCR_CPU1_P1   VIA   -    MD0100PA00X+028556Y+126173X0200Y         S0      
317PVDDCR_CPU1_P1   VIA   -    MD0100PA00X+028556Y+126423X0200Y         S0      
317PVDDCR_CPU1_P1   VIA   -    MD0100PA00X+028556Y+126673X0200Y         S0      
317PVDDCR_CPU1_P1   VIA   -    MD0100PA00X+028306Y+126673X0200Y         S0      
317PVDDCR_CPU1_P1   VIA   -    MD0100PA00X+028306Y+126423X0200Y         S0      
317PVDDCR_CPU1_P1   VIA   -    MD0100PA00X+028306Y+126173X0200Y         S0      
317PVDDCR_CPU1_P1   VIA   -    MD0100PA00X+028556Y+126923X0200Y         S0      
317PVDDCR_CPU1_P1   VIA   -    MD0100PA00X+028306Y+126923X0200Y         S0      
327PVDDCR_CPU1_P1   PL44  -4   M      A01X+027766Y+126548X0950Y1780R270 S1      
317PVDDCR_CPU1_P1   VIA   -    MD0100PA00X+027216Y+125922X0200Y         S0      
317PVDDCR_CPU1_P1   VIA   -    MD0100PA00X+026966Y+125922X0200Y         S0      
317PVDDCR_CPU1_P1   VIA   -    MD0100PA00X+027216Y+125672X0200Y         S0      
317PVDDCR_CPU1_P1   VIA   -    MD0100PA00X+038386Y+124669X0200Y         S0      
317PVDDCR_CPU1_P1   VIA   -    MD0100PA00X+038636Y+125169X0200Y         S0      
317PVDDCR_CPU1_P1   VIA   -    MD0100PA00X+038386Y+125169X0200Y         S0      
317PVDDCR_CPU1_P1   VIA   -    MD0100PA00X+038636Y+124919X0200Y         S0      
317PVDDCR_CPU1_P1   VIA   -    MD0100PA00X+038386Y+124919X0200Y         S0      
317PVDDCR_CPU1_P1   VIA   -    MD0100PA00X+038636Y+125419X0200Y         S0      
317PVDDCR_CPU1_P1   VIA   -    MD0100PA00X+038386Y+125419X0200Y         S0      
317PVDDCR_CPU1_P1   VIA   -    MD0100PA00X+038136Y+124669X0200Y         S0      
317PVDDCR_CPU1_P1   VIA   -    MD0100PA00X+038136Y+125169X0200Y         S0      
317PVDDCR_CPU1_P1   VIA   -    MD0100PA00X+038136Y+124919X0200Y         S0      
317PVDDCR_CPU1_P1   VIA   -    MD0100PA00X+038136Y+125419X0200Y         S0      
317PVDDCR_CPU1_P1   VIA   -    MD0100PA00X+037046Y+125169X0200Y         S0      
317PVDDCR_CPU1_P1   VIA   -    MD0100PA00X+037046Y+124919X0200Y         S0      
317PVDDCR_CPU1_P1   VIA   -    MD0100PA00X+037046Y+125419X0200Y         S0      
317PVDDCR_CPU1_P1   VIA   -    MD0100PA00X+036796Y+124669X0200Y         S0      
317PVDDCR_CPU1_P1   VIA   -    MD0100PA00X+036796Y+124919X0200Y         S0      
317PVDDCR_CPU1_P1   VIA   -    MD0100PA00X+036796Y+125169X0200Y         S0      
317PVDDCR_CPU1_P1   VIA   -    MD0100PA00X+036796Y+125419X0200Y         S0      
317PVDDCR_CPU1_P1   VIA   -    MD0100PA00X+035136Y+125413X0200Y         S0      
317PVDDCR_CPU1_P1   VIA   -    MD0100PA00X+035386Y+125413X0200Y         S0      
317PVDDCR_CPU1_P1   VIA   -    MD0100PA00X+035136Y+124913X0200Y         S0      
317PVDDCR_CPU1_P1   VIA   -    MD0100PA00X+035386Y+124913X0200Y         S0      
317PVDDCR_CPU1_P1   VIA   -    MD0100PA00X+035136Y+125163X0200Y         S0      
317PVDDCR_CPU1_P1   VIA   -    MD0100PA00X+035386Y+125163X0200Y         S0      
317PVDDCR_CPU1_P1   VIA   -    MD0100PA00X+035386Y+124663X0200Y         S0      
317PVDDCR_CPU1_P1   VIA   -    MD0100PA00X+035136Y+124663X0200Y         S0      
317PVDDCR_CPU1_P1   VIA   -    MD0100PA00X+036546Y+124669X0200Y         S0      
317PVDDCR_CPU1_P1   VIA   -    MD0100PA00X+036546Y+124919X0200Y         S0      
317PVDDCR_CPU1_P1   VIA   -    MD0100PA00X+036546Y+125169X0200Y         S0      
317PVDDCR_CPU1_P1   VIA   -    MD0100PA00X+036546Y+125419X0200Y         S0      
317PVDDCR_CPU1_P1   VIA   -    MD0100PA00X+034886Y+125413X0200Y         S0      
317PVDDCR_CPU1_P1   VIA   -    MD0100PA00X+034886Y+124913X0200Y         S0      
317PVDDCR_CPU1_P1   VIA   -    MD0100PA00X+034886Y+125163X0200Y         S0      
317PVDDCR_CPU1_P1   VIA   -    MD0100PA00X+034886Y+124663X0200Y         S0      
317PVDDCR_CPU1_P1   VIA   -    MD0100PA00X+033796Y+125413X0200Y         S0      
317PVDDCR_CPU1_P1   VIA   -    MD0100PA00X+033796Y+124913X0200Y         S0      
317PVDDCR_CPU1_P1   VIA   -    MD0100PA00X+033796Y+125163X0200Y         S0      
317PVDDCR_CPU1_P1   VIA   -    MD0100PA00X+033296Y+125413X0200Y         S0      
317PVDDCR_CPU1_P1   VIA   -    MD0100PA00X+033546Y+125413X0200Y         S0      
317PVDDCR_CPU1_P1   VIA   -    MD0100PA00X+033296Y+125163X0200Y         S0      
317PVDDCR_CPU1_P1   VIA   -    MD0100PA00X+033546Y+125163X0200Y         S0      
317PVDDCR_CPU1_P1   VIA   -    MD0100PA00X+033296Y+124913X0200Y         S0      
317PVDDCR_CPU1_P1   VIA   -    MD0100PA00X+033546Y+124913X0200Y         S0      
317PVDDCR_CPU1_P1   VIA   -    MD0100PA00X+033296Y+124663X0200Y         S0      
317PVDDCR_CPU1_P1   VIA   -    MD0100PA00X+033546Y+124663X0200Y         S0      
317PVDDCR_CPU1_P1   VIA   -    MD0100PA00X+031846Y+124663X0200Y         S0      
317PVDDCR_CPU1_P1   VIA   -    MD0100PA00X+031596Y+124663X0200Y         S0      
317PVDDCR_CPU1_P1   VIA   -    MD0100PA00X+032096Y+125163X0200Y         S0      
317PVDDCR_CPU1_P1   VIA   -    MD0100PA00X+031846Y+125163X0200Y         S0      
317PVDDCR_CPU1_P1   VIA   -    MD0100PA00X+031596Y+125163X0200Y         S0      
317PVDDCR_CPU1_P1   VIA   -    MD0100PA00X+032096Y+124913X0200Y         S0      
317PVDDCR_CPU1_P1   VIA   -    MD0100PA00X+031846Y+124913X0200Y         S0      
317PVDDCR_CPU1_P1   VIA   -    MD0100PA00X+031596Y+124913X0200Y         S0      
317PVDDCR_CPU1_P1   VIA   -    MD0100PA00X+031596Y+125413X0200Y         S0      
317PVDDCR_CPU1_P1   VIA   -    MD0100PA00X+032096Y+125413X0200Y         S0      
317PVDDCR_CPU1_P1   VIA   -    MD0100PA00X+031846Y+125413X0200Y         S0      
317PVDDCR_CPU1_P1   VIA   -    MD0100PA00X+030256Y+124663X0200Y         S0      
317PVDDCR_CPU1_P1   VIA   -    MD0100PA00X+030006Y+124663X0200Y         S0      
317PVDDCR_CPU1_P1   VIA   -    MD0100PA00X+030506Y+124663X0200Y         S0      
317PVDDCR_CPU1_P1   VIA   -    MD0100PA00X+030256Y+124913X0200Y         S0      
317PVDDCR_CPU1_P1   VIA   -    MD0100PA00X+030006Y+124913X0200Y         S0      
317PVDDCR_CPU1_P1   VIA   -    MD0100PA00X+030256Y+125163X0200Y         S0      
317PVDDCR_CPU1_P1   VIA   -    MD0100PA00X+030006Y+125163X0200Y         S0      
317PVDDCR_CPU1_P1   VIA   -    MD0100PA00X+030506Y+125163X0200Y         S0      
317PVDDCR_CPU1_P1   VIA   -    MD0100PA00X+030506Y+124913X0200Y         S0      
317PVDDCR_CPU1_P1   VIA   -    MD0100PA00X+030256Y+125413X0200Y         S0      
317PVDDCR_CPU1_P1   VIA   -    MD0100PA00X+030006Y+125413X0200Y         S0      
317PVDDCR_CPU1_P1   VIA   -    MD0100PA00X+030506Y+125413X0200Y         S0      
317PVDDCR_CPU1_P1   VIA   -    MD0100PA00X+028556Y+125422X0200Y         S0      
317PVDDCR_CPU1_P1   VIA   -    MD0100PA00X+028806Y+125422X0200Y         S0      
317PVDDCR_CPU1_P1   VIA   -    MD0100PA00X+028306Y+125422X0200Y         S0      
317PVDDCR_CPU1_P1   VIA   -    MD0100PA00X+028306Y+124922X0200Y         S0      
317PVDDCR_CPU1_P1   VIA   -    MD0100PA00X+028556Y+124922X0200Y         S0      
317PVDDCR_CPU1_P1   VIA   -    MD0100PA00X+028806Y+124922X0200Y         S0      
317PVDDCR_CPU1_P1   VIA   -    MD0100PA00X+028306Y+125172X0200Y         S0      
317PVDDCR_CPU1_P1   VIA   -    MD0100PA00X+028556Y+125172X0200Y         S0      
317PVDDCR_CPU1_P1   VIA   -    MD0100PA00X+028806Y+125172X0200Y         S0      
317PVDDCR_CPU1_P1   VIA   -    MD0100PA00X+028306Y+124672X0200Y         S0      
317PVDDCR_CPU1_P1   VIA   -    MD0100PA00X+028806Y+124672X0200Y         S0      
317PVDDCR_CPU1_P1   VIA   -    MD0100PA00X+028556Y+124672X0200Y         S0      
317PVDDCR_CPU1_P1   VIA   -    MD0100PA00X+044116Y+105154X0190Y    R270 S0      
317PVDDCR_CPU1_P1   VIA   -    MD0100PA00X+023059Y+137993X0200Y    R180 S0      
327PVDDCR_CPU1_P1   PR268 -2          A18X+022919Y+137711X0198Y0197R270 S2      
317m3826            VIA   -    MD0100PA00X+137378Y+134969X0200Y         S0      
327m3826            PR421 -1          A18X+137010Y+134724X0198Y0197R270 S2      
327m3826            PU11  -1          A01X+137506Y+134728X0090Y0240R090 S1      
317m3827            VIA   -    MD0100PA00X+134120Y+133036X0200Y         S0      
327m3827            PU16  -1          A01X+134248Y+132795X0090Y0240R090 S1      
327m3827            PR96  -1          A18X+133752Y+132791X0198Y0197R270 S2      
317m3828            VIA   -    MD0100PA00X+120461Y+137639X0200Y         S0      
327m3828            PR91  -1          A18X+120092Y+137394X0198Y0197R270 S2      
327m3828            PU14  -1          A01X+120589Y+137398X0090Y0240R090 S1      
317m3829            VIA   -    MD0100PA00X+124260Y+133024X0200Y         S0      
327m3829            PR92  -1          A18X+123892Y+132780X0198Y0197R270 S2      
327m3829            PU15  -1          A01X+124388Y+132784X0090Y0240R090 S1      
317m3830            VIA   -    MD0100PA00X+127550Y+133022X0200Y         S0      
327m3830            PR83  -1          A18X+127181Y+132777X0198Y0197R270 S2      
327m3830            PU2   -1          A01X+127678Y+132781X0090Y0240R090 S1      
317m3831            VIA   -    MD0100PA00X+130840Y+133016X0200Y         S0      
327m3831            PR84  -1          A18X+130472Y+132771X0198Y0197R270 S2      
327m3831            PU13  -1          A01X+130968Y+132775X0090Y0240R090 S1      
327m3832            PR53  -2          A01X+125686Y+142308X0198Y0197R090 S1      
327m3832            PR54  -1   M      A01X+125286Y+142308X0198Y0197R270 S1      
327m3832            PC67  -1   M      A01X+124886Y+142308X0198Y0197R270 S1      
327m3832            PU12  -45         A01X+123232Y+142394X0070Y0260R270 S1      
327m3833            VIA   -    M      A01X+123996Y+142754X0300Y         S1      
327m3833            PR74  -2          A01X+125300Y+142692X0198Y0197R270 S1      
327m3833            PR600 -1   M      A01X+124900Y+142692X0198Y0197R090 S1      
327m3833            PC74  -1   M      A01X+124500Y+142692X0198Y0197R090 S1      
327m3833            PU12  -46         A01X+123232Y+142551X0070Y0260R270 S1      
327m3834            PC111_-1   M      A01X+137391Y+135587X0198Y0197R090 S1      
327m3834            PU11  -39         A01X+137668Y+134974X0090Y0240     S1      
317m3834            VIA   -    MD0100PA00X+137677Y+135587X0200Y    R180 S0      
327m3834            PC132_-1   M      A01X+134132Y+133654X0198Y0197R090 S1      
327m3834            PU16  -39         A01X+134410Y+133041X0090Y0240     S1      
317m3834            VIA   -    MD0100PA00X+134419Y+133654X0200Y    R180 S0      
317m3834            VIA   -    MD0100PA00X+120760Y+138257X0200Y    R180 S0      
327m3834            PU14  -39         A01X+120750Y+137644X0090Y0240     S1      
327m3834            PC113_-1   M      A01X+120473Y+138257X0198Y0197R090 S1      
317m3834            VIA   -    MD0100PA00X+117480Y+138257X0200Y         S0      
327m3834            PU17  -39         A01X+117470Y+137644X0090Y0240     S1      
327m3834            PC145_-1   M      A01X+117193Y+138257X0198Y0197R090 S1      
317m3834            VIA   -    MD0100PA00X+114190Y+138257X0200Y         S0      
327m3834            PU18  -39         A01X+114180Y+137644X0090Y0240     S1      
327m3834            PC146_-1   M      A01X+113903Y+138257X0198Y0197R090 S1      
317m3834            VIA   -    MD0100PA00X+107660Y+138257X0200Y         S0      
327m3834            PU20  -39         A01X+107650Y+137644X0090Y0240     S1      
327m3834            PC176_-1   M      A01X+107373Y+138257X0198Y0197R090 S1      
317m3834            VIA   -    MD0100PA00X+131139Y+133634X0200Y         S0      
327m3834            PU13  -39         A01X+131130Y+133021X0090Y0240     S1      
327m3834            PC84_1-1   M      A01X+130852Y+133634X0198Y0197R090 S1      
317m3834            VIA   -    MD0100PA00X+127849Y+133640X0200Y         S0      
327m3834            PU2   -39         A01X+127839Y+133027X0090Y0240     S1      
327m3834            PC83_2-1   M      A01X+127562Y+133640X0198Y0197R090 S1      
317m3834            VIA   -    MD0100PA00X+124559Y+133643X0200Y         S0      
327m3834            PU15  -39         A01X+124550Y+133030X0090Y0240     S1      
327m3834            PC114_-1   M      A01X+124272Y+133643X0198Y0197R090 S1      
317m3834            VIA   -    MD0100PA00X+110920Y+138257X0200Y         S2      
327m3834            PU19  -39         A01X+110910Y+137644X0090Y0240     S1      
327m3834            PC175_-1   M      A01X+110633Y+138257X0198Y0197R090 S1      
327m3834            PC76  -1          A01X+124500Y+144092X0198Y0197R090 S1      
327m3834            PC15  -1   M      A01X+124100Y+144092X0198Y0197R090 S1      
327m3834            PU12  -48         A01X+123232Y+142866X0070Y0260R270 S1      
317m3834            VIA   -    MD0100PA00X+123955Y+143705X0200Y         S0      
317m3835            VIA   -    MD0100PA00X+137001Y+134484X0200Y         S0      
327m3835            PC112 -1          A01X+137001Y+134724X0198Y0197R090 S1      
327m3835            PU11  -3          A01X+137506Y+134374X0090Y0240R090 S1      
327m3835            VIA   -    M      A18X+137721Y+134923X0260Y    R180 S2      
317m3835            VIA   -    MD0100PA00X+138347Y+135284X0200Y         S0      
327m3835            PR416 -2   M      A18X+137541Y+134407X0198Y0197R270 S2      
327m3835            PU11  -35         A01X+138376Y+134974X0090Y0240     S1      
327m3836            VIA   -    M      A18X+134462Y+132990X0260Y    R180 S2      
317m3836            VIA   -    MD0100PA00X+135088Y+133351X0200Y         S0      
327m3836            PR94  -2   M      A18X+134283Y+132474X0198Y0197R270 S2      
327m3836            PU16  -35         A01X+135118Y+133041X0090Y0240     S1      
317m3836            VIA   -    MD0100PA00X+133743Y+132551X0200Y         S0      
327m3836            PC131 -1          A01X+133743Y+132791X0198Y0197R090 S1      
327m3836            PU16  -3          A01X+134248Y+132441X0090Y0240R090 S1      
317m3837            VIA   -    MD0100PA00X+121429Y+137954X0200Y         S0      
327m3837            VIA   -    M      A18X+120803Y+137593X0260Y    R180 S2      
327m3837            PR87  -2   M      A18X+120624Y+137077X0198Y0197R270 S2      
327m3837            PU14  -35         A01X+121459Y+137644X0090Y0240     S1      
317m3837            VIA   -    MD0100PA00X+120084Y+137154X0200Y         S0      
327m3837            PU14  -3          A01X+120589Y+137044X0090Y0240R090 S1      
327m3837            PC109 -1          A01X+120084Y+137394X0198Y0197R090 S1      
317m3838            VIA   -    MD0100PA00X+125228Y+133340X0200Y         S0      
327m3838            VIA   -    M      A18X+124602Y+132978X0260Y    R180 S2      
327m3838            PR88  -2   M      A18X+124423Y+132462X0198Y0197R270 S2      
317m3838            VIA   -    MD0100PA00X+123883Y+132539X0200Y         S0      
327m3838            PU15  -3          A01X+124388Y+132429X0090Y0240R090 S1      
327m3838            PC110 -1          A01X+123883Y+132780X0198Y0197R090 S1      
327m3838            PU15  -35         A01X+125258Y+133030X0090Y0240     S1      
327m3839            VIA   -    M      A18X+127892Y+132975X0260Y    R180 S2      
317m3839            VIA   -    MD0100PA00X+128518Y+133337X0200Y         S0      
327m3839            PR80  -2   M      A18X+127713Y+132460X0198Y0197R270 S2      
327m3839            PU2   -35         A01X+128548Y+133027X0090Y0240     S1      
317m3839            VIA   -    MD0100PA00X+127173Y+132537X0200Y         S0      
327m3839            PU2   -3          A01X+127678Y+132426X0090Y0240R090 S1      
327m3839            PC80  -1          A01X+127173Y+132777X0198Y0197R090 S1      
327m3840            VIA   -    M      A18X+131182Y+132970X0260Y    R180 S2      
317m3840            VIA   -    MD0100PA00X+131808Y+133331X0200Y         S0      
327m3840            PR79  -2   M      A18X+131003Y+132454X0198Y0197R270 S2      
327m3840            PU13  -35         A01X+131838Y+133021X0090Y0240     S1      
317m3840            VIA   -    MD0100PA00X+130463Y+132531X0200Y         S0      
327m3840            PC79  -1          A01X+130463Y+132771X0198Y0197R090 S1      
327m3840            PU13  -3          A01X+130968Y+132421X0090Y0240R090 S1      
327m3841            PR76  -1          A01X+125300Y+143392X0198Y0197R090 S1      
327m3841            PC75  -1   M      A01X+124900Y+143392X0198Y0197R090 S1      
327m3841            PC14  -1   M      A01X+124500Y+143392X0198Y0197R090 S1      
327m3841            PU12  -47         A01X+123232Y+142709X0070Y0260R270 S1      
327m3842            PU14  -36         A01X+121282Y+137644X0090Y0240     S1      
317m3842            VIA   -    M      A01X+121156Y+138051X0200Y         S2      
017m3842            VIA   -    M      A18X+121156Y+138051X0260Y         S2      
017m3842                  -    MD0100PA00X+121156Y+138051                       
327m3842            PU15  -36         A01X+125081Y+133030X0090Y0240     S1      
317m3842            VIA   -    MD0100PA00X+124955Y+133436X0200Y         S0      
327m3842            PU2   -36         A01X+128371Y+133027X0090Y0240     S1      
317m3842            VIA   -    MD0100PA00X+128244Y+133434X0200Y         S0      
327m3842            PU16  -36         A01X+134941Y+133041X0090Y0240     S1      
317m3842            VIA   -    MD0100PA00X+134815Y+133448X0200Y         S0      
327m3842            PU11  -36         A01X+138199Y+134974X0090Y0240     S1      
317m3842            VIA   -    MD0100PA00X+138073Y+135381X0200Y         S0      
317m3842            VIA   -    MD0100PA00X+131535Y+133428X0200Y         S0      
327m3842            PU13  -36         A01X+131661Y+133021X0090Y0240     S1      
317m3842            VIA   -    MD0100PA00X+123873Y+142236X0200Y         S0      
327m3842            PC78  -1          A01X+124178Y+142236X0198Y0197     S1      
327m3842            PU12  -44         A01X+123232Y+142236X0070Y0260R270 S1      
317m3843            VIA   -    M      A01X+120304Y+143750X0200Y         S2      
017m3843            VIA   -    M      A18X+120304Y+143750X0260Y         S2      
017m3843                  -    MD0100PA00X+120304Y+143750                       
327m3843            R8073 -2          A01X+120008Y+143750X0198Y0197     S1      
327m3843            PU12  -15         A01X+120968Y+142551X0070Y0260R270 S1      
327m3844            VIA   -    M      A18X+072838Y+040233X0260Y         S2      
327m3844            R8073 -1          A01X+119692Y+143750X0198Y0197     S1      
327m3844            C5013 -1          A01X+119108Y+143750X0198Y0197R180 S1      
317m3844            VIA   -    MD0100PA00X+119400Y+143750X0200Y         S0      
317m3844            VIA   -    MD0100PA00X+128760Y+142760X0200Y         S0      
327m3844            R1186 -1          A18X+072750Y+039644X0198Y0197R090 S2      
327m3844            U18   -L5         A01X+072883Y+043249X0160Y    R090 S1      
317m3844            VIA   -    MD0100PA00X+072729Y+043096X0180Y    R090 S0      
317m3844            VIA   -    MD0100PA00X+151192Y+048388X0200Y         S0      
317m3845            VIA   -    M      A01X+120312Y+142245X0200Y         S2      
017m3845            VIA   -    M      A18X+120312Y+142245X0260Y         S2      
017m3845                  -    MD0100PA00X+120312Y+142245                       
327m3845            R8070 -2          A18X+120008Y+141900X0198Y0197R180 S2      
327m3845            PU12  -18         A01X+120968Y+142079X0070Y0260R270 S1      
327m3845            R8063 -2          A01X+120008Y+142400X0198Y0197     S1      
317m3846            VIA   -    MD0100PA00X+119400Y+142400X0200Y         S0      
327m3846            R8063 -1          A01X+119692Y+142400X0198Y0197     S1      
317m3846            VIA   -    MD0100PA00X+128760Y+142310X0200Y         S0      
317m3846            VIA   -    M      A01X+155178Y+053070X0200Y         S2      
017m3846            VIA   -    M      A18X+155178Y+053070X0260Y         S2      
017m3846                  -    MD0100PA00X+155178Y+053070                       
327m3846            U29   -4          A01X+154523Y+055522X0140Y0440     S1      
317m3847            VIA   -    M      A01X+122184Y+143880X0300Y         S1      
017m3847            VIA   -    M      A18X+122184Y+143880X0200Y         S1      
017m3847                  -    MD0100PA00X+122184Y+143880                       
317m3847            VIA   -    MD0100PA00X+138422Y+135541X0200Y         S0      
327m3847            PU11  -34         A01X+138554Y+134974X0090Y0240     S1      
327m3847            PU12  -7          A01X+122021Y+143132X0070Y0260R180 S1      
317m3848            VIA   -    M      A01X+121950Y+143600X0200Y         S2      
017m3848            VIA   -    M      A18X+121950Y+143600X0260Y         S2      
017m3848                  -    MD0100PA00X+121950Y+143600                       
327m3848            PU16  -34         A01X+135295Y+133041X0090Y0240     S1      
317m3848            VIA   -    MD0100PA00X+135163Y+133608X0200Y         S0      
327m3848            PU12  -8          A01X+121864Y+143132X0070Y0260R180 S1      
327m3849            PU14  -34         A01X+121636Y+137644X0090Y0240     S1      
317m3849            VIA   -    MD0100PA00X+121504Y+138211X0200Y         S0      
317m3849            VIA   -    MD0100PA00X+121490Y+143980X0200Y         S0      
327m3849            PU12  -9          A01X+121706Y+143132X0070Y0260R180 S1      
317m3850            VIA   -    M      A01X+121040Y+144000X0200Y         S2      
017m3850            VIA   -    M      A18X+121040Y+144000X0260Y         S2      
017m3850                  -    MD0100PA00X+121040Y+144000                       
327m3850            PU15  -34         A01X+125435Y+133030X0090Y0240     S1      
317m3850            VIA   -    MD0100PA00X+125303Y+133596X0200Y         S0      
327m3850            PU12  -10         A01X+121549Y+143132X0070Y0260R180 S1      
327m3851            PU2   -34         A01X+128725Y+133027X0090Y0240     S1      
317m3851            VIA   -    MD0100PA00X+128593Y+133594X0200Y         S0      
317m3851            VIA   -    MD0100PA00X+121300Y+143500X0200Y         S0      
327m3851            PU12  -11         A01X+121391Y+143132X0070Y0260R180 S1      
317m3852            VIA   -    MD0100PA00X+131883Y+133588X0200Y         S0      
327m3852            PU13  -34         A01X+132015Y+133021X0090Y0240     S1      
317m3852            VIA   -    MD0100PA00X+121010Y+143650X0200Y         S0      
327m3852            PU12  -12         A01X+121234Y+143132X0070Y0260R180 S1      
327m3853            PR443 -1          A01X+106636Y+138248X0198Y0197R090 S1      
327m3853            PR442 -1          A01X+106240Y+138244X0198Y0197R090 S1      
327m3853            VIA   -           A01X+106602Y+137860X0300Y    R180 S1      
327m3853            PC173_-1   M      A01X+106984Y+136659X0198Y0197R270 S1      
327m3853            PU20  -4          A01X+107489Y+136867X0090Y0240R090 S1      
317m3853            VIA   -    MD0100PA00X+106984Y+136900X0200Y    R180 S0      
327m3853            PU19  -4          A01X+110749Y+136867X0090Y0240R090 S1      
327m3853            PC174_-1   M      A01X+110244Y+136659X0198Y0197R270 S1      
317m3853            VIA   -    MD0100PA00X+113514Y+136900X0200Y    R180 S0      
327m3853            PU18  -4          A01X+114019Y+136867X0090Y0240R090 S1      
327m3853            PC144_-1   M      A01X+113514Y+136659X0198Y0197R270 S1      
327m3853            PR99  -1          A18X+114054Y+136762X0198Y0197R270 S2      
317m3853            VIA   -    MD0100PA00X+116804Y+136900X0200Y    R180 S0      
327m3853            PU17  -4          A01X+117309Y+136867X0090Y0240R090 S1      
327m3853            PC147_-1   M      A01X+116804Y+136659X0198Y0197R270 S1      
327m3853            PR100 -1          A18X+117344Y+136762X0198Y0197R270 S2      
317m3853            VIA   -    MD0100PA00X+120084Y+136900X0200Y    R180 S0      
327m3853            PU14  -4          A01X+120589Y+136867X0090Y0240R090 S1      
327m3853            PC111_-1   M      A01X+120084Y+136659X0198Y0197R270 S1      
327m3853            PR87  -1          A18X+120624Y+136762X0198Y0197R270 S2      
317m3853            VIA   -    MD0100PA00X+110244Y+136900X0200Y    R180 S0      
327m3853            PR108 -1          A18X+110784Y+136762X0198Y0197R270 S2      
327m3853            PR107 -1          A18X+107524Y+136762X0198Y0197R270 S2      
327m3853            PR88  -1          A18X+124423Y+132147X0198Y0197R270 S2      
327m3853            PC82_C-1   M      A01X+127173Y+132042X0198Y0197R270 S1      
327m3853            PU2   -4          A01X+127678Y+132249X0090Y0240R090 S1      
327m3853            PR80  -1          A18X+127713Y+132145X0198Y0197R270 S2      
317m3853            VIA   -    MD0100PA00X+127173Y+132282X0200Y    R180 S0      
327m3853            PR79  -1          A18X+131003Y+132139X0198Y0197R270 S2      
327m3853            PC81_C-1   M      A01X+130463Y+132036X0198Y0197R270 S1      
327m3853            PU13  -4          A01X+130968Y+132244X0090Y0240R090 S1      
317m3853            VIA   -    MD0100PA00X+130463Y+132277X0200Y    R180 S0      
327m3853            PR416 -1          A18X+137541Y+134092X0198Y0197R270 S2      
327m3853            PC113_-1   M      A01X+137001Y+133989X0198Y0197R270 S1      
327m3853            PU11  -4          A01X+137506Y+134197X0090Y0240R090 S1      
317m3853            VIA   -    MD0100PA00X+137001Y+134230X0200Y    R180 S0      
327m3853            PR94  -1          A18X+134283Y+132159X0198Y0197R270 S2      
327m3853            PC133_-1   M      A01X+133743Y+132056X0198Y0197R270 S1      
327m3853            PU16  -4          A01X+134248Y+132264X0090Y0240R090 S1      
317m3853            VIA   -    MD0100PA00X+133743Y+132297X0200Y    R180 S0      
317m3853            VIA   -    MD0100PA00X+123883Y+132285X0200Y    R180 S0      
327m3853            PU15  -4          A01X+124388Y+132252X0090Y0240R090 S1      
327m3853            PC112_-1   M      A01X+123883Y+132045X0198Y0197R270 S1      
327m3854            VIA   -    M      A01X+124161Y+141450X0300Y         S1      
327m3854            R8064 -2          A01X+124542Y+141050X0198Y0197R180 S1      
327m3854            R8075 -2   M      A01X+124542Y+141450X0198Y0197R180 S1      
327m3854            PU12  -41         A01X+123232Y+141764X0070Y0260R270 S1      
317m3855            VIA   -    MD0100PA00X+127104Y+141875X0200Y         S0      
327m3855            R8064 -1          A01X+124858Y+141050X0198Y0197R180 S1      
317m3855            VIA   -    M      A01X+153458Y+046707X0200Y         S2      
017m3855            VIA   -    M      A18X+153458Y+046707X0260Y         S2      
017m3855                  -    MD0100PA00X+153458Y+046707                       
327m3855            R137  -1          A18X+070750Y+039329X0198Y0197R270 S2      
317m3855            VIA   -    MD0100PA00X+070750Y+038686X0200Y    R090 S0      
327m3856            VIA   -    M      A01X+137875Y+135432X0160Y0041R090 S1      
327m3856            PU11  -37         A01X+138022Y+134974X0090Y0240     S1      
327m3856            PR7   -1          A01X+137780Y+135884X0198Y0197     S1      
327m3857            VIA   -    M      A01X+134617Y+133514X0160Y0041R090 S1      
327m3857            PU16  -37         A01X+134764Y+133041X0090Y0240     S1      
327m3857            PR93  -1          A01X+134522Y+133951X0198Y0197     S1      
327m3858            VIA   -    M      A01X+120958Y+138115X0160Y0041R090 S1      
327m3858            PU14  -37         A01X+121105Y+137644X0090Y0240     S1      
327m3858            PR85  -1          A01X+120863Y+138554X0198Y0197     S1      
327m3859            VIA   -    M      A01X+124757Y+133509X0160Y0041R090 S1      
327m3859            PU15  -37         A01X+124904Y+133030X0090Y0240     S1      
327m3859            PR86  -1          A01X+124662Y+133940X0198Y0197     S1      
327m3860            VIA   -    M      A01X+128047Y+133500X0160Y0041R090 S1      
327m3860            PU2   -37         A01X+128194Y+133027X0090Y0240     S1      
327m3860            PR77  -1          A01X+127952Y+133937X0198Y0197     S1      
327m3861            VIA   -    M      A01X+131337Y+133491X0160Y0041R090 S1      
327m3861            PU13  -37         A01X+131484Y+133021X0090Y0240     S1      
327m3861            PR78  -1          A01X+131242Y+133931X0198Y0197     S1      
317m3862            VIA   -    M      A01X+123540Y+139120X0200Y         S2      
017m3862            VIA   -    M      A18X+123540Y+139120X0260Y         S2      
017m3862                  -    MD0100PA00X+123540Y+139120                       
317m3862            VIA   -    MD0100PA00X+137677Y+135337X0200Y         S0      
327m3862            PU11  -38         A01X+137845Y+134974X0090Y0240     S1      
327m3862            PU12  -32         A01X+122336Y+140868X0070Y0260R180 S1      
317m3863            VIA   -    M      A01X+122420Y+139350X0300Y         S1      
017m3863            VIA   -    M      A18X+122420Y+139350X0200Y         S1      
017m3863                  -    MD0100PA00X+122420Y+139350                       
327m3863            PU12  -31         A01X+122179Y+140868X0070Y0260R180 S1      
317m3863            VIA   -    MD0100PA00X+134419Y+133404X0200Y         S0      
327m3863            PU16  -38         A01X+134587Y+133041X0090Y0240     S1      
317m3864            VIA   -    M      A01X+121950Y+139890X0200Y         S2      
017m3864            VIA   -    M      A18X+121950Y+139890X0260Y         S2      
017m3864                  -    MD0100PA00X+121950Y+139890                       
327m3864            PU14  -38         A01X+120928Y+137644X0090Y0240     S1      
317m3864            VIA   -    MD0100PA00X+120760Y+138007X0200Y         S0      
327m3864            PU12  -30         A01X+122021Y+140868X0070Y0260R180 S1      
317m3865            VIA   -    M      A01X+121965Y+139205X0200Y         S2      
017m3865            VIA   -    M      A18X+121965Y+139205X0260Y         S2      
017m3865                  -    MD0100PA00X+121965Y+139205                       
327m3865            PU15  -38         A01X+124727Y+133030X0090Y0240     S1      
317m3865            VIA   -    MD0100PA00X+124559Y+133392X0200Y         S0      
327m3865            PU12  -29         A01X+121864Y+140868X0070Y0260R180 S1      
317m3866            VIA   -    M      A01X+122880Y+139130X0200Y         S2      
017m3866            VIA   -    M      A18X+122880Y+139130X0260Y         S2      
017m3866                  -    MD0100PA00X+122880Y+139130                       
327m3866            PU2   -38         A01X+128016Y+133027X0090Y0240     S1      
317m3866            VIA   -    MD0100PA00X+127849Y+133389X0200Y         S0      
327m3866            PU12  -28         A01X+121706Y+140868X0070Y0260R180 S1      
317m3867            VIA   -    M      A01X+123980Y+138950X0300Y         S1      
017m3867            VIA   -    M      A18X+123980Y+138950X0200Y         S1      
017m3867                  -    MD0100PA00X+123980Y+138950                       
317m3867            VIA   -    MD0100PA00X+131139Y+133384X0200Y         S0      
327m3867            PU13  -38         A01X+131307Y+133021X0090Y0240     S1      
327m3867            PU12  -27         A01X+121549Y+140868X0070Y0260R180 S1      
317m3868            VIA   -    M      A01X+120241Y+142741X0200Y         S2      
017m3868            VIA   -    M      A18X+120241Y+142741X0260Y         S2      
017m3868                  -    MD0100PA00X+120241Y+142741                       
327m3868            R8058 -2          A18X+120008Y+142400X0198Y0197R180 S2      
327m3868            C8069 -1          A01X+120008Y+142850X0198Y0197R180 S1      
327m3868            PU12  -17         A01X+120968Y+142236X0070Y0260R270 S1      
317m3869            VIA   -    M      A01X+123568Y+141891X0200Y         S2      
017m3869            VIA   -    M      A18X+123568Y+141891X0260Y         S2      
017m3869                  -    MD0100PA00X+123568Y+141891                       
327m3869            PQ10  -D          A01X+116804Y+144500X0320Y0360R270 S1      
327m3869            PU12  -42         A01X+123232Y+141921X0070Y0260R270 S1      
327m3869            PR67  -1   M      A18X+123208Y+141700X0198Y0197     S2      
317m3869            VIA   -    MD0100PA00X+116342Y+144500X0200Y         S0      
317PVDDCR_CPU1_P0   VIA   -    MD0080PA00X+145254Y+113010X0160Y         S0      
317PVDDCR_CPU1_P0   VIA   -    MD0080PA00X+134524Y+116199X0160Y         S0      
317PVDDCR_CPU1_P0   VIA   -    MD0080PA00X+134894Y+116199X0160Y         S0      
317PVDDCR_CPU1_P0   VIA   -    MD0080PA00X+134709Y+115880X0160Y         S0      
317PVDDCR_CPU1_P0   VIA   -    MD0080PA00X+136004Y+105994X0160Y         S0      
317PVDDCR_CPU1_P0   VIA   -    MD0080PA00X+136374Y+105994X0160Y         S0      
317PVDDCR_CPU1_P0   VIA   -    MD0080PA00X+136004Y+107270X0160Y         S0      
317PVDDCR_CPU1_P0   VIA   -    MD0080PA00X+136374Y+107270X0160Y         S0      
317PVDDCR_CPU1_P0   VIA   -    MD0080PA00X+136004Y+108546X0160Y         S0      
317PVDDCR_CPU1_P0   VIA   -    MD0080PA00X+136374Y+108546X0160Y         S0      
317PVDDCR_CPU1_P0   VIA   -    MD0080PA00X+136004Y+109821X0160Y         S0      
317PVDDCR_CPU1_P0   VIA   -    MD0080PA00X+136374Y+109821X0160Y         S0      
317PVDDCR_CPU1_P0   VIA   -    MD0080PA00X+136004Y+111735X0160Y         S0      
317PVDDCR_CPU1_P0   VIA   -    MD0080PA00X+136374Y+111735X0160Y         S0      
317PVDDCR_CPU1_P0   VIA   -    MD0080PA00X+135634Y+114924X0160Y         S0      
317PVDDCR_CPU1_P0   VIA   -    MD0080PA00X+136374Y+114286X0160Y         S0      
317PVDDCR_CPU1_P0   VIA   -    MD0080PA00X+136004Y+114286X0160Y         S0      
317PVDDCR_CPU1_P0   VIA   -    MD0080PA00X+136004Y+113010X0160Y         S0      
317PVDDCR_CPU1_P0   VIA   -    MD0080PA00X+136374Y+113010X0160Y         S0      
317PVDDCR_CPU1_P0   VIA   -    MD0080PA00X+136004Y+116199X0160Y         S0      
317PVDDCR_CPU1_P0   VIA   -    MD0080PA00X+135634Y+116199X0160Y         S0      
317PVDDCR_CPU1_P0   VIA   -    MD0080PA00X+135819Y+115242X0160Y         S0      
317PVDDCR_CPU1_P0   VIA   -    MD0080PA00X+137485Y+107270X0160Y         S0      
317PVDDCR_CPU1_P0   VIA   -    MD0080PA00X+137115Y+107270X0160Y         S0      
317PVDDCR_CPU1_P0   VIA   -    MD0080PA00X+136560Y+105676X0160Y         S0      
317PVDDCR_CPU1_P0   VIA   -    MD0080PA00X+137485Y+105994X0160Y         S0      
317PVDDCR_CPU1_P0   VIA   -    MD0080PA00X+137300Y+105038X0160Y         S0      
317PVDDCR_CPU1_P0   VIA   -    MD0080PA00X+137300Y+105676X0160Y         S0      
317PVDDCR_CPU1_P0   VIA   -    MD0080PA00X+137115Y+105994X0160Y         S0      
317PVDDCR_CPU1_P0   VIA   -    MD0080PA00X+137485Y+105357X0160Y         S0      
317PVDDCR_CPU1_P0   VIA   -    MD0080PA00X+137115Y+108546X0160Y         S0      
317PVDDCR_CPU1_P0   VIA   -    MD0080PA00X+137485Y+108546X0160Y         S0      
317PVDDCR_CPU1_P0   VIA   -    MD0080PA00X+137115Y+111735X0160Y         S0      
317PVDDCR_CPU1_P0   VIA   -    MD0080PA00X+137485Y+111735X0160Y         S0      
317PVDDCR_CPU1_P0   VIA   -    MD0080PA00X+137115Y+109821X0160Y         S0      
317PVDDCR_CPU1_P0   VIA   -    MD0080PA00X+137485Y+109821X0160Y         S0      
317PVDDCR_CPU1_P0   VIA   -    MD0080PA00X+137485Y+113010X0160Y         S0      
317PVDDCR_CPU1_P0   VIA   -    MD0080PA00X+137115Y+113010X0160Y         S0      
317PVDDCR_CPU1_P0   VIA   -    MD0080PA00X+136744Y+116199X0160Y         S0      
317PVDDCR_CPU1_P0   VIA   -    MD0080PA00X+137855Y+116199X0160Y         S0      
317PVDDCR_CPU1_P0   VIA   -    MD0080PA00X+137115Y+116199X0160Y         S0      
317PVDDCR_CPU1_P0   VIA   -    MD0080PA00X+136930Y+115242X0160Y         S0      
317PVDDCR_CPU1_P0   VIA   -    MD0080PA00X+136744Y+114924X0160Y         S0      
317PVDDCR_CPU1_P0   VIA   -    MD0080PA00X+137855Y+114924X0160Y         S0      
317PVDDCR_CPU1_P0   VIA   -    MD0080PA00X+137115Y+114286X0160Y         S0      
317PVDDCR_CPU1_P0   VIA   -    MD0080PA00X+137485Y+114286X0160Y         S0      
317PVDDCR_CPU1_P0   VIA   -    MD0080PA00X+138965Y+105357X0160Y         S0      
317PVDDCR_CPU1_P0   VIA   -    MD0080PA00X+138780Y+105038X0160Y         S0      
317PVDDCR_CPU1_P0   VIA   -    MD0080PA00X+139335Y+105994X0160Y         S0      
317PVDDCR_CPU1_P0   VIA   -    MD0080PA00X+138780Y+105676X0160Y         S0      
317PVDDCR_CPU1_P0   VIA   -    MD0080PA00X+138040Y+105676X0160Y         S0      
317PVDDCR_CPU1_P0   VIA   -    MD0080PA00X+138595Y+105994X0160Y         S0      
317PVDDCR_CPU1_P0   VIA   -    MD0080PA00X+138225Y+105357X0160Y         S0      
317PVDDCR_CPU1_P0   VIA   -    MD0080PA00X+138225Y+105994X0160Y         S0      
317PVDDCR_CPU1_P0   VIA   -    MD0080PA00X+139335Y+108546X0160Y         S0      
317PVDDCR_CPU1_P0   VIA   -    MD0080PA00X+138595Y+108546X0160Y         S0      
317PVDDCR_CPU1_P0   VIA   -    MD0080PA00X+138225Y+108546X0160Y         S0      
317PVDDCR_CPU1_P0   VIA   -    MD0080PA00X+139335Y+107270X0160Y         S0      
317PVDDCR_CPU1_P0   VIA   -    MD0080PA00X+138595Y+107270X0160Y         S0      
317PVDDCR_CPU1_P0   VIA   -    MD0080PA00X+138225Y+107270X0160Y         S0      
317PVDDCR_CPU1_P0   VIA   -    MD0080PA00X+139335Y+111735X0160Y         S0      
317PVDDCR_CPU1_P0   VIA   -    MD0080PA00X+138780Y+110778X0160Y         S0      
317PVDDCR_CPU1_P0   VIA   -    MD0080PA00X+138595Y+111735X0160Y         S0      
317PVDDCR_CPU1_P0   VIA   -    MD0080PA00X+138225Y+111735X0160Y         S0      
317PVDDCR_CPU1_P0   VIA   -    MD0080PA00X+138410Y+110778X0160Y         S0      
317PVDDCR_CPU1_P0   VIA   -    MD0080PA00X+139335Y+109821X0160Y         S0      
317PVDDCR_CPU1_P0   VIA   -    MD0080PA00X+138595Y+109821X0160Y         S0      
317PVDDCR_CPU1_P0   VIA   -    MD0080PA00X+138225Y+109821X0160Y         S0      
317PVDDCR_CPU1_P0   VIA   -    MD0080PA00X+138965Y+114924X0160Y         S0      
317PVDDCR_CPU1_P0   VIA   -    MD0080PA00X+139335Y+114286X0160Y         S0      
317PVDDCR_CPU1_P0   VIA   -    MD0080PA00X+138595Y+114286X0160Y         S0      
317PVDDCR_CPU1_P0   VIA   -    MD0080PA00X+138225Y+114286X0160Y         S0      
317PVDDCR_CPU1_P0   VIA   -    MD0080PA00X+139335Y+113010X0160Y         S0      
317PVDDCR_CPU1_P0   VIA   -    MD0080PA00X+138225Y+113010X0160Y         S0      
317PVDDCR_CPU1_P0   VIA   -    MD0080PA00X+138595Y+113010X0160Y         S0      
317PVDDCR_CPU1_P0   VIA   -    MD0080PA00X+138965Y+116199X0160Y         S0      
317PVDDCR_CPU1_P0   VIA   -    MD0080PA00X+139335Y+116199X0160Y         S0      
317PVDDCR_CPU1_P0   VIA   -    MD0080PA00X+139150Y+115242X0160Y         S0      
317PVDDCR_CPU1_P0   VIA   -    MD0080PA00X+138225Y+116199X0160Y         S0      
317PVDDCR_CPU1_P0   VIA   -    MD0080PA00X+138040Y+115242X0160Y         S0      
317PVDDCR_CPU1_P0   VIA   -    MD0080PA00X+140445Y+105357X0160Y         S0      
317PVDDCR_CPU1_P0   VIA   -    MD0080PA00X+139705Y+105357X0160Y         S0      
317PVDDCR_CPU1_P0   VIA   -    MD0080PA00X+139705Y+105994X0160Y         S0      
317PVDDCR_CPU1_P0   VIA   -    MD0080PA00X+139520Y+105676X0160Y         S0      
317PVDDCR_CPU1_P0   VIA   -    MD0080PA00X+140260Y+105038X0160Y         S0      
317PVDDCR_CPU1_P0   VIA   -    MD0080PA00X+140260Y+105676X0160Y         S0      
317PVDDCR_CPU1_P0   VIA   -    MD0080PA00X+139705Y+107270X0160Y         S0      
317PVDDCR_CPU1_P0   VIA   -    MD0080PA00X+140630Y+106951X0160Y         S0      
317PVDDCR_CPU1_P0   VIA   -    MD0080PA00X+140630Y+108227X0160Y         S0      
317PVDDCR_CPU1_P0   VIA   -    MD0080PA00X+139705Y+108546X0160Y         S0      
317PVDDCR_CPU1_P0   VIA   -    MD0080PA00X+140445Y+110459X0160Y         S0      
317PVDDCR_CPU1_P0   VIA   -    MD0080PA00X+140815Y+110459X0160Y         S0      
317PVDDCR_CPU1_P0   VIA   -    MD0080PA00X+140630Y+109502X0160Y         S0      
317PVDDCR_CPU1_P0   VIA   -    MD0080PA00X+139705Y+109821X0160Y         S0      
317PVDDCR_CPU1_P0   VIA   -    MD0080PA00X+140630Y+111416X0160Y         S0      
317PVDDCR_CPU1_P0   VIA   -    MD0080PA00X+139705Y+111735X0160Y         S0      
317PVDDCR_CPU1_P0   VIA   -    MD0080PA00X+139520Y+110778X0160Y         S0      
317PVDDCR_CPU1_P0   VIA   -    MD0080PA00X+139890Y+110778X0160Y         S0      
317PVDDCR_CPU1_P0   VIA   -    MD0080PA00X+140630Y+112691X0160Y         S0      
317PVDDCR_CPU1_P0   VIA   -    MD0080PA00X+139705Y+113010X0160Y         S0      
317PVDDCR_CPU1_P0   VIA   -    MD0080PA00X+140445Y+116199X0160Y         S0      
317PVDDCR_CPU1_P0   VIA   -    MD0080PA00X+140630Y+115242X0160Y         S0      
317PVDDCR_CPU1_P0   VIA   -    MD0080PA00X+140075Y+116199X0160Y         S0      
317PVDDCR_CPU1_P0   VIA   -    MD0080PA00X+140260Y+115242X0160Y         S0      
317PVDDCR_CPU1_P0   VIA   -    MD0080PA00X+140630Y+114605X0160Y         S0      
317PVDDCR_CPU1_P0   VIA   -    MD0080PA00X+140630Y+113967X0160Y         S0      
317PVDDCR_CPU1_P0   VIA   -    MD0080PA00X+140075Y+114924X0160Y         S0      
317PVDDCR_CPU1_P0   VIA   -    MD0080PA00X+139705Y+114286X0160Y         S0      
317PVDDCR_CPU1_P0   VIA   -    MD0080PA00X+141000Y+108227X0160Y         S0      
317PVDDCR_CPU1_P0   VIA   -    MD0080PA00X+141000Y+106951X0160Y         S0      
317PVDDCR_CPU1_P0   VIA   -    MD0080PA00X+141000Y+105676X0160Y         S0      
317PVDDCR_CPU1_P0   VIA   -    MD0080PA00X+141186Y+105357X0160Y         S0      
317PVDDCR_CPU1_P0   VIA   -    MD0080PA00X+141000Y+114605X0160Y         S0      
317PVDDCR_CPU1_P0   VIA   -    MD0080PA00X+141000Y+113967X0160Y         S0      
317PVDDCR_CPU1_P0   VIA   -    MD0080PA00X+141000Y+112691X0160Y         S0      
317PVDDCR_CPU1_P0   VIA   -    MD0080PA00X+141000Y+111416X0160Y         S0      
317PVDDCR_CPU1_P0   VIA   -    MD0080PA00X+141000Y+109502X0160Y         S0      
317PVDDCR_CPU1_P0   VIA   -    MD0080PA00X+143404Y+105357X0160Y         S0      
317PVDDCR_CPU1_P0   VIA   -    MD0080PA00X+142663Y+105357X0160Y         S0      
317PVDDCR_CPU1_P0   VIA   -    MD0080PA00X+142848Y+105676X0160Y         S0      
317PVDDCR_CPU1_P0   VIA   -    MD0080PA00X+143774Y+107270X0160Y         S0      
317PVDDCR_CPU1_P0   VIA   -    MD0080PA00X+142478Y+106951X0160Y         S0      
317PVDDCR_CPU1_P0   VIA   -    MD0080PA00X+142848Y+106951X0160Y         S0      
317PVDDCR_CPU1_P0   VIA   -    MD0080PA00X+143588Y+105676X0160Y         S0      
317PVDDCR_CPU1_P0   VIA   -    MD0080PA00X+143774Y+105994X0160Y         S0      
317PVDDCR_CPU1_P0   VIA   -    MD0080PA00X+142848Y+105038X0160Y         S0      
317PVDDCR_CPU1_P0   VIA   -    MD0080PA00X+143774Y+109821X0160Y         S0      
317PVDDCR_CPU1_P0   VIA   -    MD0080PA00X+142663Y+110459X0160Y         S0      
317PVDDCR_CPU1_P0   VIA   -    MD0080PA00X+143033Y+110459X0160Y         S0      
317PVDDCR_CPU1_P0   VIA   -    MD0080PA00X+142478Y+109502X0160Y         S0      
317PVDDCR_CPU1_P0   VIA   -    MD0080PA00X+142848Y+109502X0160Y         S0      
317PVDDCR_CPU1_P0   VIA   -    MD0080PA00X+143774Y+108546X0160Y         S0      
317PVDDCR_CPU1_P0   VIA   -    MD0080PA00X+142478Y+108227X0160Y         S0      
317PVDDCR_CPU1_P0   VIA   -    MD0080PA00X+142848Y+108227X0160Y         S0      
317PVDDCR_CPU1_P0   VIA   -    MD0080PA00X+143774Y+111735X0160Y         S0      
317PVDDCR_CPU1_P0   VIA   -    MD0080PA00X+143588Y+110778X0160Y         S0      
317PVDDCR_CPU1_P0   VIA   -    MD0080PA00X+142478Y+111416X0160Y         S0      
317PVDDCR_CPU1_P0   VIA   -    MD0080PA00X+142848Y+111416X0160Y         S0      
317PVDDCR_CPU1_P0   VIA   -    MD0080PA00X+143774Y+113010X0160Y         S0      
317PVDDCR_CPU1_P0   VIA   -    MD0080PA00X+142848Y+112691X0160Y         S0      
317PVDDCR_CPU1_P0   VIA   -    MD0080PA00X+142478Y+112691X0160Y         S0      
317PVDDCR_CPU1_P0   VIA   -    MD0080PA00X+143033Y+116199X0160Y         S0      
317PVDDCR_CPU1_P0   VIA   -    MD0080PA00X+143404Y+116199X0160Y         S0      
317PVDDCR_CPU1_P0   VIA   -    MD0080PA00X+143218Y+115242X0160Y         S0      
317PVDDCR_CPU1_P0   VIA   -    MD0080PA00X+142848Y+115242X0160Y         S0      
317PVDDCR_CPU1_P0   VIA   -    MD0080PA00X+143774Y+114286X0160Y         S0      
317PVDDCR_CPU1_P0   VIA   -    MD0080PA00X+142478Y+114605X0160Y         S0      
317PVDDCR_CPU1_P0   VIA   -    MD0080PA00X+142848Y+114605X0160Y         S0      
317PVDDCR_CPU1_P0   VIA   -    MD0080PA00X+143404Y+114924X0160Y         S0      
317PVDDCR_CPU1_P0   VIA   -    MD0080PA00X+142478Y+113967X0160Y         S0      
317PVDDCR_CPU1_P0   VIA   -    MD0080PA00X+142848Y+113967X0160Y         S0      
317PVDDCR_CPU1_P0   VIA   -    MD0080PA00X+145254Y+107270X0160Y         S0      
317PVDDCR_CPU1_P0   VIA   -    MD0080PA00X+144884Y+107270X0160Y         S0      
317PVDDCR_CPU1_P0   VIA   -    MD0080PA00X+144144Y+107270X0160Y         S0      
317PVDDCR_CPU1_P0   VIA   -    MD0080PA00X+145254Y+105994X0160Y         S0      
317PVDDCR_CPU1_P0   VIA   -    MD0080PA00X+144884Y+105994X0160Y         S0      
317PVDDCR_CPU1_P0   VIA   -    MD0080PA00X+144329Y+105038X0160Y         S0      
317PVDDCR_CPU1_P0   VIA   -    MD0080PA00X+144884Y+105357X0160Y         S0      
317PVDDCR_CPU1_P0   VIA   -    MD0080PA00X+144329Y+105676X0160Y         S0      
317PVDDCR_CPU1_P0   VIA   -    MD0080PA00X+144144Y+105357X0160Y         S0      
317PVDDCR_CPU1_P0   VIA   -    MD0080PA00X+144144Y+105994X0160Y         S0      
317PVDDCR_CPU1_P0   VIA   -    MD0080PA00X+145069Y+105676X0160Y         S0      
317PVDDCR_CPU1_P0   VIA   -    MD0080PA00X+145254Y+108546X0160Y         S0      
317PVDDCR_CPU1_P0   VIA   -    MD0080PA00X+144144Y+108546X0160Y         S0      
317PVDDCR_CPU1_P0   VIA   -    MD0080PA00X+144884Y+108546X0160Y         S0      
317PVDDCR_CPU1_P0   VIA   -    MD0080PA00X+145254Y+111735X0160Y         S0      
317PVDDCR_CPU1_P0   VIA   -    MD0080PA00X+144144Y+111735X0160Y         S0      
317PVDDCR_CPU1_P0   VIA   -    MD0080PA00X+144884Y+111735X0160Y         S0      
317PVDDCR_CPU1_P0   VIA   -    MD0080PA00X+143959Y+110778X0160Y         S0      
317PVDDCR_CPU1_P0   VIA   -    MD0080PA00X+144699Y+110778X0160Y         S0      
317PVDDCR_CPU1_P0   VIA   -    MD0080PA00X+145069Y+110778X0160Y         S0      
317PVDDCR_CPU1_P0   VIA   -    MD0080PA00X+145254Y+109821X0160Y         S0      
317PVDDCR_CPU1_P0   VIA   -    MD0080PA00X+144144Y+109821X0160Y         S0      
317PVDDCR_CPU1_P0   VIA   -    MD0080PA00X+144884Y+109821X0160Y         S0      
317PVDDCR_CPU1_P0   VIA   -    MD0080PA00X+144144Y+113010X0160Y         S0      
317PVDDCR_CPU1_P0   VIA   -    MD0080PA00X+144884Y+113010X0160Y         S0      
317PVDDCR_CPU1_P0   VIA   -    MD0080PA00X+144514Y+116199X0160Y         S0      
317PVDDCR_CPU1_P0   VIA   -    MD0080PA00X+144144Y+116199X0160Y         S0      
317PVDDCR_CPU1_P0   VIA   -    MD0080PA00X+145254Y+116199X0160Y         S0      
317PVDDCR_CPU1_P0   VIA   -    MD0080PA00X+144329Y+115242X0160Y         S0      
317PVDDCR_CPU1_P0   VIA   -    MD0080PA00X+145254Y+114286X0160Y         S0      
317PVDDCR_CPU1_P0   VIA   -    MD0080PA00X+144514Y+114924X0160Y         S0      
317PVDDCR_CPU1_P0   VIA   -    MD0080PA00X+144144Y+114286X0160Y         S0      
317PVDDCR_CPU1_P0   VIA   -    MD0080PA00X+144884Y+114286X0160Y         S0      
317PVDDCR_CPU1_P0   VIA   -    MD0080PA00X+145994Y+107270X0160Y         S0      
317PVDDCR_CPU1_P0   VIA   -    MD0080PA00X+146364Y+107270X0160Y         S0      
317PVDDCR_CPU1_P0   VIA   -    MD0080PA00X+145994Y+105994X0160Y         S0      
317PVDDCR_CPU1_P0   VIA   -    MD0080PA00X+145809Y+105038X0160Y         S0      
317PVDDCR_CPU1_P0   VIA   -    MD0080PA00X+146549Y+105676X0160Y         S0      
317PVDDCR_CPU1_P0   VIA   -    MD0080PA00X+146364Y+105994X0160Y         S0      
317PVDDCR_CPU1_P0   VIA   -    MD0080PA00X+145809Y+105676X0160Y         S0      
317PVDDCR_CPU1_P0   VIA   -    MD0080PA00X+146364Y+105357X0160Y         S0      
317PVDDCR_CPU1_P0   VIA   -    MD0080PA00X+145624Y+105357X0160Y         S0      
317PVDDCR_CPU1_P0   VIA   -    MD0080PA00X+145994Y+108546X0160Y         S0      
317PVDDCR_CPU1_P0   VIA   -    MD0080PA00X+146364Y+108546X0160Y         S0      
317PVDDCR_CPU1_P0   VIA   -    MD0080PA00X+146364Y+111735X0160Y         S0      
317PVDDCR_CPU1_P0   VIA   -    MD0080PA00X+145994Y+111735X0160Y         S0      
317PVDDCR_CPU1_P0   VIA   -    MD0080PA00X+145994Y+109821X0160Y         S0      
317PVDDCR_CPU1_P0   VIA   -    MD0080PA00X+146364Y+109821X0160Y         S0      
317PVDDCR_CPU1_P0   VIA   -    MD0080PA00X+145624Y+116199X0160Y         S0      
317PVDDCR_CPU1_P0   VIA   -    MD0080PA00X+146364Y+116199X0160Y         S0      
317PVDDCR_CPU1_P0   VIA   -    MD0080PA00X+146734Y+116199X0160Y         S0      
317PVDDCR_CPU1_P0   VIA   -    MD0080PA00X+145439Y+115242X0160Y         S0      
317PVDDCR_CPU1_P0   VIA   -    MD0080PA00X+146549Y+115242X0160Y         S0      
317PVDDCR_CPU1_P0   VIA   -    MD0080PA00X+146734Y+114924X0160Y         S0      
317PVDDCR_CPU1_P0   VIA   -    MD0080PA00X+145624Y+114924X0160Y         S0      
317PVDDCR_CPU1_P0   VIA   -    MD0080PA00X+145994Y+114286X0160Y         S0      
317PVDDCR_CPU1_P0   VIA   -    MD0080PA00X+146364Y+114286X0160Y         S0      
317PVDDCR_CPU1_P0   VIA   -    MD0080PA00X+146364Y+113010X0160Y         S0      
317PVDDCR_CPU1_P0   VIA   -    MD0080PA00X+145994Y+113010X0160Y         S0      
317PVDDCR_CPU1_P0   VIA   -    MD0080PA00X+147474Y+107270X0160Y         S0      
317PVDDCR_CPU1_P0   VIA   -    MD0080PA00X+147104Y+105994X0160Y         S0      
317PVDDCR_CPU1_P0   VIA   -    MD0080PA00X+147474Y+105994X0160Y         S0      
317PVDDCR_CPU1_P0   VIA   -    MD0080PA00X+147104Y+105357X0160Y         S0      
317PVDDCR_CPU1_P0   VIA   -    MD0080PA00X+147289Y+105676X0160Y         S0      
317PVDDCR_CPU1_P0   VIA   -    MD0080PA00X+147104Y+107270X0160Y         S0      
317PVDDCR_CPU1_P0   VIA   -    MD0080PA00X+147104Y+109821X0160Y         S0      
317PVDDCR_CPU1_P0   VIA   -    MD0080PA00X+147474Y+109821X0160Y         S0      
317PVDDCR_CPU1_P0   VIA   -    MD0080PA00X+147104Y+108546X0160Y         S0      
317PVDDCR_CPU1_P0   VIA   -    MD0080PA00X+147474Y+108546X0160Y         S0      
317PVDDCR_CPU1_P0   VIA   -    MD0080PA00X+147104Y+111735X0160Y         S0      
317PVDDCR_CPU1_P0   VIA   -    MD0080PA00X+147474Y+111735X0160Y         S0      
317PVDDCR_CPU1_P0   VIA   -    MD0080PA00X+147104Y+113010X0160Y         S0      
317PVDDCR_CPU1_P0   VIA   -    MD0080PA00X+147474Y+113010X0160Y         S0      
317PVDDCR_CPU1_P0   VIA   -    MD0080PA00X+147474Y+116199X0160Y         S0      
317PVDDCR_CPU1_P0   VIA   -    MD0080PA00X+147844Y+116199X0160Y         S0      
317PVDDCR_CPU1_P0   VIA   -    MD0080PA00X+147659Y+115242X0160Y         S0      
317PVDDCR_CPU1_P0   VIA   -    MD0080PA00X+147844Y+114924X0160Y         S0      
317PVDDCR_CPU1_P0   VIA   -    MD0080PA00X+147104Y+114286X0160Y         S0      
317PVDDCR_CPU1_P0   VIA   -    MD0080PA00X+147474Y+114286X0160Y         S0      
317PVDDCR_CPU1_P0   VIA   -    MD0080PA00X+148770Y+115880X0160Y         S0      
317PVDDCR_CPU1_P0   VIA   -    MD0080PA00X+148585Y+116199X0160Y         S0      
317PVDDCR_CPU1_P0   VIA   -    MD0080PA00X+148955Y+116199X0160Y         S0      
327PVDDCR_CPU1_P0   C2201 -1   M      A18X+139723Y+106026X0198Y0197R180 S2      
327PVDDCR_CPU1_P0   C2202 -1   M      A18X+142667Y+105326X0198Y0197     S2      
327PVDDCR_CPU1_P0   C2203 -1   M      A18X+140988Y+105676X0198Y0197     S2      
327PVDDCR_CPU1_P0   C2204 -1   M      A18X+143415Y+105326X0198Y0197     S2      
327PVDDCR_CPU1_P0   C2205 -1   M      A18X+138188Y+105326X0198Y0197     S2      
327PVDDCR_CPU1_P0   C2207 -1   M      A18X+146338Y+105314X0198Y0197     S2      
327PVDDCR_CPU1_P0   C2208 -1   M      A18X+144173Y+106026X0198Y0197R180 S2      
327PVDDCR_CPU1_P0   C2209 -1   M      A18X+140595Y+106849X0198Y0197     S2      
327PVDDCR_CPU1_P0   C2210 -1   M      A18X+138238Y+106026X0198Y0197     S2      
327PVDDCR_CPU1_P0   C2211 -1   M      A18X+144888Y+105314X0198Y0197     S2      
327PVDDCR_CPU1_P0   C2213 -1   M      A18X+144160Y+107199X0198Y0197R180 S2      
327PVDDCR_CPU1_P0   C2214 -1   M      A18X+145788Y+105676X0198Y0197     S2      
327PVDDCR_CPU1_P0   C2215 -1   M      A18X+145975Y+107199X0198Y0197     S2      
327PVDDCR_CPU1_P0   C2216 -1   M      A18X+139338Y+106026X0198Y0197     S2      
327PVDDCR_CPU1_P0   C2217 -1   M      A18X+136610Y+105676X0198Y0197R180 S2      
327PVDDCR_CPU1_P0   C2219 -1   M      A18X+143588Y+105676X0198Y0197     S2      
327PVDDCR_CPU1_P0   C2220 -1   M      A18X+138788Y+105676X0198Y0197     S2      
327PVDDCR_CPU1_P0   C2221 -1   M      A18X+143775Y+107199X0198Y0197     S2      
327PVDDCR_CPU1_P0   C2222 -1   M      A18X+144338Y+105676X0198Y0197     S2      
327PVDDCR_CPU1_P0   C2223 -1   M      A18X+147088Y+105314X0198Y0197     S2      
327PVDDCR_CPU1_P0   C2225 -1   M      A18X+142890Y+106849X0198Y0197R180 S2      
327PVDDCR_CPU1_P0   C2226 -1   M      A18X+140238Y+105676X0198Y0197     S2      
327PVDDCR_CPU1_P0   C2227 -1   M      A18X+140438Y+105326X0198Y0197     S2      
327PVDDCR_CPU1_P0   C2228 -1   M      A18X+145995Y+106026X0198Y0197     S2      
327PVDDCR_CPU1_P0   C2229 -1   M      A18X+139538Y+105676X0198Y0197     S2      
327PVDDCR_CPU1_P0   C2231 -1   M      A18X+137488Y+105326X0198Y0197     S2      
327PVDDCR_CPU1_P0   C2232 -1   M      A18X+145038Y+105676X0198Y0197     S2      
327PVDDCR_CPU1_P0   C2233 -1   M      A18X+137048Y+107196X0198Y0197R090 S2      
327PVDDCR_CPU1_P0   C2234 -1   M      A18X+137510Y+107199X0198Y0197R180 S2      
327PVDDCR_CPU1_P0   C2237 -1   M      A18X+138938Y+105326X0198Y0197     S2      
327PVDDCR_CPU1_P0   C2238 -1   M      A18X+138038Y+105676X0198Y0197     S2      
327PVDDCR_CPU1_P0   C2239 -1   M      A18X+139710Y+107199X0198Y0197R180 S2      
327PVDDCR_CPU1_P0   C2240 -1   M      A18X+141188Y+105326X0198Y0197     S2      
327PVDDCR_CPU1_P0   C2243 -1   M      A18X+145588Y+105314X0198Y0197     S2      
327PVDDCR_CPU1_P0   C2244 -1   M      A18X+141730Y+105169X0198Y0197R270 S2      
327PVDDCR_CPU1_P0   C2245 -1   M      A18X+146538Y+105676X0198Y0197     S2      
327PVDDCR_CPU1_P0   C2246 -1   M      A18X+147096Y+105985X0198Y0197R060 S2      
327PVDDCR_CPU1_P0   C2248 -1   M      A18X+142838Y+105676X0198Y0197     S2      
327PVDDCR_CPU1_P0   C2249 -1   M      A18X+146418Y+107186X0198Y0197R090 S2      
327PVDDCR_CPU1_P0   C2250 -1   M      A18X+139325Y+107199X0198Y0197     S2      
327PVDDCR_CPU1_P0   C2251 -1   M      A18X+146353Y+106026X0198Y0197R180 S2      
327PVDDCR_CPU1_P0   C2253 -1   M      A18X+139688Y+105326X0198Y0197     S2      
327PVDDCR_CPU1_P0   C2254 -1   M      A18X+143788Y+106026X0198Y0197     S2      
327PVDDCR_CPU1_P0   C2255 -1   M      A18X+144163Y+105326X0198Y0197     S2      
327PVDDCR_CPU1_P0   C2256 -1   M      A18X+136360Y+106026X0198Y0197R180 S2      
327PVDDCR_CPU1_P0   U25   -CV29       A01X+145070Y+112906X0177Y    R180 S1      
327PVDDCR_CPU1_P0   PR51  -2          A01X+140762Y+128976X0198Y0197R180 S1      
327PVDDCR_CPU1_P0   PC99  -1          A01X+140369Y+128934X0198Y0197R270 S1      
327PVDDCR_CPU1_P0   PC130_-1          A18X+122730Y+132753X0400Y0500R090 S2      
327PVDDCR_CPU1_P0   PC129_-1          A18X+121880Y+132755X0400Y0500R090 S2      
327PVDDCR_CPU1_P0   PC128_-1          A18X+121063Y+132753X0400Y0500R090 S2      
327PVDDCR_CPU1_P0   PC127_-1          A18X+120173Y+132753X0400Y0500R090 S2      
327PVDDCR_CPU1_P0   PR444 -1          A18X+140569Y+130318X0198Y0197R270 S2      
327PVDDCR_CPU1_P0   PC123_-1          A18X+140050Y+130085X0400Y0500R090 S2      
327PVDDCR_CPU1_P0   PC120_-1          A18X+137230Y+130073X0400Y0500R090 S2      
327PVDDCR_CPU1_P0   PC100 -1          A18X+138679Y+129890X0950Y1110R270 S2      
327PVDDCR_CPU1_P0   PC141_-1          A18X+136583Y+128319X0400Y0500R090 S2      
327PVDDCR_CPU1_P0   PC98  -1          A18X+135210Y+127958X0950Y1110R270 S2      
327PVDDCR_CPU1_P0   PC102_-1          A18X+133144Y+128131X0400Y0500R090 S2      
327PVDDCR_CPU1_P0   PC140_-1          A18X+133833Y+128139X0400Y0500R090 S2      
327PVDDCR_CPU1_P0   PC103 -1          A18X+131770Y+127960X0950Y1110R270 S2      
327PVDDCR_CPU1_P0   PC105_-1          A18X+130396Y+128119X0400Y0500R090 S2      
327PVDDCR_CPU1_P0   PC106_-1          A18X+129708Y+128118X0400Y0500R090 S2      
327PVDDCR_CPU1_P0   PC102 -1          A18X+128311Y+127969X0950Y1110R270 S2      
327PVDDCR_CPU1_P0   PC108_-1          A18X+126935Y+128086X0400Y0500R090 S2      
327PVDDCR_CPU1_P0   PC97  -1          A18X+125369Y+127969X0950Y1110R270 S2      
327PVDDCR_CPU1_P0   VIA   -           A18X+134669Y+124377X0260Y    R180 S2      
327PVDDCR_CPU1_P0   VIA   -           A18X+131419Y+124371X0260Y    R180 S2      
327PVDDCR_CPU1_P0   VIA   -           A18X+128129Y+124371X0260Y    R180 S2      
327PVDDCR_CPU1_P0   U25   -BN27       A01X+145625Y+104933X0177Y    R180 S1      
327PVDDCR_CPU1_P0   U25   -BN31       A01X+144145Y+104933X0177Y    R180 S1      
327PVDDCR_CPU1_P0   U25   -BN35       A01X+142665Y+104933X0177Y    R180 S1      
327PVDDCR_CPU1_P0   U25   -BN42       A01X+140444Y+104933X0177Y    R180 S1      
327PVDDCR_CPU1_P0   U25   -BN46       A01X+138964Y+104933X0177Y    R180 S1      
327PVDDCR_CPU1_P0   U25   -BN50       A01X+137484Y+104933X0177Y    R180 S1      
327PVDDCR_CPU1_P0   U25   -BP24       A01X+146920Y+105252X0177Y    R180 S1      
327PVDDCR_CPU1_P0   U25   -BP26       A01X+146180Y+105252X0177Y    R180 S1      
327PVDDCR_CPU1_P0   U25   -BP28       A01X+145440Y+105252X0177Y    R180 S1      
327PVDDCR_CPU1_P0   U25   -BP30       A01X+144700Y+105252X0177Y    R180 S1      
327PVDDCR_CPU1_P0   U25   -BP32       A01X+143960Y+105252X0177Y    R180 S1      
327PVDDCR_CPU1_P0   U25   -BP34       A01X+143220Y+105252X0177Y    R180 S1      
327PVDDCR_CPU1_P0   U25   -BP36       A01X+142480Y+105252X0177Y    R180 S1      
327PVDDCR_CPU1_P0   U25   -BP39       A01X+141369Y+105252X0177Y    R180 S1      
327PVDDCR_CPU1_P0   U25   -BP41       A01X+140629Y+105252X0177Y    R180 S1      
327PVDDCR_CPU1_P0   U25   -BP43       A01X+139889Y+105252X0177Y    R180 S1      
327PVDDCR_CPU1_P0   U25   -BP45       A01X+139149Y+105252X0177Y    R180 S1      
327PVDDCR_CPU1_P0   U25   -BP47       A01X+138409Y+105252X0177Y    R180 S1      
327PVDDCR_CPU1_P0   U25   -BP49       A01X+137668Y+105252X0177Y    R180 S1      
327PVDDCR_CPU1_P0   U25   -BR23       A01X+147106Y+105571X0177Y    R180 S1      
327PVDDCR_CPU1_P0   U25   -BR25       A01X+146365Y+105571X0177Y    R180 S1      
327PVDDCR_CPU1_P0   U25   -BR27       A01X+145625Y+105571X0177Y    R180 S1      
327PVDDCR_CPU1_P0   U25   -BR29       A01X+144885Y+105571X0177Y    R180 S1      
327PVDDCR_CPU1_P0   U25   -BR31       A01X+144145Y+105571X0177Y    R180 S1      
327PVDDCR_CPU1_P0   U25   -BR33       A01X+143405Y+105571X0177Y    R180 S1      
327PVDDCR_CPU1_P0   U25   -BR35       A01X+142665Y+105571X0177Y    R180 S1      
327PVDDCR_CPU1_P0   U25   -BR40       A01X+141184Y+105571X0177Y    R180 S1      
327PVDDCR_CPU1_P0   U25   -BR42       A01X+140444Y+105571X0177Y    R180 S1      
327PVDDCR_CPU1_P0   U25   -BR44       A01X+139704Y+105571X0177Y    R180 S1      
327PVDDCR_CPU1_P0   U25   -BR46       A01X+138964Y+105571X0177Y    R180 S1      
327PVDDCR_CPU1_P0   U25   -BR48       A01X+138224Y+105571X0177Y    R180 S1      
327PVDDCR_CPU1_P0   U25   -BR50       A01X+137484Y+105571X0177Y    R180 S1      
327PVDDCR_CPU1_P0   U25   -BR52       A01X+136743Y+105571X0177Y    R180 S1      
327PVDDCR_CPU1_P0   U25   -BT23       A01X+147290Y+105890X0177Y    R180 S1      
327PVDDCR_CPU1_P0   U25   -BT24       A01X+146920Y+105890X0177Y    R180 S1      
327PVDDCR_CPU1_P0   U25   -BT26       A01X+146180Y+105890X0177Y    R180 S1      
327PVDDCR_CPU1_P0   U25   -BT27       A01X+145810Y+105890X0177Y    R180 S1      
327PVDDCR_CPU1_P0   U25   -BT29       A01X+145070Y+105890X0177Y    R180 S1      
327PVDDCR_CPU1_P0   U25   -BT30       A01X+144700Y+105890X0177Y    R180 S1      
327PVDDCR_CPU1_P0   U25   -BT32       A01X+143960Y+105890X0177Y    R180 S1      
327PVDDCR_CPU1_P0   U25   -BT33       A01X+143590Y+105890X0177Y    R180 S1      
327PVDDCR_CPU1_P0   U25   -BT43       A01X+139889Y+105890X0177Y    R180 S1      
327PVDDCR_CPU1_P0   U25   -BT44       A01X+139519Y+105890X0177Y    R180 S1      
327PVDDCR_CPU1_P0   U25   -BT46       A01X+138779Y+105890X0177Y    R180 S1      
327PVDDCR_CPU1_P0   U25   -BT47       A01X+138409Y+105890X0177Y    R180 S1      
327PVDDCR_CPU1_P0   U25   -BT49       A01X+137668Y+105890X0177Y    R180 S1      
327PVDDCR_CPU1_P0   U25   -BT50       A01X+137298Y+105890X0177Y    R180 S1      
327PVDDCR_CPU1_P0   U25   -BT52       A01X+136558Y+105890X0177Y    R180 S1      
327PVDDCR_CPU1_P0   U25   -BT53       A01X+136188Y+105890X0177Y    R180 S1      
327PVDDCR_CPU1_P0   U25   -BW35       A01X+142665Y+106846X0177Y    R180 S1      
327PVDDCR_CPU1_P0   U25   -BW36       A01X+142294Y+106846X0177Y    R180 S1      
327PVDDCR_CPU1_P0   U25   -BW40       A01X+141184Y+106846X0177Y    R180 S1      
327PVDDCR_CPU1_P0   U25   -BW41       A01X+140814Y+106846X0177Y    R180 S1      
327PVDDCR_CPU1_P0   U25   -BY23       A01X+147290Y+107165X0177Y    R180 S1      
327PVDDCR_CPU1_P0   U25   -BY24       A01X+146920Y+107165X0177Y    R180 S1      
327PVDDCR_CPU1_P0   U25   -BY26       A01X+146180Y+107165X0177Y    R180 S1      
327PVDDCR_CPU1_P0   U25   -BY27       A01X+145810Y+107165X0177Y    R180 S1      
327PVDDCR_CPU1_P0   U25   -BY29       A01X+145070Y+107165X0177Y    R180 S1      
327PVDDCR_CPU1_P0   U25   -BY30       A01X+144700Y+107165X0177Y    R180 S1      
327PVDDCR_CPU1_P0   U25   -BY32       A01X+143960Y+107165X0177Y    R180 S1      
327PVDDCR_CPU1_P0   U25   -BY33       A01X+143590Y+107165X0177Y    R180 S1      
327PVDDCR_CPU1_P0   U25   -BY43       A01X+139889Y+107165X0177Y    R180 S1      
327PVDDCR_CPU1_P0   U25   -BY44       A01X+139519Y+107165X0177Y    R180 S1      
327PVDDCR_CPU1_P0   U25   -BY46       A01X+138779Y+107165X0177Y    R180 S1      
327PVDDCR_CPU1_P0   U25   -BY47       A01X+138409Y+107165X0177Y    R180 S1      
327PVDDCR_CPU1_P0   U25   -BY49       A01X+137668Y+107165X0177Y    R180 S1      
327PVDDCR_CPU1_P0   U25   -BY50       A01X+137298Y+107165X0177Y    R180 S1      
327PVDDCR_CPU1_P0   U25   -BY52       A01X+136558Y+107165X0177Y    R180 S1      
327PVDDCR_CPU1_P0   U25   -BY53       A01X+136188Y+107165X0177Y    R180 S1      
327PVDDCR_CPU1_P0   U25   -CC35       A01X+142665Y+108122X0177Y    R180 S1      
327PVDDCR_CPU1_P0   U25   -CC36       A01X+142294Y+108122X0177Y    R180 S1      
327PVDDCR_CPU1_P0   U25   -CC40       A01X+141184Y+108122X0177Y    R180 S1      
327PVDDCR_CPU1_P0   U25   -CC41       A01X+140814Y+108122X0177Y    R180 S1      
327PVDDCR_CPU1_P0   U25   -CD23       A01X+147290Y+108441X0177Y    R180 S1      
327PVDDCR_CPU1_P0   U25   -CD24       A01X+146920Y+108441X0177Y    R180 S1      
327PVDDCR_CPU1_P0   U25   -CD26       A01X+146180Y+108441X0177Y    R180 S1      
327PVDDCR_CPU1_P0   U25   -CD27       A01X+145810Y+108441X0177Y    R180 S1      
327PVDDCR_CPU1_P0   U25   -CD29       A01X+145070Y+108441X0177Y    R180 S1      
327PVDDCR_CPU1_P0   U25   -CD30       A01X+144700Y+108441X0177Y    R180 S1      
327PVDDCR_CPU1_P0   U25   -CD32       A01X+143960Y+108441X0177Y    R180 S1      
327PVDDCR_CPU1_P0   U25   -CD33       A01X+143590Y+108441X0177Y    R180 S1      
327PVDDCR_CPU1_P0   U25   -CD43       A01X+139889Y+108441X0177Y    R180 S1      
327PVDDCR_CPU1_P0   U25   -CD44       A01X+139519Y+108441X0177Y    R180 S1      
327PVDDCR_CPU1_P0   U25   -CD46       A01X+138779Y+108441X0177Y    R180 S1      
327PVDDCR_CPU1_P0   U25   -CD47       A01X+138409Y+108441X0177Y    R180 S1      
327PVDDCR_CPU1_P0   U25   -CD49       A01X+137668Y+108441X0177Y    R180 S1      
327PVDDCR_CPU1_P0   U25   -CD50       A01X+137298Y+108441X0177Y    R180 S1      
327PVDDCR_CPU1_P0   U25   -CD52       A01X+136558Y+108441X0177Y    R180 S1      
327PVDDCR_CPU1_P0   U25   -CD53       A01X+136188Y+108441X0177Y    R180 S1      
327PVDDCR_CPU1_P0   U25   -CG35       A01X+142665Y+109398X0177Y    R180 S1      
327PVDDCR_CPU1_P0   U25   -CG36       A01X+142294Y+109398X0177Y    R180 S1      
327PVDDCR_CPU1_P0   U25   -CG40       A01X+141184Y+109398X0177Y    R180 S1      
327PVDDCR_CPU1_P0   U25   -CG41       A01X+140814Y+109398X0177Y    R180 S1      
327PVDDCR_CPU1_P0   U25   -CH23       A01X+147290Y+109717X0177Y    R180 S1      
327PVDDCR_CPU1_P0   U25   -CH24       A01X+146920Y+109717X0177Y    R180 S1      
327PVDDCR_CPU1_P0   U25   -CH26       A01X+146180Y+109717X0177Y    R180 S1      
327PVDDCR_CPU1_P0   U25   -CH27       A01X+145810Y+109717X0177Y    R180 S1      
327PVDDCR_CPU1_P0   U25   -CH29       A01X+145070Y+109717X0177Y    R180 S1      
327PVDDCR_CPU1_P0   U25   -CH30       A01X+144700Y+109717X0177Y    R180 S1      
327PVDDCR_CPU1_P0   U25   -CH32       A01X+143960Y+109717X0177Y    R180 S1      
327PVDDCR_CPU1_P0   U25   -CH33       A01X+143590Y+109717X0177Y    R180 S1      
327PVDDCR_CPU1_P0   U25   -CH43       A01X+139889Y+109717X0177Y    R180 S1      
327PVDDCR_CPU1_P0   U25   -CH44       A01X+139519Y+109717X0177Y    R180 S1      
327PVDDCR_CPU1_P0   U25   -CH46       A01X+138779Y+109717X0177Y    R180 S1      
327PVDDCR_CPU1_P0   U25   -CH47       A01X+138409Y+109717X0177Y    R180 S1      
327PVDDCR_CPU1_P0   U25   -CH49       A01X+137668Y+109717X0177Y    R180 S1      
327PVDDCR_CPU1_P0   U25   -CH50       A01X+137298Y+109717X0177Y    R180 S1      
327PVDDCR_CPU1_P0   U25   -CH52       A01X+136558Y+109717X0177Y    R180 S1      
327PVDDCR_CPU1_P0   U25   -CH53       A01X+136188Y+109717X0177Y    R180 S1      
327PVDDCR_CPU1_P0   U25   -CK35       A01X+142850Y+110354X0177Y    R180 S1      
327PVDDCR_CPU1_P0   U25   -CK36       A01X+142480Y+110354X0177Y    R180 S1      
327PVDDCR_CPU1_P0   U25   -CK40       A01X+140999Y+110354X0177Y    R180 S1      
327PVDDCR_CPU1_P0   U25   -CK41       A01X+140629Y+110354X0177Y    R180 S1      
327PVDDCR_CPU1_P0   U25   -CL29       A01X+144885Y+110673X0177Y    R180 S1      
327PVDDCR_CPU1_P0   U25   -CL30       A01X+144515Y+110673X0177Y    R180 S1      
327PVDDCR_CPU1_P0   U25   -CL32       A01X+143775Y+110673X0177Y    R180 S1      
327PVDDCR_CPU1_P0   U25   -CL33       A01X+143405Y+110673X0177Y    R180 S1      
327PVDDCR_CPU1_P0   U25   -CL43       A01X+140074Y+110673X0177Y    R180 S1      
327PVDDCR_CPU1_P0   U25   -CL44       A01X+139704Y+110673X0177Y    R180 S1      
327PVDDCR_CPU1_P0   U25   -CL46       A01X+138964Y+110673X0177Y    R180 S1      
327PVDDCR_CPU1_P0   U25   -CL47       A01X+138594Y+110673X0177Y    R180 S1      
327PVDDCR_CPU1_P0   U25   -CN35       A01X+142665Y+111311X0177Y    R180 S1      
327PVDDCR_CPU1_P0   U25   -CN36       A01X+142294Y+111311X0177Y    R180 S1      
327PVDDCR_CPU1_P0   U25   -CN40       A01X+141184Y+111311X0177Y    R180 S1      
327PVDDCR_CPU1_P0   U25   -CN41       A01X+140814Y+111311X0177Y    R180 S1      
327PVDDCR_CPU1_P0   U25   -CP23       A01X+147290Y+111630X0177Y    R180 S1      
327PVDDCR_CPU1_P0   U25   -CP24       A01X+146920Y+111630X0177Y    R180 S1      
327PVDDCR_CPU1_P0   U25   -CP26       A01X+146180Y+111630X0177Y    R180 S1      
327PVDDCR_CPU1_P0   U25   -CP27       A01X+145810Y+111630X0177Y    R180 S1      
327PVDDCR_CPU1_P0   U25   -CP29       A01X+145070Y+111630X0177Y    R180 S1      
327PVDDCR_CPU1_P0   U25   -CP30       A01X+144700Y+111630X0177Y    R180 S1      
327PVDDCR_CPU1_P0   U25   -CP32       A01X+143960Y+111630X0177Y    R180 S1      
327PVDDCR_CPU1_P0   U25   -CP33       A01X+143590Y+111630X0177Y    R180 S1      
327PVDDCR_CPU1_P0   U25   -CP43       A01X+139889Y+111630X0177Y    R180 S1      
327PVDDCR_CPU1_P0   U25   -CP44       A01X+139519Y+111630X0177Y    R180 S1      
327PVDDCR_CPU1_P0   U25   -CP46       A01X+138779Y+111630X0177Y    R180 S1      
327PVDDCR_CPU1_P0   U25   -CP47       A01X+138409Y+111630X0177Y    R180 S1      
327PVDDCR_CPU1_P0   U25   -CP49       A01X+137668Y+111630X0177Y    R180 S1      
327PVDDCR_CPU1_P0   U25   -CP50       A01X+137298Y+111630X0177Y    R180 S1      
327PVDDCR_CPU1_P0   U25   -CP52       A01X+136558Y+111630X0177Y    R180 S1      
327PVDDCR_CPU1_P0   U25   -CP53       A01X+136188Y+111630X0177Y    R180 S1      
327PVDDCR_CPU1_P0   U25   -CU35       A01X+142665Y+112587X0177Y    R180 S1      
327PVDDCR_CPU1_P0   U25   -CU36       A01X+142294Y+112587X0177Y    R180 S1      
327PVDDCR_CPU1_P0   U25   -CU40       A01X+141184Y+112587X0177Y    R180 S1      
327PVDDCR_CPU1_P0   U25   -CU41       A01X+140814Y+112587X0177Y    R180 S1      
327PVDDCR_CPU1_P0   U25   -CV23       A01X+147290Y+112906X0177Y    R180 S1      
327PVDDCR_CPU1_P0   U25   -CV24       A01X+146920Y+112906X0177Y    R180 S1      
327PVDDCR_CPU1_P0   U25   -CV26       A01X+146180Y+112906X0177Y    R180 S1      
327PVDDCR_CPU1_P0   U25   -CV27       A01X+145810Y+112906X0177Y    R180 S1      
327PVDDCR_CPU1_P0   U25   -CV30       A01X+144700Y+112906X0177Y    R180 S1      
327PVDDCR_CPU1_P0   U25   -CV32       A01X+143960Y+112906X0177Y    R180 S1      
327PVDDCR_CPU1_P0   U25   -CV33       A01X+143590Y+112906X0177Y    R180 S1      
327PVDDCR_CPU1_P0   U25   -CV43       A01X+139889Y+112906X0177Y    R180 S1      
327PVDDCR_CPU1_P0   U25   -CV44       A01X+139519Y+112906X0177Y    R180 S1      
327PVDDCR_CPU1_P0   U25   -CV46       A01X+138779Y+112906X0177Y    R180 S1      
327PVDDCR_CPU1_P0   U25   -CV47       A01X+138409Y+112906X0177Y    R180 S1      
327PVDDCR_CPU1_P0   U25   -CV49       A01X+137668Y+112906X0177Y    R180 S1      
327PVDDCR_CPU1_P0   U25   -CV50       A01X+137298Y+112906X0177Y    R180 S1      
327PVDDCR_CPU1_P0   U25   -CV52       A01X+136558Y+112906X0177Y    R180 S1      
327PVDDCR_CPU1_P0   U25   -CV53       A01X+136188Y+112906X0177Y    R180 S1      
327PVDDCR_CPU1_P0   U25   -DA35       A01X+142665Y+113862X0177Y    R180 S1      
327PVDDCR_CPU1_P0   U25   -DA36       A01X+142294Y+113862X0177Y    R180 S1      
327PVDDCR_CPU1_P0   U25   -DA40       A01X+141184Y+113862X0177Y    R180 S1      
327PVDDCR_CPU1_P0   U25   -DA41       A01X+140814Y+113862X0177Y    R180 S1      
327PVDDCR_CPU1_P0   U25   -DB23       A01X+147290Y+114181X0177Y    R180 S1      
327PVDDCR_CPU1_P0   U25   -DB24       A01X+146920Y+114181X0177Y    R180 S1      
327PVDDCR_CPU1_P0   U25   -DB26       A01X+146180Y+114181X0177Y    R180 S1      
327PVDDCR_CPU1_P0   U25   -DB27       A01X+145810Y+114181X0177Y    R180 S1      
327PVDDCR_CPU1_P0   U25   -DB29       A01X+145070Y+114181X0177Y    R180 S1      
327PVDDCR_CPU1_P0   U25   -DB30       A01X+144700Y+114181X0177Y    R180 S1      
327PVDDCR_CPU1_P0   U25   -DB32       A01X+143960Y+114181X0177Y    R180 S1      
327PVDDCR_CPU1_P0   U25   -DB33       A01X+143590Y+114181X0177Y    R180 S1      
327PVDDCR_CPU1_P0   U25   -DB43       A01X+139889Y+114181X0177Y    R180 S1      
327PVDDCR_CPU1_P0   U25   -DB44       A01X+139519Y+114181X0177Y    R180 S1      
327PVDDCR_CPU1_P0   U25   -DB46       A01X+138779Y+114181X0177Y    R180 S1      
327PVDDCR_CPU1_P0   U25   -DB47       A01X+138409Y+114181X0177Y    R180 S1      
327PVDDCR_CPU1_P0   U25   -DB49       A01X+137668Y+114181X0177Y    R180 S1      
327PVDDCR_CPU1_P0   U25   -DB50       A01X+137298Y+114181X0177Y    R180 S1      
327PVDDCR_CPU1_P0   U25   -DB52       A01X+136558Y+114181X0177Y    R180 S1      
327PVDDCR_CPU1_P0   U25   -DB53       A01X+136188Y+114181X0177Y    R180 S1      
327PVDDCR_CPU1_P0   U25   -DC35       A01X+142665Y+114500X0177Y    R180 S1      
327PVDDCR_CPU1_P0   U25   -DC36       A01X+142294Y+114500X0177Y    R180 S1      
327PVDDCR_CPU1_P0   U25   -DC40       A01X+141184Y+114500X0177Y    R180 S1      
327PVDDCR_CPU1_P0   U25   -DC41       A01X+140814Y+114500X0177Y    R180 S1      
327PVDDCR_CPU1_P0   U25   -DD22       A01X+147661Y+114819X0177Y    R180 S1      
327PVDDCR_CPU1_P0   U25   -DD25       A01X+146550Y+114819X0177Y    R180 S1      
327PVDDCR_CPU1_P0   U25   -DD28       A01X+145440Y+114819X0177Y    R180 S1      
327PVDDCR_CPU1_P0   U25   -DD31       A01X+144330Y+114819X0177Y    R180 S1      
327PVDDCR_CPU1_P0   U25   -DD34       A01X+143220Y+114819X0177Y    R180 S1      
327PVDDCR_CPU1_P0   U25   -DD42       A01X+140259Y+114819X0177Y    R180 S1      
327PVDDCR_CPU1_P0   U25   -DD45       A01X+139149Y+114819X0177Y    R180 S1      
327PVDDCR_CPU1_P0   U25   -DD48       A01X+138039Y+114819X0177Y    R180 S1      
327PVDDCR_CPU1_P0   U25   -DD51       A01X+136928Y+114819X0177Y    R180 S1      
327PVDDCR_CPU1_P0   U25   -DD54       A01X+135818Y+114819X0177Y    R180 S1      
327PVDDCR_CPU1_P0   U25   -DE22       A01X+147476Y+115138X0177Y    R180 S1      
327PVDDCR_CPU1_P0   U25   -DE25       A01X+146365Y+115138X0177Y    R180 S1      
327PVDDCR_CPU1_P0   U25   -DE28       A01X+145255Y+115138X0177Y    R180 S1      
327PVDDCR_CPU1_P0   U25   -DE31       A01X+144145Y+115138X0177Y    R180 S1      
327PVDDCR_CPU1_P0   U25   -DE34       A01X+143035Y+115138X0177Y    R180 S1      
327PVDDCR_CPU1_P0   U25   -DE35       A01X+142665Y+115138X0177Y    R180 S1      
327PVDDCR_CPU1_P0   U25   -DE41       A01X+140814Y+115138X0177Y    R180 S1      
327PVDDCR_CPU1_P0   U25   -DE42       A01X+140444Y+115138X0177Y    R180 S1      
327PVDDCR_CPU1_P0   U25   -DE45       A01X+139334Y+115138X0177Y    R180 S1      
327PVDDCR_CPU1_P0   U25   -DE48       A01X+138224Y+115138X0177Y    R180 S1      
327PVDDCR_CPU1_P0   U25   -DE51       A01X+137113Y+115138X0177Y    R180 S1      
327PVDDCR_CPU1_P0   U25   -DE54       A01X+136003Y+115138X0177Y    R180 S1      
327PVDDCR_CPU1_P0   U25   -DG19       A01X+148586Y+115776X0177Y    R180 S1      
327PVDDCR_CPU1_P0   U25   -DG57       A01X+134893Y+115776X0177Y    R180 S1      
327PVDDCR_CPU1_P0   U25   -DH19       A01X+148771Y+116094X0177Y    R180 S1      
327PVDDCR_CPU1_P0   U25   -DH20       A01X+148401Y+116094X0177Y    R180 S1      
327PVDDCR_CPU1_P0   U25   -DH22       A01X+147661Y+116094X0177Y    R180 S1      
327PVDDCR_CPU1_P0   U25   -DH23       A01X+147290Y+116094X0177Y    R180 S1      
327PVDDCR_CPU1_P0   U25   -DH25       A01X+146550Y+116094X0177Y    R180 S1      
327PVDDCR_CPU1_P0   U25   -DH26       A01X+146180Y+116094X0177Y    R180 S1      
327PVDDCR_CPU1_P0   U25   -DH28       A01X+145440Y+116094X0177Y    R180 S1      
327PVDDCR_CPU1_P0   U25   -DH29       A01X+145070Y+116094X0177Y    R180 S1      
327PVDDCR_CPU1_P0   U25   -DH31       A01X+144330Y+116094X0177Y    R180 S1      
327PVDDCR_CPU1_P0   U25   -DH32       A01X+143960Y+116094X0177Y    R180 S1      
327PVDDCR_CPU1_P0   U25   -DH34       A01X+143220Y+116094X0177Y    R180 S1      
327PVDDCR_CPU1_P0   U25   -DH35       A01X+142850Y+116094X0177Y    R180 S1      
327PVDDCR_CPU1_P0   U25   -DH41       A01X+140629Y+116094X0177Y    R180 S1      
327PVDDCR_CPU1_P0   U25   -DH42       A01X+140259Y+116094X0177Y    R180 S1      
327PVDDCR_CPU1_P0   U25   -DH44       A01X+139519Y+116094X0177Y    R180 S1      
327PVDDCR_CPU1_P0   U25   -DH45       A01X+139149Y+116094X0177Y    R180 S1      
327PVDDCR_CPU1_P0   U25   -DH47       A01X+138409Y+116094X0177Y    R180 S1      
327PVDDCR_CPU1_P0   U25   -DH48       A01X+138039Y+116094X0177Y    R180 S1      
327PVDDCR_CPU1_P0   U25   -DH50       A01X+137298Y+116094X0177Y    R180 S1      
327PVDDCR_CPU1_P0   U25   -DH51       A01X+136928Y+116094X0177Y    R180 S1      
327PVDDCR_CPU1_P0   U25   -DH53       A01X+136188Y+116094X0177Y    R180 S1      
327PVDDCR_CPU1_P0   U25   -DH54       A01X+135818Y+116094X0177Y    R180 S1      
327PVDDCR_CPU1_P0   U25   -DH56       A01X+135078Y+116094X0177Y    R180 S1      
327PVDDCR_CPU1_P0   U25   -DH57       A01X+134708Y+116094X0177Y    R180 S1      
317PVDDCR_CPU1_P0   VIA   -    MD0100PA00X+122120Y+131786X0200Y         S0      
317PVDDCR_CPU1_P0   VIA   -    MD0100PA00X+122370Y+131786X0200Y         S0      
317PVDDCR_CPU1_P0   VIA   -    MD0100PA00X+121040Y+131786X0200Y         S0      
317PVDDCR_CPU1_P0   VIA   -    MD0100PA00X+120790Y+131786X0200Y         S0      
317PVDDCR_CPU1_P0   VIA   -    MD0100PA00X+120540Y+131536X0200Y         S0      
317PVDDCR_CPU1_P0   VIA   -    MD0100PA00X+120233Y+137991X0200Y    R180 S0      
327PVDDCR_CPU1_P0   PR91  -2          A18X+120092Y+137709X0198Y0197R270 S2      
317PVDDCR_CPU1_P0   VIA   -    MD0100PA00X+120540Y+131786X0200Y         S0      
317PVDDCR_CPU1_P0   VIA   -    MD0100PA00X+122120Y+130536X0200Y         S0      
317PVDDCR_CPU1_P0   VIA   -    MD0100PA00X+122120Y+130036X0200Y         S0      
317PVDDCR_CPU1_P0   VIA   -    MD0100PA00X+122120Y+130286X0200Y         S0      
317PVDDCR_CPU1_P0   VIA   -    MD0100PA00X+122370Y+130536X0200Y         S0      
317PVDDCR_CPU1_P0   VIA   -    MD0100PA00X+122370Y+130286X0200Y         S0      
317PVDDCR_CPU1_P0   VIA   -    MD0100PA00X+122370Y+130036X0200Y         S0      
317PVDDCR_CPU1_P0   VIA   -    MD0100PA00X+120540Y+131286X0200Y         S0      
317PVDDCR_CPU1_P0   VIA   -    MD0100PA00X+120540Y+131036X0200Y         S0      
317PVDDCR_CPU1_P0   VIA   -    MD0100PA00X+120540Y+130786X0200Y         S0      
317PVDDCR_CPU1_P0   VIA   -    MD0100PA00X+120540Y+130536X0200Y         S0      
317PVDDCR_CPU1_P0   VIA   -    MD0100PA00X+120540Y+130036X0200Y         S0      
317PVDDCR_CPU1_P0   VIA   -    MD0100PA00X+120540Y+130286X0200Y         S0      
317PVDDCR_CPU1_P0   VIA   -    MD0100PA00X+121040Y+131536X0200Y         S0      
317PVDDCR_CPU1_P0   VIA   -    MD0100PA00X+120790Y+131536X0200Y         S0      
317PVDDCR_CPU1_P0   VIA   -    MD0100PA00X+121040Y+130786X0200Y         S0      
317PVDDCR_CPU1_P0   VIA   -    MD0100PA00X+121040Y+131036X0200Y         S0      
317PVDDCR_CPU1_P0   VIA   -    MD0100PA00X+121040Y+131286X0200Y         S0      
317PVDDCR_CPU1_P0   VIA   -    MD0100PA00X+120790Y+131286X0200Y         S0      
317PVDDCR_CPU1_P0   VIA   -    MD0100PA00X+120790Y+131036X0200Y         S0      
317PVDDCR_CPU1_P0   VIA   -    MD0100PA00X+120790Y+130786X0200Y         S0      
317PVDDCR_CPU1_P0   VIA   -    MD0100PA00X+122370Y+131536X0200Y         S0      
317PVDDCR_CPU1_P0   VIA   -    MD0100PA00X+122120Y+131536X0200Y         S0      
317PVDDCR_CPU1_P0   VIA   -    MD0100PA00X+122370Y+131286X0200Y         S0      
317PVDDCR_CPU1_P0   VIA   -    MD0100PA00X+122370Y+131036X0200Y         S0      
317PVDDCR_CPU1_P0   VIA   -    MD0100PA00X+122370Y+130786X0200Y         S0      
317PVDDCR_CPU1_P0   VIA   -    MD0100PA00X+122120Y+130786X0200Y         S0      
317PVDDCR_CPU1_P0   VIA   -    MD0100PA00X+122120Y+131036X0200Y         S0      
317PVDDCR_CPU1_P0   VIA   -    MD0100PA00X+122120Y+131286X0200Y         S0      
327PVDDCR_CPU1_P0   PL13  -4   M      A01X+121580Y+131161X0950Y1780R270 S1      
317PVDDCR_CPU1_P0   VIA   -    MD0100PA00X+121040Y+130536X0200Y         S0      
317PVDDCR_CPU1_P0   VIA   -    MD0100PA00X+120790Y+130536X0200Y         S0      
317PVDDCR_CPU1_P0   VIA   -    MD0100PA00X+121040Y+130036X0200Y         S0      
317PVDDCR_CPU1_P0   VIA   -    MD0100PA00X+121040Y+130286X0200Y         S0      
317PVDDCR_CPU1_P0   VIA   -    MD0100PA00X+120790Y+130286X0200Y         S0      
317PVDDCR_CPU1_P0   VIA   -    MD0100PA00X+120790Y+130036X0200Y         S0      
317PVDDCR_CPU1_P0   VIA   -    MD0100PA00X+139288Y+129124X0200Y         S0      
317PVDDCR_CPU1_P0   VIA   -    MD0100PA00X+139538Y+129124X0200Y         S0      
317PVDDCR_CPU1_P0   VIA   -    MD0100PA00X+139538Y+128624X0200Y         S0      
317PVDDCR_CPU1_P0   VIA   -    MD0100PA00X+139538Y+128874X0200Y         S0      
317PVDDCR_CPU1_P0   VIA   -    MD0100PA00X+139038Y+129124X0200Y         S0      
317PVDDCR_CPU1_P0   VIA   -    MD0100PA00X+137150Y+135321X0200Y    R180 S0      
317PVDDCR_CPU1_P0   VIA   -    MD0100PA00X+137458Y+129124X0200Y         S0      
327PVDDCR_CPU1_P0   PR421 -2          A18X+137010Y+135039X0198Y0197R270 S2      
317PVDDCR_CPU1_P0   VIA   -    MD0100PA00X+137458Y+128624X0200Y         S0      
317PVDDCR_CPU1_P0   VIA   -    MD0100PA00X+137458Y+128874X0200Y         S0      
317PVDDCR_CPU1_P0   VIA   -    MD0100PA00X+137708Y+129124X0200Y         S0      
317PVDDCR_CPU1_P0   VIA   -    MD0100PA00X+137958Y+129124X0200Y         S0      
317PVDDCR_CPU1_P0   VIA   -    MD0100PA00X+139288Y+127864X0200Y         S0      
317PVDDCR_CPU1_P0   VIA   -    MD0100PA00X+139288Y+127614X0200Y         S0      
317PVDDCR_CPU1_P0   VIA   -    MD0100PA00X+139538Y+127864X0200Y         S0      
317PVDDCR_CPU1_P0   VIA   -    MD0100PA00X+139538Y+127614X0200Y         S0      
317PVDDCR_CPU1_P0   VIA   -    MD0100PA00X+139538Y+128374X0200Y         S0      
317PVDDCR_CPU1_P0   VIA   -    MD0100PA00X+139538Y+128124X0200Y         S0      
317PVDDCR_CPU1_P0   VIA   -    MD0100PA00X+139538Y+127114X0200Y         S0      
317PVDDCR_CPU1_P0   VIA   -    MD0100PA00X+139288Y+127114X0200Y         S0      
317PVDDCR_CPU1_P0   VIA   -    MD0100PA00X+139538Y+127364X0200Y         S0      
317PVDDCR_CPU1_P0   VIA   -    MD0100PA00X+139288Y+127364X0200Y         S0      
317PVDDCR_CPU1_P0   VIA   -    MD0100PA00X+139038Y+127864X0200Y         S0      
317PVDDCR_CPU1_P0   VIA   -    MD0100PA00X+139038Y+127614X0200Y         S0      
317PVDDCR_CPU1_P0   VIA   -    MD0100PA00X+139038Y+127114X0200Y         S0      
317PVDDCR_CPU1_P0   VIA   -    MD0100PA00X+139038Y+127364X0200Y         S0      
317PVDDCR_CPU1_P0   VIA   -    MD0100PA00X+137948Y+127614X0200Y         S0      
317PVDDCR_CPU1_P0   VIA   -    MD0100PA00X+137948Y+127864X0200Y         S0      
317PVDDCR_CPU1_P0   VIA   -    MD0100PA00X+137698Y+127864X0200Y         S0      
317PVDDCR_CPU1_P0   VIA   -    MD0100PA00X+137698Y+127614X0200Y         S0      
317PVDDCR_CPU1_P0   VIA   -    MD0100PA00X+137708Y+128866X0200Y         S0      
317PVDDCR_CPU1_P0   VIA   -    MD0100PA00X+137958Y+128116X0200Y         S0      
317PVDDCR_CPU1_P0   VIA   -    MD0100PA00X+137958Y+128366X0200Y         S0      
317PVDDCR_CPU1_P0   VIA   -    MD0100PA00X+137708Y+128366X0200Y         S0      
317PVDDCR_CPU1_P0   VIA   -    MD0100PA00X+137708Y+128116X0200Y         S0      
317PVDDCR_CPU1_P0   VIA   -    MD0100PA00X+137958Y+128616X0200Y         S0      
317PVDDCR_CPU1_P0   VIA   -    MD0100PA00X+137708Y+128616X0200Y         S0      
317PVDDCR_CPU1_P0   VIA   -    MD0100PA00X+137958Y+128866X0200Y         S0      
317PVDDCR_CPU1_P0   VIA   -    MD0100PA00X+139038Y+128616X0200Y         S0      
317PVDDCR_CPU1_P0   VIA   -    MD0100PA00X+139038Y+128866X0200Y         S0      
317PVDDCR_CPU1_P0   VIA   -    MD0100PA00X+139288Y+128616X0200Y         S0      
317PVDDCR_CPU1_P0   VIA   -    MD0100PA00X+139288Y+128866X0200Y         S0      
317PVDDCR_CPU1_P0   VIA   -    MD0100PA00X+139038Y+128366X0200Y         S0      
317PVDDCR_CPU1_P0   VIA   -    MD0100PA00X+139038Y+128116X0200Y         S0      
317PVDDCR_CPU1_P0   VIA   -    MD0100PA00X+139288Y+128116X0200Y         S0      
317PVDDCR_CPU1_P0   VIA   -    MD0100PA00X+139288Y+128366X0200Y         S0      
327PVDDCR_CPU1_P0   PL7   -4   M      A01X+138498Y+128491X0950Y1780R270 S1      
317PVDDCR_CPU1_P0   VIA   -    MD0100PA00X+137948Y+127114X0200Y         S0      
317PVDDCR_CPU1_P0   VIA   -    MD0100PA00X+137948Y+127364X0200Y         S0      
317PVDDCR_CPU1_P0   VIA   -    MD0100PA00X+137698Y+127114X0200Y         S0      
317PVDDCR_CPU1_P0   VIA   -    MD0100PA00X+137698Y+127364X0200Y         S0      
317PVDDCR_CPU1_P0   VIA   -    MD0100PA00X+137448Y+127864X0200Y         S0      
317PVDDCR_CPU1_P0   VIA   -    MD0100PA00X+137448Y+127614X0200Y         S0      
317PVDDCR_CPU1_P0   VIA   -    MD0100PA00X+137458Y+128124X0200Y         S0      
317PVDDCR_CPU1_P0   VIA   -    MD0100PA00X+137458Y+128374X0200Y         S0      
317PVDDCR_CPU1_P0   VIA   -    MD0100PA00X+137448Y+127114X0200Y         S0      
317PVDDCR_CPU1_P0   VIA   -    MD0100PA00X+137448Y+127364X0200Y         S0      
317PVDDCR_CPU1_P0   VIA   -    MD0100PA00X+135999Y+127177X0200Y         S0      
317PVDDCR_CPU1_P0   VIA   -    MD0100PA00X+136249Y+127177X0200Y         S0      
317PVDDCR_CPU1_P0   VIA   -    MD0100PA00X+134419Y+127177X0200Y         S0      
317PVDDCR_CPU1_P0   VIA   -    MD0100PA00X+134669Y+127177X0200Y         S0      
317PVDDCR_CPU1_P0   VIA   -    MD0100PA00X+135749Y+127177X0200Y         S0      
317PVDDCR_CPU1_P0   VIA   -    MD0100PA00X+132999Y+127167X0200Y         S0      
317PVDDCR_CPU1_P0   VIA   -    MD0100PA00X+134169Y+127177X0200Y         S0      
317PVDDCR_CPU1_P0   VIA   -    MD0100PA00X+133892Y+133388X0200Y    R180 S0      
327PVDDCR_CPU1_P0   PR96  -2          A18X+133752Y+133106X0198Y0197R270 S2      
317PVDDCR_CPU1_P0   VIA   -    MD0100PA00X+132499Y+127167X0200Y         S0      
317PVDDCR_CPU1_P0   VIA   -    MD0100PA00X+131409Y+127167X0200Y         S0      
317PVDDCR_CPU1_P0   VIA   -    MD0100PA00X+132749Y+127167X0200Y         S0      
317PVDDCR_CPU1_P0   VIA   -    MD0100PA00X+131159Y+127167X0200Y         S0      
317PVDDCR_CPU1_P0   VIA   -    MD0100PA00X+130909Y+127167X0200Y         S0      
317PVDDCR_CPU1_P0   VIA   -    MD0100PA00X+130612Y+133368X0200Y    R180 S0      
327PVDDCR_CPU1_P0   PR84  -2          A18X+130472Y+133086X0198Y0197R270 S2      
317PVDDCR_CPU1_P0   VIA   -    MD0100PA00X+129450Y+127167X0200Y         S0      
317PVDDCR_CPU1_P0   VIA   -    MD0100PA00X+129200Y+127167X0200Y         S0      
317PVDDCR_CPU1_P0   VIA   -    MD0100PA00X+129700Y+127167X0200Y         S0      
317PVDDCR_CPU1_P0   VIA   -    MD0100PA00X+127322Y+133374X0200Y    R180 S0      
317PVDDCR_CPU1_P0   VIA   -    MD0100PA00X+127620Y+127167X0200Y         S0      
327PVDDCR_CPU1_P0   PR83  -2          A18X+127181Y+133092X0198Y0197R270 S2      
317PVDDCR_CPU1_P0   VIA   -    MD0100PA00X+127870Y+127167X0200Y         S0      
317PVDDCR_CPU1_P0   VIA   -    MD0100PA00X+128120Y+127167X0200Y         S0      
317PVDDCR_CPU1_P0   VIA   -    MD0100PA00X+126161Y+127175X0200Y         S0      
317PVDDCR_CPU1_P0   VIA   -    MD0100PA00X+125911Y+127175X0200Y         S0      
317PVDDCR_CPU1_P0   VIA   -    MD0100PA00X+126411Y+127175X0200Y         S0      
317PVDDCR_CPU1_P0   VIA   -    MD0100PA00X+124032Y+133377X0200Y    R180 S0      
317PVDDCR_CPU1_P0   VIA   -    MD0100PA00X+124331Y+127175X0200Y         S0      
327PVDDCR_CPU1_P0   PR92  -2          A18X+123892Y+133095X0198Y0197R270 S2      
317PVDDCR_CPU1_P0   VIA   -    MD0100PA00X+124581Y+127175X0200Y         S0      
317PVDDCR_CPU1_P0   VIA   -    MD0100PA00X+124831Y+127175X0200Y         S0      
317PVDDCR_CPU1_P0   VIA   -    MD0100PA00X+139538Y+126864X0200Y         S0      
317PVDDCR_CPU1_P0   VIA   -    MD0100PA00X+139288Y+126864X0200Y         S0      
317PVDDCR_CPU1_P0   VIA   -    MD0100PA00X+139038Y+126864X0200Y         S0      
317PVDDCR_CPU1_P0   VIA   -    MD0100PA00X+137948Y+126864X0200Y         S0      
317PVDDCR_CPU1_P0   VIA   -    MD0100PA00X+137698Y+126864X0200Y         S0      
317PVDDCR_CPU1_P0   VIA   -    MD0100PA00X+137448Y+126864X0200Y         S0      
317PVDDCR_CPU1_P0   VIA   -    MD0100PA00X+137948Y+126614X0200Y         S0      
317PVDDCR_CPU1_P0   VIA   -    MD0100PA00X+137698Y+126614X0200Y         S0      
317PVDDCR_CPU1_P0   VIA   -    MD0100PA00X+137448Y+126614X0200Y         S0      
317PVDDCR_CPU1_P0   VIA   -    MD0100PA00X+135999Y+125917X0200Y         S0      
317PVDDCR_CPU1_P0   VIA   -    MD0100PA00X+135999Y+125667X0200Y         S0      
317PVDDCR_CPU1_P0   VIA   -    MD0100PA00X+136249Y+125917X0200Y         S0      
317PVDDCR_CPU1_P0   VIA   -    MD0100PA00X+136249Y+125667X0200Y         S0      
317PVDDCR_CPU1_P0   VIA   -    MD0100PA00X+136249Y+126427X0200Y         S0      
317PVDDCR_CPU1_P0   VIA   -    MD0100PA00X+136249Y+126677X0200Y         S0      
317PVDDCR_CPU1_P0   VIA   -    MD0100PA00X+136249Y+126177X0200Y         S0      
317PVDDCR_CPU1_P0   VIA   -    MD0100PA00X+136249Y+126927X0200Y         S0      
317PVDDCR_CPU1_P0   VIA   -    MD0100PA00X+134659Y+125667X0200Y         S0      
317PVDDCR_CPU1_P0   VIA   -    MD0100PA00X+134659Y+125917X0200Y         S0      
317PVDDCR_CPU1_P0   VIA   -    MD0100PA00X+134409Y+125917X0200Y         S0      
317PVDDCR_CPU1_P0   VIA   -    MD0100PA00X+134409Y+125667X0200Y         S0      
317PVDDCR_CPU1_P0   VIA   -    MD0100PA00X+135749Y+125917X0200Y         S0      
317PVDDCR_CPU1_P0   VIA   -    MD0100PA00X+135749Y+125667X0200Y         S0      
317PVDDCR_CPU1_P0   VIA   -    MD0100PA00X+135749Y+126669X0200Y         S0      
317PVDDCR_CPU1_P0   VIA   -    MD0100PA00X+135749Y+126419X0200Y         S0      
317PVDDCR_CPU1_P0   VIA   -    MD0100PA00X+135749Y+126169X0200Y         S0      
317PVDDCR_CPU1_P0   VIA   -    MD0100PA00X+135749Y+126919X0200Y         S0      
317PVDDCR_CPU1_P0   VIA   -    MD0100PA00X+134669Y+126169X0200Y         S0      
317PVDDCR_CPU1_P0   VIA   -    MD0100PA00X+134669Y+126419X0200Y         S0      
317PVDDCR_CPU1_P0   VIA   -    MD0100PA00X+134669Y+126669X0200Y         S0      
317PVDDCR_CPU1_P0   VIA   -    MD0100PA00X+134419Y+126669X0200Y         S0      
317PVDDCR_CPU1_P0   VIA   -    MD0100PA00X+134419Y+126419X0200Y         S0      
317PVDDCR_CPU1_P0   VIA   -    MD0100PA00X+134419Y+126169X0200Y         S0      
317PVDDCR_CPU1_P0   VIA   -    MD0100PA00X+134669Y+126919X0200Y         S0      
317PVDDCR_CPU1_P0   VIA   -    MD0100PA00X+134419Y+126919X0200Y         S0      
317PVDDCR_CPU1_P0   VIA   -    MD0100PA00X+135999Y+126169X0200Y         S0      
317PVDDCR_CPU1_P0   VIA   -    MD0100PA00X+135999Y+126419X0200Y         S0      
317PVDDCR_CPU1_P0   VIA   -    MD0100PA00X+135999Y+126669X0200Y         S0      
317PVDDCR_CPU1_P0   VIA   -    MD0100PA00X+135999Y+126919X0200Y         S0      
327PVDDCR_CPU1_P0   PL15  -4   M      A01X+135209Y+126544X0950Y1780R270 S1      
317PVDDCR_CPU1_P0   VIA   -    MD0100PA00X+134159Y+125917X0200Y         S0      
317PVDDCR_CPU1_P0   VIA   -    MD0100PA00X+134159Y+125667X0200Y         S0      
317PVDDCR_CPU1_P0   VIA   -    MD0100PA00X+132999Y+126911X0200Y         S0      
317PVDDCR_CPU1_P0   VIA   -    MD0100PA00X+132999Y+126161X0200Y         S0      
317PVDDCR_CPU1_P0   VIA   -    MD0100PA00X+132999Y+126411X0200Y         S0      
317PVDDCR_CPU1_P0   VIA   -    MD0100PA00X+132999Y+126661X0200Y         S0      
317PVDDCR_CPU1_P0   VIA   -    MD0100PA00X+132999Y+125661X0200Y         S0      
317PVDDCR_CPU1_P0   VIA   -    MD0100PA00X+132999Y+125911X0200Y         S0      
317PVDDCR_CPU1_P0   VIA   -    MD0100PA00X+134169Y+126177X0200Y         S0      
317PVDDCR_CPU1_P0   VIA   -    MD0100PA00X+134169Y+126677X0200Y         S0      
317PVDDCR_CPU1_P0   VIA   -    MD0100PA00X+134169Y+126427X0200Y         S0      
317PVDDCR_CPU1_P0   VIA   -    MD0100PA00X+134169Y+126927X0200Y         S0      
317PVDDCR_CPU1_P0   VIA   -    MD0100PA00X+132499Y+125661X0200Y         S0      
317PVDDCR_CPU1_P0   VIA   -    MD0100PA00X+132499Y+125911X0200Y         S0      
317PVDDCR_CPU1_P0   VIA   -    MD0100PA00X+131409Y+125911X0200Y         S0      
317PVDDCR_CPU1_P0   VIA   -    MD0100PA00X+131409Y+125661X0200Y         S0      
317PVDDCR_CPU1_P0   VIA   -    MD0100PA00X+132749Y+125661X0200Y         S0      
317PVDDCR_CPU1_P0   VIA   -    MD0100PA00X+132749Y+125911X0200Y         S0      
317PVDDCR_CPU1_P0   VIA   -    MD0100PA00X+130909Y+125661X0200Y         S0      
317PVDDCR_CPU1_P0   VIA   -    MD0100PA00X+130909Y+125911X0200Y         S0      
317PVDDCR_CPU1_P0   VIA   -    MD0100PA00X+131159Y+125661X0200Y         S0      
317PVDDCR_CPU1_P0   VIA   -    MD0100PA00X+131159Y+125911X0200Y         S0      
317PVDDCR_CPU1_P0   VIA   -    MD0100PA00X+131169Y+126663X0200Y         S0      
317PVDDCR_CPU1_P0   VIA   -    MD0100PA00X+131169Y+126413X0200Y         S0      
317PVDDCR_CPU1_P0   VIA   -    MD0100PA00X+131169Y+126163X0200Y         S0      
317PVDDCR_CPU1_P0   VIA   -    MD0100PA00X+131169Y+126913X0200Y         S0      
317PVDDCR_CPU1_P0   VIA   -    MD0100PA00X+132749Y+126163X0200Y         S0      
317PVDDCR_CPU1_P0   VIA   -    MD0100PA00X+132749Y+126413X0200Y         S0      
317PVDDCR_CPU1_P0   VIA   -    MD0100PA00X+132749Y+126663X0200Y         S0      
317PVDDCR_CPU1_P0   VIA   -    MD0100PA00X+132749Y+126913X0200Y         S0      
317PVDDCR_CPU1_P0   VIA   -    MD0100PA00X+131419Y+126163X0200Y         S0      
317PVDDCR_CPU1_P0   VIA   -    MD0100PA00X+131419Y+126413X0200Y         S0      
317PVDDCR_CPU1_P0   VIA   -    MD0100PA00X+131419Y+126663X0200Y         S0      
317PVDDCR_CPU1_P0   VIA   -    MD0100PA00X+131419Y+126913X0200Y         S0      
317PVDDCR_CPU1_P0   VIA   -    MD0100PA00X+132499Y+126663X0200Y         S0      
317PVDDCR_CPU1_P0   VIA   -    MD0100PA00X+132499Y+126413X0200Y         S0      
317PVDDCR_CPU1_P0   VIA   -    MD0100PA00X+132499Y+126163X0200Y         S0      
317PVDDCR_CPU1_P0   VIA   -    MD0100PA00X+132499Y+126913X0200Y         S0      
327PVDDCR_CPU1_P0   PL10  -4   M      A01X+131959Y+126538X0950Y1780R270 S1      
317PVDDCR_CPU1_P0   VIA   -    MD0100PA00X+130909Y+126417X0200Y         S0      
317PVDDCR_CPU1_P0   VIA   -    MD0100PA00X+130909Y+126167X0200Y         S0      
317PVDDCR_CPU1_P0   VIA   -    MD0100PA00X+130909Y+126667X0200Y         S0      
317PVDDCR_CPU1_P0   VIA   -    MD0100PA00X+130909Y+126917X0200Y         S0      
317PVDDCR_CPU1_P0   VIA   -    MD0100PA00X+129209Y+125911X0200Y         S0      
317PVDDCR_CPU1_P0   VIA   -    MD0100PA00X+129209Y+125661X0200Y         S0      
317PVDDCR_CPU1_P0   VIA   -    MD0100PA00X+129709Y+126661X0200Y         S0      
317PVDDCR_CPU1_P0   VIA   -    MD0100PA00X+129709Y+126411X0200Y         S0      
317PVDDCR_CPU1_P0   VIA   -    MD0100PA00X+129459Y+125911X0200Y         S0      
317PVDDCR_CPU1_P0   VIA   -    MD0100PA00X+129459Y+125661X0200Y         S0      
317PVDDCR_CPU1_P0   VIA   -    MD0100PA00X+129709Y+126161X0200Y         S0      
317PVDDCR_CPU1_P0   VIA   -    MD0100PA00X+129709Y+125911X0200Y         S0      
317PVDDCR_CPU1_P0   VIA   -    MD0100PA00X+129709Y+125661X0200Y         S0      
317PVDDCR_CPU1_P0   VIA   -    MD0100PA00X+129709Y+126911X0200Y         S0      
317PVDDCR_CPU1_P0   VIA   -    MD0100PA00X+128129Y+126163X0200Y         S0      
317PVDDCR_CPU1_P0   VIA   -    MD0100PA00X+128129Y+126413X0200Y         S0      
317PVDDCR_CPU1_P0   VIA   -    MD0100PA00X+128129Y+126663X0200Y         S0      
317PVDDCR_CPU1_P0   VIA   -    MD0100PA00X+127879Y+126663X0200Y         S0      
317PVDDCR_CPU1_P0   VIA   -    MD0100PA00X+127879Y+126413X0200Y         S0      
317PVDDCR_CPU1_P0   VIA   -    MD0100PA00X+127879Y+126163X0200Y         S0      
317PVDDCR_CPU1_P0   VIA   -    MD0100PA00X+128129Y+126913X0200Y         S0      
317PVDDCR_CPU1_P0   VIA   -    MD0100PA00X+127879Y+126913X0200Y         S0      
317PVDDCR_CPU1_P0   VIA   -    MD0100PA00X+129459Y+126163X0200Y         S0      
317PVDDCR_CPU1_P0   VIA   -    MD0100PA00X+129459Y+126413X0200Y         S0      
317PVDDCR_CPU1_P0   VIA   -    MD0100PA00X+129459Y+126663X0200Y         S0      
317PVDDCR_CPU1_P0   VIA   -    MD0100PA00X+129209Y+126663X0200Y         S0      
317PVDDCR_CPU1_P0   VIA   -    MD0100PA00X+129209Y+126413X0200Y         S0      
317PVDDCR_CPU1_P0   VIA   -    MD0100PA00X+129209Y+126163X0200Y         S0      
317PVDDCR_CPU1_P0   VIA   -    MD0100PA00X+129459Y+126913X0200Y         S0      
317PVDDCR_CPU1_P0   VIA   -    MD0100PA00X+129209Y+126913X0200Y         S0      
327PVDDCR_CPU1_P0   PL11  -4   M      A01X+128669Y+126538X0950Y1780R270 S1      
317PVDDCR_CPU1_P0   VIA   -    MD0100PA00X+127869Y+125911X0200Y         S0      
317PVDDCR_CPU1_P0   VIA   -    MD0100PA00X+127869Y+125661X0200Y         S0      
317PVDDCR_CPU1_P0   VIA   -    MD0100PA00X+127619Y+126411X0200Y         S0      
317PVDDCR_CPU1_P0   VIA   -    MD0100PA00X+127619Y+126161X0200Y         S0      
317PVDDCR_CPU1_P0   VIA   -    MD0100PA00X+127619Y+125911X0200Y         S0      
317PVDDCR_CPU1_P0   VIA   -    MD0100PA00X+127619Y+125661X0200Y         S0      
317PVDDCR_CPU1_P0   VIA   -    MD0100PA00X+128119Y+125661X0200Y         S0      
317PVDDCR_CPU1_P0   VIA   -    MD0100PA00X+128119Y+125911X0200Y         S0      
317PVDDCR_CPU1_P0   VIA   -    MD0100PA00X+127619Y+126661X0200Y         S0      
317PVDDCR_CPU1_P0   VIA   -    MD0100PA00X+127619Y+126911X0200Y         S0      
317PVDDCR_CPU1_P0   VIA   -    MD0100PA00X+125919Y+125920X0200Y         S0      
317PVDDCR_CPU1_P0   VIA   -    MD0100PA00X+125919Y+125670X0200Y         S0      
317PVDDCR_CPU1_P0   VIA   -    MD0100PA00X+126419Y+126670X0200Y         S0      
317PVDDCR_CPU1_P0   VIA   -    MD0100PA00X+126419Y+126420X0200Y         S0      
317PVDDCR_CPU1_P0   VIA   -    MD0100PA00X+126169Y+125920X0200Y         S0      
317PVDDCR_CPU1_P0   VIA   -    MD0100PA00X+126169Y+125670X0200Y         S0      
317PVDDCR_CPU1_P0   VIA   -    MD0100PA00X+126419Y+126170X0200Y         S0      
317PVDDCR_CPU1_P0   VIA   -    MD0100PA00X+126419Y+125920X0200Y         S0      
317PVDDCR_CPU1_P0   VIA   -    MD0100PA00X+126419Y+125670X0200Y         S0      
317PVDDCR_CPU1_P0   VIA   -    MD0100PA00X+126419Y+126920X0200Y         S0      
317PVDDCR_CPU1_P0   VIA   -    MD0100PA00X+124839Y+126172X0200Y         S0      
317PVDDCR_CPU1_P0   VIA   -    MD0100PA00X+124839Y+126422X0200Y         S0      
317PVDDCR_CPU1_P0   VIA   -    MD0100PA00X+124839Y+126672X0200Y         S0      
317PVDDCR_CPU1_P0   VIA   -    MD0100PA00X+124589Y+126672X0200Y         S0      
317PVDDCR_CPU1_P0   VIA   -    MD0100PA00X+124589Y+126422X0200Y         S0      
317PVDDCR_CPU1_P0   VIA   -    MD0100PA00X+124589Y+126172X0200Y         S0      
317PVDDCR_CPU1_P0   VIA   -    MD0100PA00X+124839Y+126922X0200Y         S0      
317PVDDCR_CPU1_P0   VIA   -    MD0100PA00X+124589Y+126922X0200Y         S0      
317PVDDCR_CPU1_P0   VIA   -    MD0100PA00X+126169Y+126172X0200Y         S0      
317PVDDCR_CPU1_P0   VIA   -    MD0100PA00X+126169Y+126422X0200Y         S0      
317PVDDCR_CPU1_P0   VIA   -    MD0100PA00X+126169Y+126672X0200Y         S0      
317PVDDCR_CPU1_P0   VIA   -    MD0100PA00X+125919Y+126672X0200Y         S0      
317PVDDCR_CPU1_P0   VIA   -    MD0100PA00X+125919Y+126422X0200Y         S0      
317PVDDCR_CPU1_P0   VIA   -    MD0100PA00X+125919Y+126172X0200Y         S0      
317PVDDCR_CPU1_P0   VIA   -    MD0100PA00X+126169Y+126922X0200Y         S0      
317PVDDCR_CPU1_P0   VIA   -    MD0100PA00X+125919Y+126922X0200Y         S0      
327PVDDCR_CPU1_P0   PL14  -4   M      A01X+125379Y+126546X0950Y1780R270 S1      
317PVDDCR_CPU1_P0   VIA   -    MD0100PA00X+124579Y+125920X0200Y         S0      
317PVDDCR_CPU1_P0   VIA   -    MD0100PA00X+124329Y+126420X0200Y         S0      
317PVDDCR_CPU1_P0   VIA   -    MD0100PA00X+124329Y+126170X0200Y         S0      
317PVDDCR_CPU1_P0   VIA   -    MD0100PA00X+124829Y+125670X0200Y         S0      
317PVDDCR_CPU1_P0   VIA   -    MD0100PA00X+124829Y+125920X0200Y         S0      
317PVDDCR_CPU1_P0   VIA   -    MD0100PA00X+124329Y+126670X0200Y         S0      
317PVDDCR_CPU1_P0   VIA   -    MD0100PA00X+124329Y+126920X0200Y         S0      
317PVDDCR_CPU1_P0   VIA   -    MD0100PA00X+135999Y+124667X0200Y         S0      
317PVDDCR_CPU1_P0   VIA   -    MD0100PA00X+136249Y+124667X0200Y         S0      
317PVDDCR_CPU1_P0   VIA   -    MD0100PA00X+136249Y+125167X0200Y         S0      
317PVDDCR_CPU1_P0   VIA   -    MD0100PA00X+135999Y+125167X0200Y         S0      
317PVDDCR_CPU1_P0   VIA   -    MD0100PA00X+136249Y+124917X0200Y         S0      
317PVDDCR_CPU1_P0   VIA   -    MD0100PA00X+135999Y+124917X0200Y         S0      
317PVDDCR_CPU1_P0   VIA   -    MD0100PA00X+136249Y+125417X0200Y         S0      
317PVDDCR_CPU1_P0   VIA   -    MD0100PA00X+135999Y+125417X0200Y         S0      
317PVDDCR_CPU1_P0   VIA   -    MD0100PA00X+134659Y+124667X0200Y         S0      
317PVDDCR_CPU1_P0   VIA   -    MD0100PA00X+134659Y+125167X0200Y         S0      
317PVDDCR_CPU1_P0   VIA   -    MD0100PA00X+134659Y+124917X0200Y         S0      
317PVDDCR_CPU1_P0   VIA   -    MD0100PA00X+134659Y+125417X0200Y         S0      
317PVDDCR_CPU1_P0   VIA   -    MD0100PA00X+134409Y+124667X0200Y         S0      
317PVDDCR_CPU1_P0   VIA   -    MD0100PA00X+134409Y+124917X0200Y         S0      
317PVDDCR_CPU1_P0   VIA   -    MD0100PA00X+134409Y+125167X0200Y         S0      
317PVDDCR_CPU1_P0   VIA   -    MD0100PA00X+134409Y+125417X0200Y         S0      
317PVDDCR_CPU1_P0   VIA   -    MD0100PA00X+135749Y+124667X0200Y         S0      
317PVDDCR_CPU1_P0   VIA   -    MD0100PA00X+135749Y+125167X0200Y         S0      
317PVDDCR_CPU1_P0   VIA   -    MD0100PA00X+135749Y+124917X0200Y         S0      
317PVDDCR_CPU1_P0   VIA   -    MD0100PA00X+135749Y+125417X0200Y         S0      
317PVDDCR_CPU1_P0   VIA   -    MD0100PA00X+134159Y+124667X0200Y         S0      
317PVDDCR_CPU1_P0   VIA   -    MD0100PA00X+134159Y+124917X0200Y         S0      
317PVDDCR_CPU1_P0   VIA   -    MD0100PA00X+134159Y+125167X0200Y         S0      
317PVDDCR_CPU1_P0   VIA   -    MD0100PA00X+134159Y+125417X0200Y         S0      
317PVDDCR_CPU1_P0   VIA   -    MD0100PA00X+132999Y+125411X0200Y         S0      
317PVDDCR_CPU1_P0   VIA   -    MD0100PA00X+132999Y+124911X0200Y         S0      
317PVDDCR_CPU1_P0   VIA   -    MD0100PA00X+132999Y+125161X0200Y         S0      
317PVDDCR_CPU1_P0   VIA   -    MD0100PA00X+132999Y+124661X0200Y         S0      
317PVDDCR_CPU1_P0   VIA   -    MD0100PA00X+132499Y+125411X0200Y         S0      
317PVDDCR_CPU1_P0   VIA   -    MD0100PA00X+132499Y+124911X0200Y         S0      
317PVDDCR_CPU1_P0   VIA   -    MD0100PA00X+132499Y+125161X0200Y         S0      
317PVDDCR_CPU1_P0   VIA   -    MD0100PA00X+132499Y+124661X0200Y         S0      
317PVDDCR_CPU1_P0   VIA   -    MD0100PA00X+131409Y+125411X0200Y         S0      
317PVDDCR_CPU1_P0   VIA   -    MD0100PA00X+131409Y+124911X0200Y         S0      
317PVDDCR_CPU1_P0   VIA   -    MD0100PA00X+131409Y+125161X0200Y         S0      
317PVDDCR_CPU1_P0   VIA   -    MD0100PA00X+131409Y+124661X0200Y         S0      
317PVDDCR_CPU1_P0   VIA   -    MD0100PA00X+132749Y+125411X0200Y         S0      
317PVDDCR_CPU1_P0   VIA   -    MD0100PA00X+132749Y+124911X0200Y         S0      
317PVDDCR_CPU1_P0   VIA   -    MD0100PA00X+132749Y+125161X0200Y         S0      
317PVDDCR_CPU1_P0   VIA   -    MD0100PA00X+132749Y+124661X0200Y         S0      
317PVDDCR_CPU1_P0   VIA   -    MD0100PA00X+130909Y+124911X0200Y         S0      
317PVDDCR_CPU1_P0   VIA   -    MD0100PA00X+131159Y+124911X0200Y         S0      
317PVDDCR_CPU1_P0   VIA   -    MD0100PA00X+130909Y+124661X0200Y         S0      
317PVDDCR_CPU1_P0   VIA   -    MD0100PA00X+131159Y+124661X0200Y         S0      
317PVDDCR_CPU1_P0   VIA   -    MD0100PA00X+130909Y+125411X0200Y         S0      
317PVDDCR_CPU1_P0   VIA   -    MD0100PA00X+131159Y+125411X0200Y         S0      
317PVDDCR_CPU1_P0   VIA   -    MD0100PA00X+130909Y+125161X0200Y         S0      
317PVDDCR_CPU1_P0   VIA   -    MD0100PA00X+131159Y+125161X0200Y         S0      
317PVDDCR_CPU1_P0   VIA   -    MD0100PA00X+129459Y+124661X0200Y         S0      
317PVDDCR_CPU1_P0   VIA   -    MD0100PA00X+129709Y+124661X0200Y         S0      
317PVDDCR_CPU1_P0   VIA   -    MD0100PA00X+129209Y+124661X0200Y         S0      
317PVDDCR_CPU1_P0   VIA   -    MD0100PA00X+129709Y+125161X0200Y         S0      
317PVDDCR_CPU1_P0   VIA   -    MD0100PA00X+129459Y+125161X0200Y         S0      
317PVDDCR_CPU1_P0   VIA   -    MD0100PA00X+129209Y+125161X0200Y         S0      
317PVDDCR_CPU1_P0   VIA   -    MD0100PA00X+129709Y+124911X0200Y         S0      
317PVDDCR_CPU1_P0   VIA   -    MD0100PA00X+129459Y+124911X0200Y         S0      
317PVDDCR_CPU1_P0   VIA   -    MD0100PA00X+129209Y+124911X0200Y         S0      
317PVDDCR_CPU1_P0   VIA   -    MD0100PA00X+129209Y+125411X0200Y         S0      
317PVDDCR_CPU1_P0   VIA   -    MD0100PA00X+129709Y+125411X0200Y         S0      
317PVDDCR_CPU1_P0   VIA   -    MD0100PA00X+129459Y+125411X0200Y         S0      
317PVDDCR_CPU1_P0   VIA   -    MD0100PA00X+127869Y+124661X0200Y         S0      
317PVDDCR_CPU1_P0   VIA   -    MD0100PA00X+127619Y+124661X0200Y         S0      
317PVDDCR_CPU1_P0   VIA   -    MD0100PA00X+128119Y+124661X0200Y         S0      
317PVDDCR_CPU1_P0   VIA   -    MD0100PA00X+127869Y+124911X0200Y         S0      
317PVDDCR_CPU1_P0   VIA   -    MD0100PA00X+127619Y+124911X0200Y         S0      
317PVDDCR_CPU1_P0   VIA   -    MD0100PA00X+127869Y+125161X0200Y         S0      
317PVDDCR_CPU1_P0   VIA   -    MD0100PA00X+127619Y+125161X0200Y         S0      
317PVDDCR_CPU1_P0   VIA   -    MD0100PA00X+128119Y+125161X0200Y         S0      
317PVDDCR_CPU1_P0   VIA   -    MD0100PA00X+128119Y+124911X0200Y         S0      
317PVDDCR_CPU1_P0   VIA   -    MD0100PA00X+127869Y+125411X0200Y         S0      
317PVDDCR_CPU1_P0   VIA   -    MD0100PA00X+127619Y+125411X0200Y         S0      
317PVDDCR_CPU1_P0   VIA   -    MD0100PA00X+128119Y+125411X0200Y         S0      
317PVDDCR_CPU1_P0   VIA   -    MD0100PA00X+126419Y+124920X0200Y         S0      
317PVDDCR_CPU1_P0   VIA   -    MD0100PA00X+126169Y+124920X0200Y         S0      
317PVDDCR_CPU1_P0   VIA   -    MD0100PA00X+125919Y+124920X0200Y         S0      
317PVDDCR_CPU1_P0   VIA   -    MD0100PA00X+125919Y+125420X0200Y         S0      
317PVDDCR_CPU1_P0   VIA   -    MD0100PA00X+126419Y+125420X0200Y         S0      
317PVDDCR_CPU1_P0   VIA   -    MD0100PA00X+126169Y+125420X0200Y         S0      
317PVDDCR_CPU1_P0   VIA   -    MD0100PA00X+126169Y+124670X0200Y         S0      
317PVDDCR_CPU1_P0   VIA   -    MD0100PA00X+126419Y+124670X0200Y         S0      
317PVDDCR_CPU1_P0   VIA   -    MD0100PA00X+125919Y+124670X0200Y         S0      
317PVDDCR_CPU1_P0   VIA   -    MD0100PA00X+126419Y+125170X0200Y         S0      
317PVDDCR_CPU1_P0   VIA   -    MD0100PA00X+126169Y+125170X0200Y         S0      
317PVDDCR_CPU1_P0   VIA   -    MD0100PA00X+125919Y+125170X0200Y         S0      
317PVDDCR_CPU1_P0   VIA   -    MD0100PA00X+141730Y+105154X0190Y    R270 S0      
327m3870            PU24  -1          A01X+026790Y+065612X0090Y0240R270 S1      
327m3870            PR425 -1          A18X+027287Y+065616X0198Y0197R090 S2      
317m3870            VIA   -    MD0100PA00X+026918Y+065371X0200Y    R180 S0      
327m3871            PU29  -1          A01X+030063Y+069036X0090Y0240R270 S1      
327m3871            PR204 -1          A18X+030560Y+069040X0198Y0197R090 S2      
317m3871            VIA   -    MD0100PA00X+030191Y+068795X0200Y    R180 S0      
327m3872            PU28  -1          A01X+043250Y+069251X0090Y0240R270 S1      
327m3872            PR200 -1          A18X+043747Y+069255X0198Y0197R090 S2      
317m3872            VIA   -    MD0100PA00X+043378Y+069010X0200Y    R180 S0      
327m3873            PU27  -1          A01X+039950Y+071031X0090Y0240R270 S1      
327m3873            PR199 -1          A18X+040447Y+071035X0198Y0197R090 S2      
317m3873            VIA   -    MD0100PA00X+040078Y+070790X0200Y    R180 S0      
327m3874            PU26  -1          A01X+036646Y+071024X0090Y0240R270 S1      
327m3874            PR192 -1          A18X+037143Y+071028X0198Y0197R090 S2      
317m3874            VIA   -    MD0100PA00X+036774Y+070783X0200Y    R180 S0      
327m3875            PU4   -1          A01X+033340Y+071051X0090Y0240R270 S1      
327m3875            PR191 -1          A18X+033837Y+071055X0198Y0197R090 S2      
317m3875            VIA   -    MD0100PA00X+033468Y+070810X0200Y    R180 S0      
327m3876            PR4   -1          A01X+039073Y+056592X0198Y0197R180 S1      
327m3876            PC243 -1          A18X+039758Y+056142X0198Y0197R180 S2      
327m3876            PU25  -45         A18X+038798Y+056598X0070Y0260R270 S2      
317m3876            VIA   -    MD0100PA00X+039567Y+056333X0200Y    R180 S0      
327m3876            VIA   -           A01X+039710Y+056619X0300Y    R180 S1      
327m3876            PR157 -2          A01X+039980Y+056142X0198Y0197R180 S1      
317m3877            VIA   -    M      A01X+039517Y+055946X0300Y    R180 S1      
017m3877            VIA   -    M      A18X+039517Y+055946X0200Y    R180 S1      
017m3877                  -    MD0100PA00X+039517Y+055946                       
327m3877            PU25  -46         A18X+038798Y+056440X0070Y0260R270 S2      
327m3877            PC6   -1          A18X+039758Y+055742X0198Y0197R180 S2      
327m3877            PR181 -2   M      A01X+039980Y+055592X0198Y0197R180 S1      
327m3877            PR602 -1          A01X+039980Y+055192X0198Y0197     S1      
317m3878            VIA   -    M      A01X+038898Y+055487X0300Y    R180 S1      
017m3878            VIA   -    M      A18X+038898Y+055487X0200Y    R180 S1      
017m3878                  -    MD0100PA00X+038898Y+055487                       
327m3878            PU4   -39         A01X+033179Y+070805X0090Y0240R180 S1      
327m3878            PC254_-1   M      A01X+033456Y+070192X0198Y0197R270 S1      
317m3878            VIA   -    MD0100PA00X+033169Y+070192X0200Y    R180 S0      
317m3878            VIA   -    MD0100PA00X+052915Y+059874X0200Y    R180 S0      
327m3878            PC345_-1   M      A01X+053196Y+059872X0198Y0197R270 S1      
327m3878            PU32  -39         A01X+052919Y+060485X0090Y0240R180 S1      
317m3878            VIA   -    MD0100PA00X+046319Y+065932X0200Y    R180 S0      
327m3878            PC317_-1   M      A01X+046606Y+065932X0198Y0197R270 S1      
327m3878            PU30  -39         A01X+046329Y+066545X0090Y0240R180 S1      
327m3878            PU29  -39         A01X+029902Y+068790X0090Y0240R180 S1      
327m3878            PC306_-1   M      A01X+030179Y+068176X0198Y0197R270 S1      
317m3878            VIA   -    MD0100PA00X+029892Y+068176X0200Y    R180 S0      
327m3878            PC11  -1          A18X+038766Y+055249X0198Y0197R090 S2      
327m3878            PC251 -1          A18X+039166Y+055249X0198Y0197R090 S2      
327m3878            PU25  -48         A18X+038798Y+056125X0070Y0260R270 S2      
317m3878            VIA   -    MD0100PA00X+026619Y+064752X0200Y    R180 S0      
327m3878            PC124_-1   M      A01X+026906Y+064752X0198Y0197R270 S1      
327m3878            PU24  -39         A01X+026629Y+065366X0090Y0240R180 S1      
327m3878            PU28  -39         A01X+043089Y+069005X0090Y0240R180 S1      
327m3878            PC285_-1   M      A01X+043366Y+068392X0198Y0197R270 S1      
317m3878            VIA   -    MD0100PA00X+043079Y+068392X0200Y    R180 S0      
327m3878            PU27  -39         A01X+039789Y+070785X0090Y0240R180 S1      
327m3878            PC284_-1   M      A01X+040066Y+070172X0198Y0197R270 S1      
317m3878            VIA   -    MD0100PA00X+039779Y+070172X0200Y    R180 S0      
327m3878            PU26  -39         A01X+036485Y+070778X0090Y0240R180 S1      
327m3878            PC255_-1   M      A01X+036762Y+070165X0198Y0197R270 S1      
317m3878            VIA   -    MD0100PA00X+036475Y+070165X0200Y    R180 S0      
327m3878            PU31  -39         A01X+049589Y+063895X0090Y0240R180 S1      
327m3878            PC318_-1   M      A01X+049866Y+063282X0198Y0197R270 S1      
317m3878            VIA   -    MD0100PA00X+049579Y+063282X0200Y    R180 S0      
327m3879            VIA   -    M      A18X+026578Y+065395X0260Y         S2      
327m3879            PU24  -3          A01X+026790Y+065966X0090Y0240R270 S1      
327m3879            PC125 -1          A01X+027296Y+065616X0198Y0197R270 S1      
327m3879            PR422 -2   M      A18X+026755Y+065933X0198Y0197R090 S2      
317m3879            VIA   -    MD0100PA00X+027296Y+065856X0200Y    R180 S0      
317m3879            VIA   -    MD0100PA00X+025950Y+065056X0200Y    R180 S0      
327m3879            PU24  -35         A01X+025920Y+065366X0090Y0240R180 S1      
327m3880            VIA   -    M      A18X+029382Y+068799X0260Y         S2      
327m3880            PU29  -3          A01X+030063Y+069390X0090Y0240R270 S1      
327m3880            PC307 -1          A01X+030568Y+069040X0198Y0197R270 S1      
327m3880            PR201 -2   M      A18X+030028Y+069357X0198Y0197R090 S2      
317m3880            VIA   -    MD0100PA00X+030568Y+069280X0200Y    R180 S0      
317m3880            VIA   -    MD0100PA00X+029223Y+068480X0200Y    R180 S0      
327m3880            PU29  -35         A01X+029193Y+068790X0090Y0240R180 S1      
327m3881            PU28  -3          A01X+043250Y+069605X0090Y0240R270 S1      
327m3881            PC287 -1          A01X+043756Y+069255X0198Y0197R270 S1      
327m3881            PR194 -2   M      A18X+043215Y+069572X0198Y0197R090 S2      
317m3881            VIA   -    MD0100PA00X+043756Y+069495X0200Y    R180 S0      
327m3881            VIA   -    M      A18X+042515Y+069014X0260Y         S2      
317m3881            VIA   -    MD0100PA00X+042410Y+068695X0200Y    R180 S0      
327m3881            PU28  -35         A01X+042380Y+069005X0090Y0240R180 S1      
327m3882            VIA   -    M      A18X+039332Y+070794X0260Y         S2      
327m3882            PU27  -3          A01X+039950Y+071385X0090Y0240R270 S1      
327m3882            PC286 -1          A01X+040456Y+071035X0198Y0197R270 S1      
327m3882            PR193 -2   M      A18X+039915Y+071352X0198Y0197R090 S2      
317m3882            VIA   -    MD0100PA00X+040456Y+071275X0200Y    R180 S0      
327m3882            PU27  -35         A01X+039080Y+070785X0090Y0240R180 S1      
317m3882            VIA   -    MD0100PA00X+039110Y+070475X0200Y    R180 S0      
327m3883            VIA   -    M      A18X+035985Y+070787X0260Y         S2      
327m3883            PU26  -3          A01X+036646Y+071378X0090Y0240R270 S1      
327m3883            PC257 -1          A01X+037152Y+071028X0198Y0197R270 S1      
327m3883            PR186 -2   M      A18X+036611Y+071345X0198Y0197R090 S2      
317m3883            VIA   -    MD0100PA00X+037152Y+071268X0200Y    R180 S0      
317m3883            VIA   -    MD0100PA00X+035806Y+070468X0200Y    R180 S0      
327m3883            PU26  -35         A01X+035776Y+070778X0090Y0240R180 S1      
327m3884            VIA   -    M      A18X+032639Y+070814X0260Y         S2      
327m3884            PU4   -3          A01X+033340Y+071405X0090Y0240R270 S1      
327m3884            PC256 -1          A01X+033846Y+071055X0198Y0197R270 S1      
327m3884            PR185 -2   M      A18X+033305Y+071372X0198Y0197R090 S2      
317m3884            VIA   -    MD0100PA00X+033846Y+071295X0200Y    R180 S0      
317m3884            VIA   -    MD0100PA00X+032500Y+070495X0200Y    R180 S0      
327m3884            PU4   -35         A01X+032470Y+070805X0090Y0240R180 S1      
327m3885            VIA   -           A18X+039255Y+055708X0260Y    R180 S2      
327m3885            PU25  -47         A18X+038798Y+056283X0070Y0260R270 S2      
327m3885            PC10  -1          A18X+039566Y+055249X0198Y0197R090 S2      
327m3885            PC252 -1          A18X+039966Y+055249X0198Y0197R090 S2      
327m3885            PR183 -1          A18X+040366Y+055249X0198Y0197R090 S2      
327m3886            PU28  -36         A01X+042558Y+069005X0090Y0240R180 S1      
317m3886            VIA   -    MD0100PA00X+042684Y+068598X0200Y    R180 S0      
327m3886            PU27  -36         A01X+039258Y+070785X0090Y0240R180 S1      
317m3886            VIA   -    MD0100PA00X+039384Y+070378X0200Y    R180 S0      
327m3886            PU24  -36         A01X+026098Y+065366X0090Y0240R180 S1      
317m3886            VIA   -    MD0100PA00X+026224Y+064959X0200Y    R180 S2      
327m3886            PU29  -36         A01X+029370Y+068790X0090Y0240R180 S1      
317m3886            VIA   -    MD0100PA00X+029497Y+068383X0200Y    R180 S0      
327m3886            PU4   -36         A01X+032648Y+070805X0090Y0240R180 S1      
317m3886            VIA   -    MD0100PA00X+032774Y+070398X0200Y    R180 S0      
327m3886            PU26  -36         A01X+035954Y+070778X0090Y0240R180 S1      
317m3886            VIA   -    MD0100PA00X+036080Y+070371X0200Y    R180 S0      
327m3886            PU25  -44         A18X+038798Y+056755X0070Y0260R270 S2      
327m3886            PC250 -1   M      A18X+039758Y+056542X0198Y0197R180 S2      
317m3886            VIA   -    MD0100PA00X+040487Y+056734X0200Y    R180 S0      
327m3887            VIA   -    M      A18X+036100Y+056879X0160Y0041R225 S2      
327m3887            R8182 -2          A18X+035673Y+056642X0198Y0197R180 S2      
327m3887            R8184 -2          A01X+035673Y+056642X0198Y0197     S1      
327m3887            PU25  -18         A18X+036534Y+056913X0070Y0260R270 S2      
317m3887            VIA   -    MD0100PA00X+035920Y+056699X0200Y    R180 S0      
317m3888            VIA   -    M      A01X+032296Y+055615X0200Y         S2      
017m3888            VIA   -    M      A18X+032296Y+055615X0260Y         S2      
017m3888                  -    MD0100PA00X+032296Y+055615                       
327m3888            U40   -6          A01X+032582Y+056027X0140Y0440     S1      
317m3888            VIA   -    MD0100PA00X+034940Y+056446X0200Y    R180 S0      
327m3888            R8182 -1          A18X+035358Y+056642X0198Y0197R180 S2      
317m3889            VIA   -    MD0100PA00X+025875Y+064799X0200Y    R180 S0      
327m3889            PU24  -34         A01X+025743Y+065366X0090Y0240R180 S1      
317m3889            VIA   -    MD0100PA00X+037750Y+055419X0200Y    R180 S0      
327m3889            PU25  -7          A18X+037587Y+055860X0070Y0260     S2      
327m3890            PU29  -34         A01X+029016Y+068790X0090Y0240R180 S1      
317m3890            VIA   -    MD0100PA00X+029148Y+068223X0200Y    R180 S0      
317m3890            VIA   -    M      A01X+037541Y+055225X0200Y    R180 S2      
017m3890            VIA   -    M      A18X+037541Y+055225X0260Y    R180 S2      
017m3890                  -    MD0100PA00X+037541Y+055225                       
327m3890            PU25  -8          A18X+037430Y+055860X0070Y0260     S2      
327m3891            PU28  -34         A01X+042203Y+069005X0090Y0240R180 S1      
317m3891            VIA   -    MD0100PA00X+042335Y+068438X0200Y    R180 S0      
317m3891            VIA   -    MD0100PA00X+037197Y+055314X0200Y    R180 S0      
327m3891            PU25  -9          A18X+037272Y+055860X0070Y0260     S2      
317m3892            VIA   -    MD0100PA00X+037027Y+055504X0200Y    R180 S0      
327m3892            PU25  -10         A18X+037114Y+055860X0070Y0260     S2      
327m3892            PU27  -34         A01X+038903Y+070785X0090Y0240R180 S1      
317m3892            VIA   -    MD0100PA00X+039035Y+070218X0200Y    R180 S0      
327m3893            PU26  -34         A01X+035599Y+070778X0090Y0240R180 S1      
317m3893            VIA   -    MD0100PA00X+035731Y+070211X0200Y    R180 S0      
317m3893            VIA   -    MD0100PA00X+036837Y+055304X0200Y    R180 S0      
327m3893            PU25  -11         A18X+036957Y+055860X0070Y0260     S2      
317m3894            VIA   -    M      A01X+036507Y+055104X0300Y    R180 S1      
017m3894            VIA   -    M      A18X+036507Y+055104X0200Y    R180 S1      
017m3894                  -    MD0100PA00X+036507Y+055104                       
327m3894            PU4   -34         A01X+032293Y+070805X0090Y0240R180 S1      
317m3894            VIA   -    MD0100PA00X+032425Y+070238X0200Y    R180 S0      
327m3894            PU25  -12         A18X+036800Y+055860X0070Y0260     S2      
327m3895            PU24  -4          A01X+026790Y+066143X0090Y0240R270 S1      
327m3895            PC126_-1   M      A01X+027296Y+066350X0198Y0197R090 S1      
327m3895            PR422 -1          A18X+026755Y+066248X0198Y0197R090 S2      
317m3895            VIA   -    MD0100PA00X+027296Y+066110X0200Y    R180 S0      
327m3895            PC259_-1   M      A01X+037152Y+071763X0198Y0197R090 S1      
327m3895            PU26  -4          A01X+036646Y+071555X0090Y0240R270 S1      
327m3895            PR186 -1          A18X+036611Y+071660X0198Y0197R090 S2      
317m3895            VIA   -    MD0100PA00X+037152Y+071522X0200Y    R180 S0      
327m3895            PC321_-1   M      A01X+046996Y+067530X0198Y0197R090 S1      
327m3895            PU30  -4          A01X+046490Y+067322X0090Y0240R270 S1      
327m3895            PR205 -1          A18X+046455Y+067427X0198Y0197R090 S2      
317m3895            VIA   -    MD0100PA00X+046996Y+067289X0200Y    R180 S0      
327m3895            PU31  -4          A01X+049750Y+064672X0090Y0240R270 S1      
327m3895            PC322_-1   M      A01X+050256Y+064880X0198Y0197R090 S1      
327m3895            PR206 -1          A18X+049715Y+064777X0198Y0197R090 S2      
317m3895            VIA   -    MD0100PA00X+050256Y+064639X0200Y    R180 S0      
327m3895            PU32  -4          A01X+053080Y+061262X0090Y0240R270 S1      
327m3895            PR213 -1          A18X+053045Y+061367X0198Y0197R090 S2      
327m3895            PR336 -1          A01X+053950Y+059849X0198Y0197R270 S1      
327m3895            PR335 -1          A01X+054337Y+059850X0198Y0197R270 S1      
327m3895            PC347_-1   M      A01X+053586Y+061470X0198Y0197R090 S1      
327m3895            VIA   -           A01X+054075Y+060340X0300Y    R180 S1      
317m3895            VIA   -    MD0100PA00X+053966Y+060766X0200Y    R180 S0      
317m3895            VIA   -    MD0100PA00X+053586Y+061229X0200Y    R180 S0      
327m3895            PU28  -4          A01X+043250Y+069782X0090Y0240R270 S1      
327m3895            PC289_-1   M      A01X+043756Y+069990X0198Y0197R090 S1      
327m3895            PR194 -1          A18X+043215Y+069887X0198Y0197R090 S2      
317m3895            VIA   -    MD0100PA00X+043756Y+069749X0200Y    R180 S0      
327m3895            PC288_-1   M      A01X+040456Y+071770X0198Y0197R090 S1      
327m3895            PU27  -4          A01X+039950Y+071562X0090Y0240R270 S1      
327m3895            PR193 -1          A18X+039915Y+071667X0198Y0197R090 S2      
317m3895            VIA   -    MD0100PA00X+040456Y+071529X0200Y    R180 S0      
327m3895            PC258_-1   M      A01X+033846Y+071790X0198Y0197R090 S1      
327m3895            PU4   -4          A01X+033340Y+071582X0090Y0240R270 S1      
327m3895            PR185 -1          A18X+033305Y+071687X0198Y0197R090 S2      
317m3895            VIA   -    MD0100PA00X+033846Y+071549X0200Y    R180 S0      
327m3895            PC308_-1   M      A01X+030568Y+069775X0198Y0197R090 S1      
327m3895            PU29  -4          A01X+030063Y+069567X0090Y0240R270 S1      
327m3895            PR201 -1          A18X+030028Y+069672X0198Y0197R090 S2      
317m3895            VIA   -    MD0100PA00X+030568Y+069534X0200Y         S0      
327m3896            R8176 -2          A18X+036216Y+055349X0198Y0197R270 S2      
327m3896            PU25  -13         A18X+036534Y+056125X0070Y0260R270 S2      
317m3896            VIA   -    M      A01X+036405Y+055677X0300Y    R180 S1      
017m3896            VIA   -    M      A18X+036405Y+055677X0200Y    R180 S1      
017m3896                  -    MD0100PA00X+036405Y+055677                       
327m3897            VIA   -    M      A18X+035760Y+054308X0260Y    R180 S2      
327m3897            R175  -2          A18X+036216Y+054649X0198Y0197R270 S2      
327m3897            PU25  -14         A18X+036534Y+056283X0070Y0260R270 S2      
327m3898            VIA   -    M      A18X+036065Y+055833X0160Y0041R225 S2      
327m3898            PU25  -15         A18X+036534Y+056440X0070Y0260R270 S2      
327m3898            R8177 -2          A18X+035673Y+055442X0198Y0197R180 S2      
317m3899            VIA   -    M      A01X+035116Y+055042X0300Y         S1      
017m3899            VIA   -    M      A18X+035116Y+055042X0200Y         S1      
017m3899                  -    MD0100PA00X+035116Y+055042                       
327m3899            C5012 -1   M      A18X+035358Y+055042X0198Y0197R180 S2      
327m3899            R8177 -1          A18X+035358Y+055442X0198Y0197R180 S2      
327m3899            R1187 -1          A01X+073141Y+037991X0198Y0197R270 S1      
327m3899            U18   -M5         A01X+073198Y+043249X0160Y    R090 S1      
317m3899            VIA   -    MD0100PA00X+073351Y+043096X0180Y    R090 S0      
317m3899            VIA   -    MD0100PA00X+073550Y+038686X0200Y    R090 S0      
317m3899            VIA   -    MD0100PA00X+065040Y+049610X0200Y         S0      
317m3899            VIA   -    MD0100PA00X+038483Y+050706X0200Y         S0      
317m3900            VIA   -    M      A01X+039516Y+057382X0300Y    R180 S1      
017m3900            VIA   -    M      A18X+039516Y+057382X0200Y    R180 S1      
017m3900                  -    MD0100PA00X+039516Y+057382                       
327m3900            R8180 -2          A01X+040067Y+057078X0198Y0197R270 S1      
327m3900            R8168 -2          A18X+039758Y+057342X0198Y0197     S2      
327m3900            PU25  -41         A18X+038798Y+057228X0070Y0260R270 S2      
327m3901            R8168 -1          A18X+040073Y+057342X0198Y0197     S2      
317m3901            VIA   -    M      A01X+041011Y+057261X0200Y    R180 S2      
017m3901            VIA   -    M      A18X+041011Y+057261X0260Y    R180 S2      
017m3901                  -    MD0100PA00X+041011Y+057261                       
317m3901            VIA   -    MD0100PA00X+064078Y+039596X0200Y         S0      
327m3901            R284  -2          A01X+071950Y+039329X0198Y0197R270 S1      
327m3902            PR423 -2          A01X+026517Y+064456X0198Y0197     S1      
327m3902            PU24  -37         A01X+026275Y+065366X0090Y0240R180 S1      
327m3902            VIA   -    M      A01X+026421Y+064904X0160Y0041R090 S1      
327m3903            PR202 -2          A01X+029790Y+067880X0198Y0197     S1      
327m3903            PU29  -37         A01X+029548Y+068790X0090Y0240R180 S1      
327m3903            VIA   -    M      A01X+029696Y+068316X0160Y0041R090 S1      
327m3904            VIA   -    M      A01X+042881Y+068544X0160Y0041R090 S1      
327m3904            PR196 -2          A01X+042977Y+068095X0198Y0197     S1      
327m3904            PU28  -37         A01X+042735Y+069005X0090Y0240R180 S1      
327m3905            PR195 -2          A01X+039677Y+069875X0198Y0197     S1      
327m3905            PU27  -37         A01X+039435Y+070785X0090Y0240R180 S1      
327m3905            VIA   -    M      A01X+039581Y+070318X0160Y0041R090 S1      
327m3906            PR188 -2          A01X+036373Y+069868X0198Y0197     S1      
327m3906            PU26  -37         A01X+036131Y+070778X0090Y0240R180 S1      
327m3906            VIA   -    M      A01X+036277Y+070313X0160Y0041R090 S1      
327m3907            PR187 -2          A01X+033067Y+069895X0198Y0197     S1      
327m3907            PU4   -37         A01X+032825Y+070805X0090Y0240R180 S1      
327m3907            VIA   -    M      A01X+032971Y+070336X0160Y0041R090 S1      
317m3908            VIA   -    MD0100PA00X+026619Y+065003X0200Y    R180 S0      
327m3908            PU24  -38         A01X+026452Y+065366X0090Y0240R180 S1      
317m3908            VIA   -    M      A01X+037969Y+058604X0300Y    R180 S1      
017m3908            VIA   -    M      A18X+037969Y+058604X0200Y    R180 S1      
017m3908                  -    MD0100PA00X+037969Y+058604                       
327m3908            PU25  -32         A18X+037902Y+058123X0070Y0260     S2      
317m3909            VIA   -    MD0100PA00X+037758Y+059013X0200Y    R180 S0      
327m3909            PU25  -31         A18X+037744Y+058123X0070Y0260     S2      
317m3909            VIA   -    MD0100PA00X+029892Y+068427X0200Y    R180 S0      
327m3909            PU29  -38         A01X+029725Y+068790X0090Y0240R180 S1      
327m3910            PU28  -38         A01X+042912Y+069005X0090Y0240R180 S1      
317m3910            VIA   -    MD0100PA00X+043079Y+068642X0200Y    R180 S2      
317m3910            VIA   -    MD0100PA00X+037858Y+059303X0200Y    R180 S0      
327m3910            PU25  -30         A18X+037587Y+058123X0070Y0260     S2      
327m3911            PU27  -38         A01X+039612Y+070785X0090Y0240R180 S1      
317m3911            VIA   -    MD0100PA00X+039779Y+070422X0200Y    R180 S0      
317m3911            VIA   -    M      A01X+037348Y+059334X0200Y    R180 S2      
017m3911            VIA   -    M      A18X+037348Y+059334X0260Y    R180 S2      
017m3911                  -    MD0100PA00X+037348Y+059334                       
327m3911            PU25  -29         A18X+037430Y+058123X0070Y0260     S2      
317m3912            VIA   -    MD0100PA00X+036475Y+070416X0200Y    R180 S0      
327m3912            PU26  -38         A01X+036308Y+070778X0090Y0240R180 S1      
317m3912            VIA   -    M      A01X+036927Y+060014X0200Y    R180 S2      
017m3912            VIA   -    M      A18X+036927Y+060014X0260Y    R180 S2      
017m3912                  -    MD0100PA00X+036927Y+060014                       
327m3912            PU25  -28         A18X+037272Y+058123X0070Y0260     S2      
327m3913            PU4   -38         A01X+033002Y+070805X0090Y0240R180 S1      
317m3913            VIA   -    MD0100PA00X+033169Y+070442X0200Y    R180 S0      
317m3913            VIA   -    M      A01X+036880Y+058794X0300Y    R180 S1      
017m3913            VIA   -    M      A18X+036880Y+058794X0200Y    R180 S1      
017m3913                  -    MD0100PA00X+036880Y+058794                       
327m3913            PU25  -27         A18X+037114Y+058123X0070Y0260     S2      
327m3914            R8179 -2          A01X+035673Y+056242X0198Y0197     S1      
327m3914            C249  -1          A18X+035673Y+056242X0198Y0197     S2      
327m3914            PU25  -17         A18X+036534Y+056755X0070Y0260R270 S2      
317m3914            VIA   -    M      A01X+036220Y+056675X0300Y    R180 S1      
017m3914            VIA   -    M      A18X+036220Y+056675X0200Y    R180 S1      
017m3914                  -    MD0100PA00X+036220Y+056675                       
317m3915            VIA   -    MD0100PA00X+058783Y+044514X0200Y         S0      
327m3915            R8179 -1          A01X+035358Y+056242X0198Y0197     S1      
317m3915            VIA   -    MD0100PA00X+034552Y+056439X0200Y         S0      
317m3915            VIA   -    MD0100PA00X+063606Y+052860X0200Y         S0      
317m3915            VIA   -    M      A01X+079628Y+042334X0200Y    R180 S2      
017m3915            VIA   -    M      A18X+079628Y+042334X0260Y    R180 S2      
017m3915                  -    MD0100PA00X+079628Y+042334                       
327m3915            R208  -1          A01X+079268Y+042334X0198Y0197R180 S1      
317PVDDCR_CPU0_P1   VIA   -    MD0080PA00X+040492Y+090832X0160Y    R180 S0      
317PVDDCR_CPU0_P1   VIA   -    MD0080PA00X+037902Y+087644X0160Y    R180 S0      
317PVDDCR_CPU0_P1   VIA   -    MD0080PA00X+037162Y+087644X0160Y    R180 S0      
317PVDDCR_CPU0_P1   VIA   -    MD0080PA00X+036792Y+087644X0160Y    R180 S0      
317PVDDCR_CPU0_P1   VIA   -    MD0080PA00X+037902Y+088919X0160Y    R180 S0      
317PVDDCR_CPU0_P1   VIA   -    MD0080PA00X+037532Y+088281X0160Y    R180 S0      
317PVDDCR_CPU0_P1   VIA   -    MD0080PA00X+037162Y+088281X0160Y    R180 S0      
317PVDDCR_CPU0_P1   VIA   -    MD0080PA00X+038642Y+089557X0160Y    R180 S0      
317PVDDCR_CPU0_P1   VIA   -    MD0080PA00X+039012Y+088919X0160Y    R180 S0      
317PVDDCR_CPU0_P1   VIA   -    MD0080PA00X+038272Y+089557X0160Y    R180 S0      
317PVDDCR_CPU0_P1   VIA   -    MD0080PA00X+038087Y+088600X0160Y    R180 S0      
317PVDDCR_CPU0_P1   VIA   -    MD0080PA00X+039382Y+089557X0160Y    R180 S0      
317PVDDCR_CPU0_P1   VIA   -    MD0080PA00X+039197Y+088600X0160Y    R180 S0      
317PVDDCR_CPU0_P1   VIA   -    MD0080PA00X+039012Y+087644X0160Y    R180 S0      
317PVDDCR_CPU0_P1   VIA   -    MD0080PA00X+038272Y+087644X0160Y    R180 S0      
317PVDDCR_CPU0_P1   VIA   -    MD0080PA00X+039382Y+087644X0160Y    R180 S0      
317PVDDCR_CPU0_P1   VIA   -    MD0080PA00X+038272Y+090832X0160Y    R180 S0      
317PVDDCR_CPU0_P1   VIA   -    MD0080PA00X+038642Y+090832X0160Y    R180 S0      
317PVDDCR_CPU0_P1   VIA   -    MD0080PA00X+039382Y+090832X0160Y    R180 S0      
317PVDDCR_CPU0_P1   VIA   -    MD0080PA00X+038642Y+094021X0160Y    R180 S0      
317PVDDCR_CPU0_P1   VIA   -    MD0080PA00X+038272Y+094021X0160Y    R180 S0      
317PVDDCR_CPU0_P1   VIA   -    MD0080PA00X+039382Y+094021X0160Y    R180 S0      
317PVDDCR_CPU0_P1   VIA   -    MD0080PA00X+038642Y+092108X0160Y    R180 S0      
317PVDDCR_CPU0_P1   VIA   -    MD0080PA00X+038272Y+092108X0160Y    R180 S0      
317PVDDCR_CPU0_P1   VIA   -    MD0080PA00X+039382Y+092108X0160Y    R180 S0      
317PVDDCR_CPU0_P1   VIA   -    MD0080PA00X+038642Y+095297X0160Y    R180 S0      
317PVDDCR_CPU0_P1   VIA   -    MD0080PA00X+038272Y+095297X0160Y    R180 S0      
317PVDDCR_CPU0_P1   VIA   -    MD0080PA00X+039382Y+095297X0160Y    R180 S0      
317PVDDCR_CPU0_P1   VIA   -    MD0080PA00X+038272Y+097848X0160Y    R180 S0      
317PVDDCR_CPU0_P1   VIA   -    MD0080PA00X+039567Y+098167X0160Y    R180 S0      
317PVDDCR_CPU0_P1   VIA   -    MD0080PA00X+039382Y+097848X0160Y    R180 S0      
317PVDDCR_CPU0_P1   VIA   -    MD0080PA00X+038642Y+096573X0160Y    R180 S0      
317PVDDCR_CPU0_P1   VIA   -    MD0080PA00X+038272Y+096573X0160Y    R180 S0      
317PVDDCR_CPU0_P1   VIA   -    MD0080PA00X+039382Y+096573X0160Y    R180 S0      
317PVDDCR_CPU0_P1   VIA   -    MD0080PA00X+038642Y+097848X0160Y    R180 S0      
317PVDDCR_CPU0_P1   VIA   -    MD0080PA00X+040492Y+089557X0160Y    R180 S0      
317PVDDCR_CPU0_P1   VIA   -    MD0080PA00X+040863Y+089557X0160Y    R180 S0      
317PVDDCR_CPU0_P1   VIA   -    MD0080PA00X+040122Y+088919X0160Y    R180 S0      
317PVDDCR_CPU0_P1   VIA   -    MD0080PA00X+040308Y+088600X0160Y    R180 S0      
317PVDDCR_CPU0_P1   VIA   -    MD0080PA00X+039752Y+089557X0160Y    R180 S0      
317PVDDCR_CPU0_P1   VIA   -    MD0080PA00X+040122Y+087644X0160Y    R180 S0      
317PVDDCR_CPU0_P1   VIA   -    MD0080PA00X+040492Y+087644X0160Y    R180 S0      
317PVDDCR_CPU0_P1   VIA   -    MD0080PA00X+040492Y+092108X0160Y    R180 S0      
317PVDDCR_CPU0_P1   VIA   -    MD0080PA00X+040863Y+092108X0160Y    R180 S0      
317PVDDCR_CPU0_P1   VIA   -    MD0080PA00X+039752Y+092108X0160Y    R180 S0      
317PVDDCR_CPU0_P1   VIA   -    MD0080PA00X+040863Y+090832X0160Y    R180 S0      
317PVDDCR_CPU0_P1   VIA   -    MD0080PA00X+039752Y+090832X0160Y    R180 S0      
317PVDDCR_CPU0_P1   VIA   -    MD0080PA00X+040492Y+095297X0160Y    R180 S0      
317PVDDCR_CPU0_P1   VIA   -    MD0080PA00X+040863Y+095297X0160Y    R180 S0      
317PVDDCR_CPU0_P1   VIA   -    MD0080PA00X+039752Y+095297X0160Y    R180 S0      
317PVDDCR_CPU0_P1   VIA   -    MD0080PA00X+040492Y+094021X0160Y    R180 S0      
317PVDDCR_CPU0_P1   VIA   -    MD0080PA00X+040863Y+094021X0160Y    R180 S0      
317PVDDCR_CPU0_P1   VIA   -    MD0080PA00X+040678Y+093065X0160Y    R180 S0      
317PVDDCR_CPU0_P1   VIA   -    MD0080PA00X+041048Y+093065X0160Y    R180 S0      
317PVDDCR_CPU0_P1   VIA   -    MD0080PA00X+039752Y+094021X0160Y    R180 S0      
317PVDDCR_CPU0_P1   VIA   -    MD0080PA00X+040308Y+098805X0160Y    R180 S0      
317PVDDCR_CPU0_P1   VIA   -    MD0080PA00X+041048Y+098805X0160Y    R180 S0      
317PVDDCR_CPU0_P1   VIA   -    MD0080PA00X+040492Y+098486X0160Y    R180 S0      
317PVDDCR_CPU0_P1   VIA   -    MD0080PA00X+040308Y+098167X0160Y    R180 S0      
317PVDDCR_CPU0_P1   VIA   -    MD0080PA00X+041048Y+098167X0160Y    R180 S0      
317PVDDCR_CPU0_P1   VIA   -    MD0080PA00X+040863Y+097848X0160Y    R180 S0      
317PVDDCR_CPU0_P1   VIA   -    MD0080PA00X+040492Y+097848X0160Y    R180 S0      
317PVDDCR_CPU0_P1   VIA   -    MD0080PA00X+039752Y+098486X0160Y    R180 S0      
317PVDDCR_CPU0_P1   VIA   -    MD0080PA00X+039752Y+097848X0160Y    R180 S0      
317PVDDCR_CPU0_P1   VIA   -    MD0080PA00X+040492Y+096573X0160Y    R180 S0      
317PVDDCR_CPU0_P1   VIA   -    MD0080PA00X+040863Y+096573X0160Y    R180 S0      
317PVDDCR_CPU0_P1   VIA   -    MD0080PA00X+039752Y+096573X0160Y    R180 S0      
317PVDDCR_CPU0_P1   VIA   -    MD0080PA00X+041603Y+090832X0160Y    R180 S0      
317PVDDCR_CPU0_P1   VIA   -    MD0080PA00X+041973Y+090832X0160Y    R180 S0      
317PVDDCR_CPU0_P1   VIA   -    MD0080PA00X+041418Y+088600X0160Y    R180 S0      
317PVDDCR_CPU0_P1   VIA   -    MD0080PA00X+041603Y+089557X0160Y    R180 S0      
317PVDDCR_CPU0_P1   VIA   -    MD0080PA00X+041973Y+089557X0160Y    R180 S0      
317PVDDCR_CPU0_P1   VIA   -    MD0080PA00X+042343Y+088919X0160Y    R180 S0      
317PVDDCR_CPU0_P1   VIA   -    MD0080PA00X+042528Y+088600X0160Y    R180 S0      
317PVDDCR_CPU0_P1   VIA   -    MD0080PA00X+041233Y+088919X0160Y    R180 S0      
317PVDDCR_CPU0_P1   VIA   -    MD0080PA00X+042343Y+087644X0160Y    R180 S0      
317PVDDCR_CPU0_P1   VIA   -    MD0080PA00X+041233Y+087644X0160Y    R180 S0      
317PVDDCR_CPU0_P1   VIA   -    MD0080PA00X+041603Y+087644X0160Y    R180 S0      
317PVDDCR_CPU0_P1   VIA   -    MD0080PA00X+041973Y+094021X0160Y    R180 S0      
317PVDDCR_CPU0_P1   VIA   -    MD0080PA00X+041603Y+094021X0160Y    R180 S0      
317PVDDCR_CPU0_P1   VIA   -    MD0080PA00X+042158Y+093065X0160Y    R180 S0      
317PVDDCR_CPU0_P1   VIA   -    MD0080PA00X+041788Y+093065X0160Y    R180 S0      
317PVDDCR_CPU0_P1   VIA   -    MD0080PA00X+041973Y+092108X0160Y    R180 S0      
317PVDDCR_CPU0_P1   VIA   -    MD0080PA00X+041603Y+092108X0160Y    R180 S0      
317PVDDCR_CPU0_P1   VIA   -    MD0080PA00X+041603Y+096573X0160Y    R180 S0      
317PVDDCR_CPU0_P1   VIA   -    MD0080PA00X+041973Y+096573X0160Y    R180 S0      
317PVDDCR_CPU0_P1   VIA   -    MD0080PA00X+041973Y+095297X0160Y    R180 S0      
317PVDDCR_CPU0_P1   VIA   -    MD0080PA00X+041603Y+095297X0160Y    R180 S0      
317PVDDCR_CPU0_P1   VIA   -    MD0080PA00X+042528Y+098805X0160Y    R180 S0      
317PVDDCR_CPU0_P1   VIA   -    MD0080PA00X+041788Y+098805X0160Y    R180 S0      
317PVDDCR_CPU0_P1   VIA   -    MD0080PA00X+041973Y+098486X0160Y    R180 S0      
317PVDDCR_CPU0_P1   VIA   -    MD0080PA00X+041788Y+098167X0160Y    R180 S0      
317PVDDCR_CPU0_P1   VIA   -    MD0080PA00X+042528Y+098167X0160Y    R180 S0      
317PVDDCR_CPU0_P1   VIA   -    MD0080PA00X+041973Y+097848X0160Y    R180 S0      
317PVDDCR_CPU0_P1   VIA   -    MD0080PA00X+041603Y+097848X0160Y    R180 S0      
317PVDDCR_CPU0_P1   VIA   -    MD0080PA00X+041233Y+098486X0160Y    R180 S0      
317PVDDCR_CPU0_P1   VIA   -    MD0080PA00X+043268Y+089876X0160Y    R180 S0      
317PVDDCR_CPU0_P1   VIA   -    MD0080PA00X+042898Y+089876X0160Y    R180 S0      
317PVDDCR_CPU0_P1   VIA   -    MD0080PA00X+043268Y+091151X0160Y    R180 S0      
317PVDDCR_CPU0_P1   VIA   -    MD0080PA00X+042898Y+091151X0160Y    R180 S0      
317PVDDCR_CPU0_P1   VIA   -    MD0080PA00X+043268Y+089238X0160Y    R180 S0      
317PVDDCR_CPU0_P1   VIA   -    MD0080PA00X+042898Y+089238X0160Y    R180 S0      
317PVDDCR_CPU0_P1   VIA   -    MD0080PA00X+042713Y+087644X0160Y    R180 S0      
317PVDDCR_CPU0_P1   VIA   -    MD0080PA00X+043268Y+095616X0160Y    R180 S0      
317PVDDCR_CPU0_P1   VIA   -    MD0080PA00X+043268Y+094340X0160Y    R180 S0      
317PVDDCR_CPU0_P1   VIA   -    MD0080PA00X+042898Y+095616X0160Y    R180 S0      
317PVDDCR_CPU0_P1   VIA   -    MD0080PA00X+042898Y+094340X0160Y    R180 S0      
317PVDDCR_CPU0_P1   VIA   -    MD0080PA00X+043083Y+093384X0160Y    R180 S0      
317PVDDCR_CPU0_P1   VIA   -    MD0080PA00X+042713Y+093384X0160Y    R180 S0      
317PVDDCR_CPU0_P1   VIA   -    MD0080PA00X+043268Y+092427X0160Y    R180 S0      
317PVDDCR_CPU0_P1   VIA   -    MD0080PA00X+042898Y+092427X0160Y    R180 S0      
317PVDDCR_CPU0_P1   VIA   -    MD0080PA00X+043453Y+098486X0160Y    R180 S0      
317PVDDCR_CPU0_P1   VIA   -    MD0080PA00X+043268Y+098167X0160Y    R180 S0      
317PVDDCR_CPU0_P1   VIA   -    MD0080PA00X+042713Y+098486X0160Y    R180 S0      
317PVDDCR_CPU0_P1   VIA   -    MD0080PA00X+043268Y+096892X0160Y    R180 S0      
317PVDDCR_CPU0_P1   VIA   -    MD0080PA00X+042898Y+096892X0160Y    R180 S0      
317PVDDCR_CPU0_P1   VIA   -    MD0080PA00X+045301Y+087644X0160Y    R180 S0      
317PVDDCR_CPU0_P1   VIA   -    MD0080PA00X+044746Y+092427X0160Y    R180 S0      
317PVDDCR_CPU0_P1   VIA   -    MD0080PA00X+045116Y+092427X0160Y    R180 S0      
317PVDDCR_CPU0_P1   VIA   -    MD0080PA00X+044746Y+089876X0160Y    R180 S0      
317PVDDCR_CPU0_P1   VIA   -    MD0080PA00X+045116Y+089876X0160Y    R180 S0      
317PVDDCR_CPU0_P1   VIA   -    MD0080PA00X+044746Y+091151X0160Y    R180 S0      
317PVDDCR_CPU0_P1   VIA   -    MD0080PA00X+045116Y+091151X0160Y    R180 S0      
317PVDDCR_CPU0_P1   VIA   -    MD0080PA00X+044746Y+089238X0160Y    R180 S0      
317PVDDCR_CPU0_P1   VIA   -    MD0080PA00X+045116Y+089238X0160Y    R180 S0      
317PVDDCR_CPU0_P1   VIA   -    MD0080PA00X+045486Y+088600X0160Y    R180 S0      
317PVDDCR_CPU0_P1   VIA   -    MD0080PA00X+045116Y+088600X0160Y    R180 S0      
317PVDDCR_CPU0_P1   VIA   -    MD0080PA00X+044931Y+098486X0160Y    R180 S0      
317PVDDCR_CPU0_P1   VIA   -    MD0080PA00X+045116Y+098167X0160Y    R180 S0      
317PVDDCR_CPU0_P1   VIA   -    MD0080PA00X+044746Y+096892X0160Y    R180 S0      
317PVDDCR_CPU0_P1   VIA   -    MD0080PA00X+045116Y+096892X0160Y    R180 S0      
317PVDDCR_CPU0_P1   VIA   -    MD0080PA00X+044746Y+095616X0160Y    R180 S0      
317PVDDCR_CPU0_P1   VIA   -    MD0080PA00X+044746Y+094340X0160Y    R180 S0      
317PVDDCR_CPU0_P1   VIA   -    MD0080PA00X+045116Y+095616X0160Y    R180 S0      
317PVDDCR_CPU0_P1   VIA   -    MD0080PA00X+045116Y+094340X0160Y    R180 S0      
317PVDDCR_CPU0_P1   VIA   -    MD0080PA00X+045301Y+093384X0160Y    R180 S0      
317PVDDCR_CPU0_P1   VIA   -    MD0080PA00X+044931Y+093384X0160Y    R180 S0      
317PVDDCR_CPU0_P1   VIA   -    MD0080PA00X+046411Y+089557X0160Y    R180 S0      
317PVDDCR_CPU0_P1   VIA   -    MD0080PA00X+046781Y+088919X0160Y    R180 S0      
317PVDDCR_CPU0_P1   VIA   -    MD0080PA00X+046596Y+088600X0160Y    R180 S0      
317PVDDCR_CPU0_P1   VIA   -    MD0080PA00X+046041Y+089557X0160Y    R180 S0      
317PVDDCR_CPU0_P1   VIA   -    MD0080PA00X+045671Y+088919X0160Y    R180 S0      
317PVDDCR_CPU0_P1   VIA   -    MD0080PA00X+046411Y+087644X0160Y    R180 S0      
317PVDDCR_CPU0_P1   VIA   -    MD0080PA00X+046781Y+087644X0160Y    R180 S0      
317PVDDCR_CPU0_P1   VIA   -    MD0080PA00X+045671Y+087644X0160Y    R180 S0      
317PVDDCR_CPU0_P1   VIA   -    MD0080PA00X+046411Y+095297X0160Y    R180 S0      
317PVDDCR_CPU0_P1   VIA   -    MD0080PA00X+046041Y+095297X0160Y    R180 S0      
317PVDDCR_CPU0_P1   VIA   -    MD0080PA00X+046411Y+094021X0160Y    R180 S0      
317PVDDCR_CPU0_P1   VIA   -    MD0080PA00X+046966Y+093065X0160Y    R180 S0      
317PVDDCR_CPU0_P1   VIA   -    MD0080PA00X+046041Y+094021X0160Y    R180 S0      
317PVDDCR_CPU0_P1   VIA   -    MD0080PA00X+045856Y+093065X0160Y    R180 S0      
317PVDDCR_CPU0_P1   VIA   -    MD0080PA00X+046226Y+093065X0160Y    R180 S0      
317PVDDCR_CPU0_P1   VIA   -    MD0080PA00X+046411Y+092108X0160Y    R180 S0      
317PVDDCR_CPU0_P1   VIA   -    MD0080PA00X+046041Y+092108X0160Y    R180 S0      
317PVDDCR_CPU0_P1   VIA   -    MD0080PA00X+046411Y+090832X0160Y    R180 S0      
317PVDDCR_CPU0_P1   VIA   -    MD0080PA00X+046041Y+090832X0160Y    R180 S0      
317PVDDCR_CPU0_P1   VIA   -    MD0080PA00X+045856Y+098805X0160Y    R180 S0      
317PVDDCR_CPU0_P1   VIA   -    MD0080PA00X+046411Y+098486X0160Y    R180 S0      
317PVDDCR_CPU0_P1   VIA   -    MD0080PA00X+046596Y+098167X0160Y    R180 S0      
317PVDDCR_CPU0_P1   VIA   -    MD0080PA00X+046411Y+097848X0160Y    R180 S0      
317PVDDCR_CPU0_P1   VIA   -    MD0080PA00X+045671Y+098486X0160Y    R180 S0      
317PVDDCR_CPU0_P1   VIA   -    MD0080PA00X+045856Y+098167X0160Y    R180 S0      
317PVDDCR_CPU0_P1   VIA   -    MD0080PA00X+046041Y+097848X0160Y    R180 S0      
317PVDDCR_CPU0_P1   VIA   -    MD0080PA00X+046411Y+096573X0160Y    R180 S0      
317PVDDCR_CPU0_P1   VIA   -    MD0080PA00X+046041Y+096573X0160Y    R180 S0      
317PVDDCR_CPU0_P1   VIA   -    MD0080PA00X+048262Y+089557X0160Y    R180 S0      
317PVDDCR_CPU0_P1   VIA   -    MD0080PA00X+047892Y+088919X0160Y    R180 S0      
317PVDDCR_CPU0_P1   VIA   -    MD0080PA00X+047152Y+089557X0160Y    R180 S0      
317PVDDCR_CPU0_P1   VIA   -    MD0080PA00X+047522Y+089557X0160Y    R180 S0      
317PVDDCR_CPU0_P1   VIA   -    MD0080PA00X+047707Y+088600X0160Y    R180 S0      
317PVDDCR_CPU0_P1   VIA   -    MD0080PA00X+047892Y+087644X0160Y    R180 S0      
317PVDDCR_CPU0_P1   VIA   -    MD0080PA00X+047522Y+087644X0160Y    R180 S0      
317PVDDCR_CPU0_P1   VIA   -    MD0080PA00X+048262Y+094021X0160Y    R180 S0      
317PVDDCR_CPU0_P1   VIA   -    MD0080PA00X+047522Y+094021X0160Y    R180 S0      
317PVDDCR_CPU0_P1   VIA   -    MD0080PA00X+047152Y+094021X0160Y    R180 S0      
317PVDDCR_CPU0_P1   VIA   -    MD0080PA00X+047336Y+093065X0160Y    R180 S0      
317PVDDCR_CPU0_P1   VIA   -    MD0080PA00X+048262Y+092108X0160Y    R180 S0      
317PVDDCR_CPU0_P1   VIA   -    MD0080PA00X+047152Y+092108X0160Y    R180 S0      
317PVDDCR_CPU0_P1   VIA   -    MD0080PA00X+047522Y+092108X0160Y    R180 S0      
317PVDDCR_CPU0_P1   VIA   -    MD0080PA00X+048262Y+090832X0160Y    R180 S0      
317PVDDCR_CPU0_P1   VIA   -    MD0080PA00X+047152Y+090832X0160Y    R180 S0      
317PVDDCR_CPU0_P1   VIA   -    MD0080PA00X+047522Y+090832X0160Y    R180 S0      
317PVDDCR_CPU0_P1   VIA   -    MD0080PA00X+047336Y+098805X0160Y    R180 S0      
317PVDDCR_CPU0_P1   VIA   -    MD0080PA00X+048077Y+098167X0160Y    R180 S0      
317PVDDCR_CPU0_P1   VIA   -    MD0080PA00X+048262Y+097848X0160Y    R180 S0      
317PVDDCR_CPU0_P1   VIA   -    MD0080PA00X+047892Y+098486X0160Y    R180 S0      
317PVDDCR_CPU0_P1   VIA   -    MD0080PA00X+047152Y+098486X0160Y    R180 S0      
317PVDDCR_CPU0_P1   VIA   -    MD0080PA00X+047336Y+098167X0160Y    R180 S0      
317PVDDCR_CPU0_P1   VIA   -    MD0080PA00X+047152Y+097848X0160Y    R180 S0      
317PVDDCR_CPU0_P1   VIA   -    MD0080PA00X+047522Y+097848X0160Y    R180 S0      
317PVDDCR_CPU0_P1   VIA   -    MD0080PA00X+048262Y+096573X0160Y    R180 S0      
317PVDDCR_CPU0_P1   VIA   -    MD0080PA00X+047152Y+096573X0160Y    R180 S0      
317PVDDCR_CPU0_P1   VIA   -    MD0080PA00X+047522Y+096573X0160Y    R180 S0      
317PVDDCR_CPU0_P1   VIA   -    MD0080PA00X+048262Y+095297X0160Y    R180 S0      
317PVDDCR_CPU0_P1   VIA   -    MD0080PA00X+047152Y+095297X0160Y    R180 S0      
317PVDDCR_CPU0_P1   VIA   -    MD0080PA00X+047522Y+095297X0160Y    R180 S0      
317PVDDCR_CPU0_P1   VIA   -    MD0080PA00X+049742Y+089557X0160Y    R180 S0      
317PVDDCR_CPU0_P1   VIA   -    MD0080PA00X+049927Y+088600X0160Y    R180 S0      
317PVDDCR_CPU0_P1   VIA   -    MD0080PA00X+048632Y+089557X0160Y    R180 S0      
317PVDDCR_CPU0_P1   VIA   -    MD0080PA00X+049372Y+089557X0160Y    R180 S0      
317PVDDCR_CPU0_P1   VIA   -    MD0080PA00X+049002Y+088919X0160Y    R180 S0      
317PVDDCR_CPU0_P1   VIA   -    MD0080PA00X+048817Y+088600X0160Y    R180 S0      
317PVDDCR_CPU0_P1   VIA   -    MD0080PA00X+049742Y+087644X0160Y    R180 S0      
317PVDDCR_CPU0_P1   VIA   -    MD0080PA00X+049002Y+087644X0160Y    R180 S0      
317PVDDCR_CPU0_P1   VIA   -    MD0080PA00X+048632Y+087644X0160Y    R180 S0      
317PVDDCR_CPU0_P1   VIA   -    MD0080PA00X+049742Y+094021X0160Y    R180 S0      
317PVDDCR_CPU0_P1   VIA   -    MD0080PA00X+048632Y+094021X0160Y    R180 S0      
317PVDDCR_CPU0_P1   VIA   -    MD0080PA00X+049372Y+094021X0160Y    R180 S0      
317PVDDCR_CPU0_P1   VIA   -    MD0080PA00X+049742Y+092108X0160Y    R180 S0      
317PVDDCR_CPU0_P1   VIA   -    MD0080PA00X+048632Y+092108X0160Y    R180 S0      
317PVDDCR_CPU0_P1   VIA   -    MD0080PA00X+049372Y+092108X0160Y    R180 S0      
317PVDDCR_CPU0_P1   VIA   -    MD0080PA00X+049742Y+090832X0160Y    R180 S0      
317PVDDCR_CPU0_P1   VIA   -    MD0080PA00X+048632Y+090832X0160Y    R180 S0      
317PVDDCR_CPU0_P1   VIA   -    MD0080PA00X+049372Y+090832X0160Y    R180 S0      
317PVDDCR_CPU0_P1   VIA   -    MD0080PA00X+048817Y+098805X0160Y    R180 S0      
317PVDDCR_CPU0_P1   VIA   -    MD0080PA00X+049742Y+097848X0160Y    R180 S0      
317PVDDCR_CPU0_P1   VIA   -    MD0080PA00X+049557Y+098167X0160Y    R180 S0      
317PVDDCR_CPU0_P1   VIA   -    MD0080PA00X+048632Y+098486X0160Y    R180 S0      
317PVDDCR_CPU0_P1   VIA   -    MD0080PA00X+049372Y+098486X0160Y    R180 S0      
317PVDDCR_CPU0_P1   VIA   -    MD0080PA00X+048817Y+098167X0160Y    R180 S0      
317PVDDCR_CPU0_P1   VIA   -    MD0080PA00X+048632Y+097848X0160Y    R180 S0      
317PVDDCR_CPU0_P1   VIA   -    MD0080PA00X+049372Y+097848X0160Y    R180 S0      
317PVDDCR_CPU0_P1   VIA   -    MD0080PA00X+049742Y+096573X0160Y    R180 S0      
317PVDDCR_CPU0_P1   VIA   -    MD0080PA00X+048632Y+096573X0160Y    R180 S0      
317PVDDCR_CPU0_P1   VIA   -    MD0080PA00X+049372Y+096573X0160Y    R180 S0      
317PVDDCR_CPU0_P1   VIA   -    MD0080PA00X+049742Y+095297X0160Y    R180 S0      
317PVDDCR_CPU0_P1   VIA   -    MD0080PA00X+049372Y+095297X0160Y    R180 S0      
317PVDDCR_CPU0_P1   VIA   -    MD0080PA00X+048632Y+095297X0160Y    R180 S0      
317PVDDCR_CPU0_P1   VIA   -    MD0080PA00X+050112Y+087644X0160Y    R180 S0      
317PVDDCR_CPU0_P1   VIA   -    MD0080PA00X+051222Y+087644X0160Y    R180 S0      
317PVDDCR_CPU0_P1   VIA   -    MD0080PA00X+050667Y+087962X0160Y    R180 S0      
317PVDDCR_CPU0_P1   VIA   -    MD0080PA00X+050852Y+087644X0160Y    R180 S0      
317PVDDCR_CPU0_P1   VIA   -    MD0080PA00X+050112Y+088919X0160Y    R180 S0      
327PVDDCR_CPU0_P1   C2294 -1   M      A18X+041820Y+098177X0198Y0197R180 S2      
327PVDDCR_CPU0_P1   C2295 -1   M      A18X+039337Y+096641X0198Y0197R270 S2      
327PVDDCR_CPU0_P1   C2296 -1   M      A18X+047323Y+098777X0198Y0197     S2      
327PVDDCR_CPU0_P1   C2297 -1   M      A18X+046573Y+098177X0198Y0197     S2      
327PVDDCR_CPU0_P1   C2298 -1   M      A18X+042570Y+098177X0198Y0197R180 S2      
327PVDDCR_CPU0_P1   C2300 -1   M      A18X+041070Y+098177X0198Y0197R180 S2      
327PVDDCR_CPU0_P1   C2301 -1   M      A18X+042735Y+098527X0198Y0197     S2      
327PVDDCR_CPU0_P1   C2302 -1   M      A18X+045823Y+098777X0198Y0197     S2      
327PVDDCR_CPU0_P1   C2303 -1   M      A18X+039570Y+098177X0198Y0197R180 S2      
327PVDDCR_CPU0_P1   C2304 -1          A18X+042875Y+097009X0198Y0197     S2      
327PVDDCR_CPU0_P1   C2306 -1   M      A18X+046035Y+096649X0198Y0197     S2      
327PVDDCR_CPU0_P1   C2307 -1   M      A18X+045823Y+098177X0198Y0197     S2      
327PVDDCR_CPU0_P1   C2308 -1   M      A18X+042020Y+096649X0198Y0197R180 S2      
327PVDDCR_CPU0_P1   C2309 -1   M      A18X+041585Y+096649X0198Y0197     S2      
327PVDDCR_CPU0_P1   C2310 -1   M      A18X+038626Y+097827X0198Y0197R180 S2      
327PVDDCR_CPU0_P1   C2312 -1   M      A18X+048823Y+098777X0198Y0197     S2      
327PVDDCR_CPU0_P1   C2313 -1   M      A18X+049523Y+098177X0198Y0197     S2      
327PVDDCR_CPU0_P1   C2314 -1   M      A18X+042008Y+097827X0198Y0197R180 S2      
327PVDDCR_CPU0_P1   C2315 -1   M      A18X+048231Y+097827X0198Y0197     S2      
327PVDDCR_CPU0_P1   C2316 -1   M      A18X+044923Y+098527X0198Y0197     S2      
327PVDDCR_CPU0_P1   C2318 -1   M      A18X+048261Y+096649X0198Y0197     S2      
327PVDDCR_CPU0_P1   C2319 -1   M      A18X+041573Y+097827X0198Y0197     S2      
327PVDDCR_CPU0_P1   C2320 -1   M      A18X+048823Y+098177X0198Y0197     S2      
327PVDDCR_CPU0_P1   C2321 -1   M      A18X+044016Y+097034X0198Y0197R090 S2      
327PVDDCR_CPU0_P1   C2322 -1   M      A18X+043423Y+098527X0198Y0197     S2      
327PVDDCR_CPU0_P1   C2324 -1          A18X+045170Y+096999X0198Y0197R180 S2      
327PVDDCR_CPU0_P1   C2325 -1   M      A18X+048073Y+098177X0198Y0197     S2      
327PVDDCR_CPU0_P1   C2326 -1   M      A18X+039756Y+097827X0198Y0197R180 S2      
327PVDDCR_CPU0_P1   C2327 -1   M      A18X+041767Y+098776X0198Y0197R180 S2      
327PVDDCR_CPU0_P1   C2330 -1   M      A18X+046470Y+096649X0198Y0197R180 S2      
327PVDDCR_CPU0_P1   C2331 -1   M      A18X+046023Y+097827X0198Y0197     S2      
327PVDDCR_CPU0_P1   C2332 -1   M      A18X+044016Y+098534X0198Y0197R090 S2      
327PVDDCR_CPU0_P1   C2333 -1   M      A18X+049361Y+097827X0198Y0197     S2      
327PVDDCR_CPU0_P1   C2335 -1   M      A18X+041070Y+098777X0198Y0197R180 S2      
327PVDDCR_CPU0_P1   C2336 -1          A18X+048727Y+096641X0198Y0197R270 S2      
327PVDDCR_CPU0_P1   C2337 -1   M      A18X+046408Y+097827X0198Y0197R180 S2      
327PVDDCR_CPU0_P1   C2338 -1   M      A18X+045073Y+098177X0198Y0197     S2      
327PVDDCR_CPU0_P1   C2340 -1   M      A18X+043287Y+096890X0198Y0197R240 S2      
327PVDDCR_CPU0_P1   C2341 -1   M      A18X+044016Y+097784X0198Y0197R090 S2      
327PVDDCR_CPU0_P1   C2342 -1   M      A18X+044745Y+096890X0198Y0197R300 S2      
327PVDDCR_CPU0_P1   C2343 -1   M      A18X+040320Y+098177X0198Y0197R180 S2      
327PVDDCR_CPU0_P1   C2345 -1   M      A18X+047323Y+098177X0198Y0197     S2      
327PVDDCR_CPU0_P1   C2346 -1   M      A18X+039770Y+096649X0198Y0197R180 S2      
327PVDDCR_CPU0_P1   C2347 -1   M      A18X+043298Y+098135X0198Y0197R120 S2      
327PVDDCR_CPU0_P1   C2348 -1   M      A18X+040370Y+098777X0198Y0197R180 S2      
327PVDDCR_CPU0_P1   VIA   -           A18X+032889Y+079466X0260Y         S2      
327PVDDCR_CPU0_P1   VIA   -           A18X+041516Y+077418X0260Y         S2      
327PVDDCR_CPU0_P1   VIA   -           A18X+029612Y+077461X0260Y         S2      
327PVDDCR_CPU0_P1   PC305_-1          A18X+043785Y+075496X0400Y0500R270 S2      
327PVDDCR_CPU0_P1   PC304_-1          A18X+040128Y+075656X0400Y0500R270 S2      
327PVDDCR_CPU0_P1   PC275 -1          A18X+038715Y+075848X0950Y1110R090 S2      
327PVDDCR_CPU0_P1   PC282_-1          A18X+037155Y+075688X0400Y0500R270 S2      
327PVDDCR_CPU0_P1   PC276 -1          A18X+035666Y+075851X0950Y1110R090 S2      
327PVDDCR_CPU0_P1   PC283_-1          A18X+034115Y+075688X0400Y0500R270 S2      
327PVDDCR_CPU0_P1   PC277 -1          A18X+032695Y+075851X0950Y1110R090 S2      
327PVDDCR_CPU0_P1   PC302_-1          A18X+031205Y+075688X0400Y0500R270 S2      
327PVDDCR_CPU0_P1   PC105 -1          A18X+042295Y+074058X0950Y1110R090 S2      
327PVDDCR_CPU0_P1   PC303_-1          A18X+040915Y+073898X0400Y0500R270 S2      
327PVDDCR_CPU0_P1   PC280_-1          A18X+030218Y+073703X0400Y0500R270 S2      
327PVDDCR_CPU0_P1   PC279 -1          A18X+028838Y+073836X0950Y1110R090 S2      
327PVDDCR_CPU0_P1   VIA   -           A18X+026329Y+074026X0260Y         S2      
327PVDDCR_CPU0_P1   PC281_-1          A18X+027462Y+073341X0400Y0500R270 S2      
327PVDDCR_CPU0_P1   PC315_-1          A18X+026828Y+070173X0400Y0500R270 S2      
327PVDDCR_CPU0_P1   PC316_-1          A18X+024955Y+070173X0400Y0500R270 S2      
327PVDDCR_CPU0_P1   PC135_-1          A18X+025916Y+070173X0400Y0500R270 S2      
327PVDDCR_CPU0_P1   PC134_-1          A18X+024071Y+070185X0400Y0500R270 S2      
327PVDDCR_CPU0_P1   PR337 -1          A18X+023483Y+069965X0198Y0197R090 S2      
327PVDDCR_CPU0_P1   U26   -M47        A01X+040676Y+090937X0177Y    R180 S1      
327PVDDCR_CPU0_P1   U26   -AB23       A01X+049558Y+094126X0177Y    R180 S1      
327PVDDCR_CPU0_P1   U26   -AB24       A01X+049188Y+094126X0177Y    R180 S1      
327PVDDCR_CPU0_P1   U26   -AB26       A01X+048448Y+094126X0177Y    R180 S1      
327PVDDCR_CPU0_P1   U26   -AB27       A01X+048078Y+094126X0177Y    R180 S1      
327PVDDCR_CPU0_P1   U26   -AB29       A01X+047338Y+094126X0177Y    R180 S1      
327PVDDCR_CPU0_P1   U26   -AB30       A01X+046968Y+094126X0177Y    R180 S1      
327PVDDCR_CPU0_P1   U26   -AB32       A01X+046228Y+094126X0177Y    R180 S1      
327PVDDCR_CPU0_P1   U26   -AB33       A01X+045857Y+094126X0177Y    R180 S1      
327PVDDCR_CPU0_P1   U26   -AB43       A01X+042157Y+094126X0177Y    R180 S1      
327PVDDCR_CPU0_P1   U26   -AB44       A01X+041787Y+094126X0177Y    R180 S1      
327PVDDCR_CPU0_P1   U26   -AB46       A01X+041046Y+094126X0177Y    R180 S1      
327PVDDCR_CPU0_P1   U26   -AB47       A01X+040676Y+094126X0177Y    R180 S1      
327PVDDCR_CPU0_P1   U26   -AB49       A01X+039936Y+094126X0177Y    R180 S1      
327PVDDCR_CPU0_P1   U26   -AB50       A01X+039566Y+094126X0177Y    R180 S1      
327PVDDCR_CPU0_P1   U26   -AB52       A01X+038826Y+094126X0177Y    R180 S1      
327PVDDCR_CPU0_P1   U26   -AB53       A01X+038456Y+094126X0177Y    R180 S1      
327PVDDCR_CPU0_P1   U26   -AC35       A01X+044932Y+094445X0177Y    R180 S1      
327PVDDCR_CPU0_P1   U26   -AC36       A01X+044562Y+094445X0177Y    R180 S1      
327PVDDCR_CPU0_P1   U26   -AC40       A01X+043452Y+094445X0177Y    R180 S1      
327PVDDCR_CPU0_P1   U26   -AC41       A01X+043082Y+094445X0177Y    R180 S1      
327PVDDCR_CPU0_P1   U26   -AF23       A01X+049558Y+095402X0177Y    R180 S1      
327PVDDCR_CPU0_P1   U26   -AF24       A01X+049188Y+095402X0177Y    R180 S1      
327PVDDCR_CPU0_P1   U26   -AF26       A01X+048448Y+095402X0177Y    R180 S1      
327PVDDCR_CPU0_P1   U26   -AF27       A01X+048078Y+095402X0177Y    R180 S1      
327PVDDCR_CPU0_P1   U26   -AF29       A01X+047338Y+095402X0177Y    R180 S1      
327PVDDCR_CPU0_P1   U26   -AF30       A01X+046968Y+095402X0177Y    R180 S1      
327PVDDCR_CPU0_P1   U26   -AF32       A01X+046228Y+095402X0177Y    R180 S1      
327PVDDCR_CPU0_P1   U26   -AF33       A01X+045857Y+095402X0177Y    R180 S1      
327PVDDCR_CPU0_P1   U26   -AF43       A01X+042157Y+095402X0177Y    R180 S1      
327PVDDCR_CPU0_P1   U26   -AF44       A01X+041787Y+095402X0177Y    R180 S1      
327PVDDCR_CPU0_P1   U26   -AF46       A01X+041046Y+095402X0177Y    R180 S1      
327PVDDCR_CPU0_P1   U26   -AF47       A01X+040676Y+095402X0177Y    R180 S1      
327PVDDCR_CPU0_P1   U26   -AF49       A01X+039936Y+095402X0177Y    R180 S1      
327PVDDCR_CPU0_P1   U26   -AF50       A01X+039566Y+095402X0177Y    R180 S1      
327PVDDCR_CPU0_P1   U26   -AF52       A01X+038826Y+095402X0177Y    R180 S1      
327PVDDCR_CPU0_P1   U26   -AF53       A01X+038456Y+095402X0177Y    R180 S1      
327PVDDCR_CPU0_P1   U26   -AG35       A01X+044932Y+095721X0177Y    R180 S1      
327PVDDCR_CPU0_P1   U26   -AG36       A01X+044562Y+095721X0177Y    R180 S1      
327PVDDCR_CPU0_P1   U26   -AG40       A01X+043452Y+095721X0177Y    R180 S1      
327PVDDCR_CPU0_P1   U26   -AG41       A01X+043082Y+095721X0177Y    R180 S1      
327PVDDCR_CPU0_P1   U26   -AK23       A01X+049558Y+096677X0177Y    R180 S1      
327PVDDCR_CPU0_P1   U26   -AK24       A01X+049188Y+096677X0177Y    R180 S1      
327PVDDCR_CPU0_P1   U26   -AK26       A01X+048448Y+096677X0177Y    R180 S1      
327PVDDCR_CPU0_P1   U26   -AK27       A01X+048078Y+096677X0177Y    R180 S1      
327PVDDCR_CPU0_P1   U26   -AK29       A01X+047338Y+096677X0177Y    R180 S1      
327PVDDCR_CPU0_P1   U26   -AK30       A01X+046968Y+096677X0177Y    R180 S1      
327PVDDCR_CPU0_P1   U26   -AK32       A01X+046228Y+096677X0177Y    R180 S1      
327PVDDCR_CPU0_P1   U26   -AK33       A01X+045857Y+096677X0177Y    R180 S1      
327PVDDCR_CPU0_P1   U26   -AK43       A01X+042157Y+096677X0177Y    R180 S1      
327PVDDCR_CPU0_P1   U26   -AK44       A01X+041787Y+096677X0177Y    R180 S1      
327PVDDCR_CPU0_P1   U26   -AK46       A01X+041046Y+096677X0177Y    R180 S1      
327PVDDCR_CPU0_P1   U26   -AK47       A01X+040676Y+096677X0177Y    R180 S1      
327PVDDCR_CPU0_P1   U26   -AK49       A01X+039936Y+096677X0177Y    R180 S1      
327PVDDCR_CPU0_P1   U26   -AK50       A01X+039566Y+096677X0177Y    R180 S1      
327PVDDCR_CPU0_P1   U26   -AK52       A01X+038826Y+096677X0177Y    R180 S1      
327PVDDCR_CPU0_P1   U26   -AK53       A01X+038456Y+096677X0177Y    R180 S1      
327PVDDCR_CPU0_P1   U26   -AL35       A01X+044932Y+096996X0177Y    R180 S1      
327PVDDCR_CPU0_P1   U26   -AL36       A01X+044562Y+096996X0177Y    R180 S1      
327PVDDCR_CPU0_P1   U26   -AL40       A01X+043452Y+096996X0177Y    R180 S1      
327PVDDCR_CPU0_P1   U26   -AL41       A01X+043082Y+096996X0177Y    R180 S1      
327PVDDCR_CPU0_P1   U26   -AP23       A01X+049558Y+097953X0177Y    R180 S1      
327PVDDCR_CPU0_P1   U26   -AP24       A01X+049188Y+097953X0177Y    R180 S1      
327PVDDCR_CPU0_P1   U26   -AP26       A01X+048448Y+097953X0177Y    R180 S1      
327PVDDCR_CPU0_P1   U26   -AP27       A01X+048078Y+097953X0177Y    R180 S1      
327PVDDCR_CPU0_P1   U26   -AP29       A01X+047338Y+097953X0177Y    R180 S1      
327PVDDCR_CPU0_P1   U26   -AP30       A01X+046968Y+097953X0177Y    R180 S1      
327PVDDCR_CPU0_P1   U26   -AP32       A01X+046228Y+097953X0177Y    R180 S1      
327PVDDCR_CPU0_P1   U26   -AP33       A01X+045857Y+097953X0177Y    R180 S1      
327PVDDCR_CPU0_P1   U26   -AP43       A01X+042157Y+097953X0177Y    R180 S1      
327PVDDCR_CPU0_P1   U26   -AP44       A01X+041787Y+097953X0177Y    R180 S1      
327PVDDCR_CPU0_P1   U26   -AP46       A01X+041046Y+097953X0177Y    R180 S1      
327PVDDCR_CPU0_P1   U26   -AP47       A01X+040676Y+097953X0177Y    R180 S1      
327PVDDCR_CPU0_P1   U26   -AP49       A01X+039936Y+097953X0177Y    R180 S1      
327PVDDCR_CPU0_P1   U26   -AP50       A01X+039566Y+097953X0177Y    R180 S1      
327PVDDCR_CPU0_P1   U26   -AP52       A01X+038826Y+097953X0177Y    R180 S1      
327PVDDCR_CPU0_P1   U26   -AP53       A01X+038456Y+097953X0177Y    R180 S1      
327PVDDCR_CPU0_P1   U26   -AR23       A01X+049373Y+098272X0177Y    R180 S1      
327PVDDCR_CPU0_P1   U26   -AR25       A01X+048633Y+098272X0177Y    R180 S1      
327PVDDCR_CPU0_P1   U26   -AR27       A01X+047893Y+098272X0177Y    R180 S1      
327PVDDCR_CPU0_P1   U26   -AR29       A01X+047153Y+098272X0177Y    R180 S1      
327PVDDCR_CPU0_P1   U26   -AR31       A01X+046413Y+098272X0177Y    R180 S1      
327PVDDCR_CPU0_P1   U26   -AR33       A01X+045672Y+098272X0177Y    R180 S1      
327PVDDCR_CPU0_P1   U26   -AR35       A01X+044932Y+098272X0177Y    R180 S1      
327PVDDCR_CPU0_P1   U26   -AR40       A01X+043452Y+098272X0177Y    R180 S1      
327PVDDCR_CPU0_P1   U26   -AR42       A01X+042712Y+098272X0177Y    R180 S1      
327PVDDCR_CPU0_P1   U26   -AR44       A01X+041972Y+098272X0177Y    R180 S1      
327PVDDCR_CPU0_P1   U26   -AR46       A01X+041232Y+098272X0177Y    R180 S1      
327PVDDCR_CPU0_P1   U26   -AR48       A01X+040491Y+098272X0177Y    R180 S1      
327PVDDCR_CPU0_P1   U26   -AR50       A01X+039751Y+098272X0177Y    R180 S1      
327PVDDCR_CPU0_P1   U26   -AT24       A01X+049188Y+098591X0177Y    R180 S1      
327PVDDCR_CPU0_P1   U26   -AT26       A01X+048448Y+098591X0177Y    R180 S1      
327PVDDCR_CPU0_P1   U26   -AT28       A01X+047708Y+098591X0177Y    R180 S1      
327PVDDCR_CPU0_P1   U26   -AT30       A01X+046968Y+098591X0177Y    R180 S1      
327PVDDCR_CPU0_P1   U26   -AT32       A01X+046228Y+098591X0177Y    R180 S1      
327PVDDCR_CPU0_P1   U26   -AT34       A01X+045487Y+098591X0177Y    R180 S1      
327PVDDCR_CPU0_P1   U26   -AT36       A01X+044747Y+098591X0177Y    R180 S1      
327PVDDCR_CPU0_P1   U26   -AT39       A01X+043637Y+098591X0177Y    R180 S1      
327PVDDCR_CPU0_P1   U26   -AT41       A01X+042897Y+098591X0177Y    R180 S1      
327PVDDCR_CPU0_P1   U26   -AT43       A01X+042157Y+098591X0177Y    R180 S1      
327PVDDCR_CPU0_P1   U26   -AT45       A01X+041416Y+098591X0177Y    R180 S1      
327PVDDCR_CPU0_P1   U26   -AT47       A01X+040676Y+098591X0177Y    R180 S1      
327PVDDCR_CPU0_P1   U26   -AT49       A01X+039936Y+098591X0177Y    R180 S1      
327PVDDCR_CPU0_P1   U26   -AU25       A01X+048633Y+098910X0177Y    R180 S1      
327PVDDCR_CPU0_P1   U26   -AU29       A01X+047153Y+098910X0177Y    R180 S1      
327PVDDCR_CPU0_P1   U26   -AU33       A01X+045672Y+098910X0177Y    R180 S1      
327PVDDCR_CPU0_P1   U26   -AU42       A01X+042712Y+098910X0177Y    R180 S1      
327PVDDCR_CPU0_P1   U26   -AU44       A01X+041972Y+098910X0177Y    R180 S1      
327PVDDCR_CPU0_P1   U26   -AU46       A01X+041232Y+098910X0177Y    R180 S1      
327PVDDCR_CPU0_P1   U26   -AU48       A01X+040491Y+098910X0177Y    R180 S1      
327PVDDCR_CPU0_P1   U26   -B19        A01X+051038Y+087748X0177Y    R180 S1      
327PVDDCR_CPU0_P1   U26   -B20        A01X+050668Y+087748X0177Y    R180 S1      
327PVDDCR_CPU0_P1   U26   -B22        A01X+049928Y+087748X0177Y    R180 S1      
327PVDDCR_CPU0_P1   U26   -B23        A01X+049558Y+087748X0177Y    R180 S1      
327PVDDCR_CPU0_P1   U26   -B25        A01X+048818Y+087748X0177Y    R180 S1      
327PVDDCR_CPU0_P1   U26   -B26        A01X+048448Y+087748X0177Y    R180 S1      
327PVDDCR_CPU0_P1   U26   -B28        A01X+047708Y+087748X0177Y    R180 S1      
327PVDDCR_CPU0_P1   U26   -B29        A01X+047338Y+087748X0177Y    R180 S1      
327PVDDCR_CPU0_P1   U26   -B31        A01X+046598Y+087748X0177Y    R180 S1      
327PVDDCR_CPU0_P1   U26   -B32        A01X+046228Y+087748X0177Y    R180 S1      
327PVDDCR_CPU0_P1   U26   -B34        A01X+045487Y+087748X0177Y    R180 S1      
327PVDDCR_CPU0_P1   U26   -B35        A01X+045117Y+087748X0177Y    R180 S1      
327PVDDCR_CPU0_P1   U26   -B41        A01X+042897Y+087748X0177Y    R180 S1      
327PVDDCR_CPU0_P1   U26   -B42        A01X+042527Y+087748X0177Y    R180 S1      
327PVDDCR_CPU0_P1   U26   -B44        A01X+041787Y+087748X0177Y    R180 S1      
327PVDDCR_CPU0_P1   U26   -B45        A01X+041416Y+087748X0177Y    R180 S1      
327PVDDCR_CPU0_P1   U26   -B47        A01X+040676Y+087748X0177Y    R180 S1      
327PVDDCR_CPU0_P1   U26   -B48        A01X+040306Y+087748X0177Y    R180 S1      
327PVDDCR_CPU0_P1   U26   -B50        A01X+039566Y+087748X0177Y    R180 S1      
327PVDDCR_CPU0_P1   U26   -B51        A01X+039196Y+087748X0177Y    R180 S1      
327PVDDCR_CPU0_P1   U26   -B53        A01X+038456Y+087748X0177Y    R180 S1      
327PVDDCR_CPU0_P1   U26   -B54        A01X+038086Y+087748X0177Y    R180 S1      
327PVDDCR_CPU0_P1   U26   -B56        A01X+037346Y+087748X0177Y    R180 S1      
327PVDDCR_CPU0_P1   U26   -B57        A01X+036976Y+087748X0177Y    R180 S1      
327PVDDCR_CPU0_P1   U26   -C20        A01X+050483Y+088067X0177Y    R180 S1      
327PVDDCR_CPU0_P1   U26   -D55        A01X+037716Y+088386X0177Y    R180 S1      
327PVDDCR_CPU0_P1   U26   -D56        A01X+037346Y+088386X0177Y    R180 S1      
327PVDDCR_CPU0_P1   U26   -E22        A01X+049743Y+088705X0177Y    R180 S1      
327PVDDCR_CPU0_P1   U26   -E25        A01X+048633Y+088705X0177Y    R180 S1      
327PVDDCR_CPU0_P1   U26   -E28        A01X+047523Y+088705X0177Y    R180 S1      
327PVDDCR_CPU0_P1   U26   -E31        A01X+046413Y+088705X0177Y    R180 S1      
327PVDDCR_CPU0_P1   U26   -E34        A01X+045302Y+088705X0177Y    R180 S1      
327PVDDCR_CPU0_P1   U26   -E35        A01X+044932Y+088705X0177Y    R180 S1      
327PVDDCR_CPU0_P1   U26   -E42        A01X+042712Y+088705X0177Y    R180 S1      
327PVDDCR_CPU0_P1   U26   -E45        A01X+041602Y+088705X0177Y    R180 S1      
327PVDDCR_CPU0_P1   U26   -E48        A01X+040491Y+088705X0177Y    R180 S1      
327PVDDCR_CPU0_P1   U26   -E51        A01X+039381Y+088705X0177Y    R180 S1      
327PVDDCR_CPU0_P1   U26   -E54        A01X+038271Y+088705X0177Y    R180 S1      
327PVDDCR_CPU0_P1   U26   -F22        A01X+049928Y+089024X0177Y    R180 S1      
327PVDDCR_CPU0_P1   U26   -F25        A01X+048818Y+089024X0177Y    R180 S1      
327PVDDCR_CPU0_P1   U26   -F28        A01X+047708Y+089024X0177Y    R180 S1      
327PVDDCR_CPU0_P1   U26   -F31        A01X+046598Y+089024X0177Y    R180 S1      
327PVDDCR_CPU0_P1   U26   -F34        A01X+045487Y+089024X0177Y    R180 S1      
327PVDDCR_CPU0_P1   U26   -F42        A01X+042527Y+089024X0177Y    R180 S1      
327PVDDCR_CPU0_P1   U26   -F45        A01X+041416Y+089024X0177Y    R180 S1      
327PVDDCR_CPU0_P1   U26   -F48        A01X+040306Y+089024X0177Y    R180 S1      
327PVDDCR_CPU0_P1   U26   -F51        A01X+039196Y+089024X0177Y    R180 S1      
327PVDDCR_CPU0_P1   U26   -F54        A01X+038086Y+089024X0177Y    R180 S1      
327PVDDCR_CPU0_P1   U26   -G35        A01X+044932Y+089343X0177Y    R180 S1      
327PVDDCR_CPU0_P1   U26   -G36        A01X+044562Y+089343X0177Y    R180 S1      
327PVDDCR_CPU0_P1   U26   -G40        A01X+043452Y+089343X0177Y    R180 S1      
327PVDDCR_CPU0_P1   U26   -G41        A01X+043082Y+089343X0177Y    R180 S1      
327PVDDCR_CPU0_P1   U26   -H23        A01X+049558Y+089662X0177Y    R180 S1      
327PVDDCR_CPU0_P1   U26   -H24        A01X+049188Y+089662X0177Y    R180 S1      
327PVDDCR_CPU0_P1   U26   -H26        A01X+048448Y+089662X0177Y    R180 S1      
327PVDDCR_CPU0_P1   U26   -H27        A01X+048078Y+089662X0177Y    R180 S1      
327PVDDCR_CPU0_P1   U26   -H29        A01X+047338Y+089662X0177Y    R180 S1      
327PVDDCR_CPU0_P1   U26   -H30        A01X+046968Y+089662X0177Y    R180 S1      
327PVDDCR_CPU0_P1   U26   -H32        A01X+046228Y+089662X0177Y    R180 S1      
327PVDDCR_CPU0_P1   U26   -H33        A01X+045857Y+089662X0177Y    R180 S1      
327PVDDCR_CPU0_P1   U26   -H43        A01X+042157Y+089662X0177Y    R180 S1      
327PVDDCR_CPU0_P1   U26   -H44        A01X+041787Y+089662X0177Y    R180 S1      
327PVDDCR_CPU0_P1   U26   -H46        A01X+041046Y+089662X0177Y    R180 S1      
327PVDDCR_CPU0_P1   U26   -H47        A01X+040676Y+089662X0177Y    R180 S1      
327PVDDCR_CPU0_P1   U26   -H49        A01X+039936Y+089662X0177Y    R180 S1      
327PVDDCR_CPU0_P1   U26   -H50        A01X+039566Y+089662X0177Y    R180 S1      
327PVDDCR_CPU0_P1   U26   -H52        A01X+038826Y+089662X0177Y    R180 S1      
327PVDDCR_CPU0_P1   U26   -H53        A01X+038456Y+089662X0177Y    R180 S1      
327PVDDCR_CPU0_P1   U26   -J35        A01X+044932Y+089980X0177Y    R180 S1      
327PVDDCR_CPU0_P1   U26   -J36        A01X+044562Y+089980X0177Y    R180 S1      
327PVDDCR_CPU0_P1   U26   -J40        A01X+043452Y+089980X0177Y    R180 S1      
327PVDDCR_CPU0_P1   U26   -J41        A01X+043082Y+089980X0177Y    R180 S1      
327PVDDCR_CPU0_P1   U26   -M23        A01X+049558Y+090937X0177Y    R180 S1      
327PVDDCR_CPU0_P1   U26   -M24        A01X+049188Y+090937X0177Y    R180 S1      
327PVDDCR_CPU0_P1   U26   -M26        A01X+048448Y+090937X0177Y    R180 S1      
327PVDDCR_CPU0_P1   U26   -M27        A01X+048078Y+090937X0177Y    R180 S1      
327PVDDCR_CPU0_P1   U26   -M29        A01X+047338Y+090937X0177Y    R180 S1      
327PVDDCR_CPU0_P1   U26   -M30        A01X+046968Y+090937X0177Y    R180 S1      
327PVDDCR_CPU0_P1   U26   -M32        A01X+046228Y+090937X0177Y    R180 S1      
327PVDDCR_CPU0_P1   U26   -M33        A01X+045857Y+090937X0177Y    R180 S1      
327PVDDCR_CPU0_P1   U26   -M43        A01X+042157Y+090937X0177Y    R180 S1      
327PVDDCR_CPU0_P1   U26   -M44        A01X+041787Y+090937X0177Y    R180 S1      
327PVDDCR_CPU0_P1   U26   -M46        A01X+041046Y+090937X0177Y    R180 S1      
327PVDDCR_CPU0_P1   U26   -M49        A01X+039936Y+090937X0177Y    R180 S1      
327PVDDCR_CPU0_P1   U26   -M50        A01X+039566Y+090937X0177Y    R180 S1      
327PVDDCR_CPU0_P1   U26   -M52        A01X+038826Y+090937X0177Y    R180 S1      
327PVDDCR_CPU0_P1   U26   -M53        A01X+038456Y+090937X0177Y    R180 S1      
327PVDDCR_CPU0_P1   U26   -N35        A01X+044932Y+091256X0177Y    R180 S1      
327PVDDCR_CPU0_P1   U26   -N36        A01X+044562Y+091256X0177Y    R180 S1      
327PVDDCR_CPU0_P1   U26   -N40        A01X+043452Y+091256X0177Y    R180 S1      
327PVDDCR_CPU0_P1   U26   -N41        A01X+043082Y+091256X0177Y    R180 S1      
327PVDDCR_CPU0_P1   U26   -T23        A01X+049558Y+092213X0177Y    R180 S1      
327PVDDCR_CPU0_P1   U26   -T24        A01X+049188Y+092213X0177Y    R180 S1      
327PVDDCR_CPU0_P1   U26   -T26        A01X+048448Y+092213X0177Y    R180 S1      
327PVDDCR_CPU0_P1   U26   -T27        A01X+048078Y+092213X0177Y    R180 S1      
327PVDDCR_CPU0_P1   U26   -T29        A01X+047338Y+092213X0177Y    R180 S1      
327PVDDCR_CPU0_P1   U26   -T30        A01X+046968Y+092213X0177Y    R180 S1      
327PVDDCR_CPU0_P1   U26   -T32        A01X+046228Y+092213X0177Y    R180 S1      
327PVDDCR_CPU0_P1   U26   -T33        A01X+045857Y+092213X0177Y    R180 S1      
327PVDDCR_CPU0_P1   U26   -T43        A01X+042157Y+092213X0177Y    R180 S1      
327PVDDCR_CPU0_P1   U26   -T44        A01X+041787Y+092213X0177Y    R180 S1      
327PVDDCR_CPU0_P1   U26   -T46        A01X+041046Y+092213X0177Y    R180 S1      
327PVDDCR_CPU0_P1   U26   -T47        A01X+040676Y+092213X0177Y    R180 S1      
327PVDDCR_CPU0_P1   U26   -T49        A01X+039936Y+092213X0177Y    R180 S1      
327PVDDCR_CPU0_P1   U26   -T50        A01X+039566Y+092213X0177Y    R180 S1      
327PVDDCR_CPU0_P1   U26   -T52        A01X+038826Y+092213X0177Y    R180 S1      
327PVDDCR_CPU0_P1   U26   -T53        A01X+038456Y+092213X0177Y    R180 S1      
327PVDDCR_CPU0_P1   U26   -U35        A01X+044932Y+092532X0177Y    R180 S1      
327PVDDCR_CPU0_P1   U26   -U36        A01X+044562Y+092532X0177Y    R180 S1      
327PVDDCR_CPU0_P1   U26   -U40        A01X+043452Y+092532X0177Y    R180 S1      
327PVDDCR_CPU0_P1   U26   -U41        A01X+043082Y+092532X0177Y    R180 S1      
327PVDDCR_CPU0_P1   U26   -W29        A01X+047153Y+093169X0177Y    R180 S1      
327PVDDCR_CPU0_P1   U26   -W30        A01X+046783Y+093169X0177Y    R180 S1      
327PVDDCR_CPU0_P1   U26   -W32        A01X+046042Y+093169X0177Y    R180 S1      
327PVDDCR_CPU0_P1   U26   -W33        A01X+045672Y+093169X0177Y    R180 S1      
327PVDDCR_CPU0_P1   U26   -W43        A01X+042342Y+093169X0177Y    R180 S1      
327PVDDCR_CPU0_P1   U26   -W44        A01X+041972Y+093169X0177Y    R180 S1      
327PVDDCR_CPU0_P1   U26   -W46        A01X+041232Y+093169X0177Y    R180 S1      
327PVDDCR_CPU0_P1   U26   -W47        A01X+040861Y+093169X0177Y    R180 S1      
327PVDDCR_CPU0_P1   U26   -Y35        A01X+045117Y+093488X0177Y    R180 S1      
327PVDDCR_CPU0_P1   U26   -Y36        A01X+044747Y+093488X0177Y    R180 S1      
327PVDDCR_CPU0_P1   U26   -Y40        A01X+043267Y+093488X0177Y    R180 S1      
327PVDDCR_CPU0_P1   U26   -Y41        A01X+042897Y+093488X0177Y    R180 S1      
317PVDDCR_CPU0_P1   VIA   -    MD0100PA00X+026339Y+072224X0200Y         S0      
317PVDDCR_CPU0_P1   VIA   -    MD0100PA00X+026589Y+072224X0200Y         S0      
317PVDDCR_CPU0_P1   VIA   -    MD0100PA00X+026329Y+073226X0200Y    R180 S0      
317PVDDCR_CPU0_P1   VIA   -    MD0100PA00X+026579Y+073226X0200Y    R180 S0      
317PVDDCR_CPU0_P1   VIA   -    MD0100PA00X+026329Y+072976X0200Y    R180 S0      
317PVDDCR_CPU0_P1   VIA   -    MD0100PA00X+026579Y+072976X0200Y    R180 S0      
317PVDDCR_CPU0_P1   VIA   -    MD0100PA00X+026329Y+072726X0200Y    R180 S0      
317PVDDCR_CPU0_P1   VIA   -    MD0100PA00X+026579Y+072726X0200Y    R180 S0      
317PVDDCR_CPU0_P1   VIA   -    MD0100PA00X+026329Y+072476X0200Y    R180 S0      
317PVDDCR_CPU0_P1   VIA   -    MD0100PA00X+026579Y+072476X0200Y    R180 S0      
317PVDDCR_CPU0_P1   VIA   -    MD0100PA00X+025009Y+072224X0200Y         S0      
317PVDDCR_CPU0_P1   VIA   -    MD0100PA00X+025259Y+072224X0200Y         S0      
317PVDDCR_CPU0_P1   VIA   -    MD0100PA00X+025259Y+072976X0200Y    R180 S0      
317PVDDCR_CPU0_P1   VIA   -    MD0100PA00X+025259Y+072726X0200Y    R180 S0      
317PVDDCR_CPU0_P1   VIA   -    MD0100PA00X+025009Y+072726X0200Y    R180 S0      
317PVDDCR_CPU0_P1   VIA   -    MD0100PA00X+024759Y+072976X0200Y    R180 S0      
317PVDDCR_CPU0_P1   VIA   -    MD0100PA00X+025009Y+072976X0200Y    R180 S0      
317PVDDCR_CPU0_P1   VIA   -    MD0100PA00X+024759Y+072726X0200Y    R180 S0      
317PVDDCR_CPU0_P1   VIA   -    MD0100PA00X+024759Y+072226X0200Y    R180 S0      
317PVDDCR_CPU0_P1   VIA   -    MD0100PA00X+025009Y+072476X0200Y    R180 S0      
317PVDDCR_CPU0_P1   VIA   -    MD0100PA00X+025259Y+072476X0200Y    R180 S0      
317PVDDCR_CPU0_P1   VIA   -    MD0100PA00X+024759Y+072476X0200Y    R180 S0      
317PVDDCR_CPU0_P1   VIA   -    MD0100PA00X+026329Y+073476X0200Y    R180 S0      
317PVDDCR_CPU0_P1   VIA   -    MD0100PA00X+026579Y+073476X0200Y    R180 S0      
317PVDDCR_CPU0_P1   VIA   -    MD0100PA00X+026329Y+073726X0200Y    R180 S0      
317PVDDCR_CPU0_P1   VIA   -    MD0100PA00X+026579Y+073726X0200Y    R180 S0      
317PVDDCR_CPU0_P1   VIA   -    MD0100PA00X+028282Y+076161X0200Y    R180 S0      
317PVDDCR_CPU0_P1   VIA   -    MD0100PA00X+028032Y+076161X0200Y    R180 S0      
317PVDDCR_CPU0_P1   VIA   -    MD0100PA00X+028032Y+074911X0200Y    R180 S0      
317PVDDCR_CPU0_P1   VIA   -    MD0100PA00X+028032Y+075411X0200Y    R180 S0      
317PVDDCR_CPU0_P1   VIA   -    MD0100PA00X+028032Y+075161X0200Y    R180 S0      
317PVDDCR_CPU0_P1   VIA   -    MD0100PA00X+028032Y+075661X0200Y    R180 S0      
317PVDDCR_CPU0_P1   VIA   -    MD0100PA00X+028032Y+074648X0200Y    R180 S0      
317PVDDCR_CPU0_P1   VIA   -    MD0100PA00X+028282Y+074648X0200Y    R180 S0      
317PVDDCR_CPU0_P1   VIA   -    MD0100PA00X+028532Y+074648X0200Y    R180 S0      
317PVDDCR_CPU0_P1   VIA   -    MD0100PA00X+028282Y+075648X0200Y         S0      
317PVDDCR_CPU0_P1   VIA   -    MD0100PA00X+028532Y+075648X0200Y         S0      
317PVDDCR_CPU0_P1   VIA   -    MD0100PA00X+028282Y+074898X0200Y         S0      
317PVDDCR_CPU0_P1   VIA   -    MD0100PA00X+028282Y+075148X0200Y         S0      
317PVDDCR_CPU0_P1   VIA   -    MD0100PA00X+028282Y+075398X0200Y         S0      
317PVDDCR_CPU0_P1   VIA   -    MD0100PA00X+028532Y+075398X0200Y         S0      
317PVDDCR_CPU0_P1   VIA   -    MD0100PA00X+028532Y+075148X0200Y         S0      
317PVDDCR_CPU0_P1   VIA   -    MD0100PA00X+028532Y+074898X0200Y         S0      
317PVDDCR_CPU0_P1   VIA   -    MD0100PA00X+028532Y+076161X0200Y    R180 S0      
317PVDDCR_CPU0_P1   VIA   -    MD0100PA00X+028282Y+075911X0200Y    R180 S0      
317PVDDCR_CPU0_P1   VIA   -    MD0100PA00X+028532Y+075911X0200Y    R180 S0      
317PVDDCR_CPU0_P1   VIA   -    MD0100PA00X+028032Y+075911X0200Y    R180 S0      
317PVDDCR_CPU0_P1   VIA   -    MD0100PA00X+029862Y+075148X0200Y         S0      
317PVDDCR_CPU0_P1   VIA   -    MD0100PA00X+029862Y+074898X0200Y         S0      
317PVDDCR_CPU0_P1   VIA   -    MD0100PA00X+029862Y+076161X0200Y    R180 S0      
317PVDDCR_CPU0_P1   VIA   -    MD0100PA00X+030112Y+076161X0200Y    R180 S0      
317PVDDCR_CPU0_P1   VIA   -    MD0100PA00X+029862Y+075911X0200Y    R180 S0      
317PVDDCR_CPU0_P1   VIA   -    MD0100PA00X+030112Y+075911X0200Y    R180 S0      
317PVDDCR_CPU0_P1   VIA   -    MD0100PA00X+029612Y+076161X0200Y    R180 S0      
317PVDDCR_CPU0_P1   VIA   -    MD0100PA00X+029612Y+075911X0200Y    R180 S0      
317PVDDCR_CPU0_P1   VIA   -    MD0100PA00X+030112Y+074648X0200Y    R180 S0      
317PVDDCR_CPU0_P1   VIA   -    MD0100PA00X+029612Y+074648X0200Y    R180 S0      
317PVDDCR_CPU0_P1   VIA   -    MD0100PA00X+029862Y+074648X0200Y    R180 S0      
317PVDDCR_CPU0_P1   VIA   -    MD0100PA00X+030112Y+076411X0200Y    R180 S0      
317PVDDCR_CPU0_P1   VIA   -    MD0100PA00X+029862Y+076411X0200Y    R180 S0      
317PVDDCR_CPU0_P1   VIA   -    MD0100PA00X+029862Y+076661X0200Y    R180 S0      
317PVDDCR_CPU0_P1   VIA   -    MD0100PA00X+029612Y+076911X0200Y    R180 S0      
317PVDDCR_CPU0_P1   VIA   -    MD0100PA00X+029612Y+077161X0200Y    R180 S0      
317PVDDCR_CPU0_P1   VIA   -    MD0100PA00X+030112Y+076911X0200Y    R180 S0      
317PVDDCR_CPU0_P1   VIA   -    MD0100PA00X+029862Y+076911X0200Y    R180 S0      
317PVDDCR_CPU0_P1   VIA   -    MD0100PA00X+029862Y+077161X0200Y    R180 S0      
317PVDDCR_CPU0_P1   VIA   -    MD0100PA00X+030112Y+077161X0200Y    R180 S0      
317PVDDCR_CPU0_P1   VIA   -    MD0100PA00X+029612Y+076411X0200Y    R180 S0      
317PVDDCR_CPU0_P1   VIA   -    MD0100PA00X+029612Y+076661X0200Y    R180 S0      
317PVDDCR_CPU0_P1   VIA   -    MD0100PA00X+030112Y+076661X0200Y    R180 S0      
317PVDDCR_CPU0_P1   VIA   -    MD0100PA00X+030112Y+075650X0200Y    R180 S0      
317PVDDCR_CPU0_P1   VIA   -    MD0100PA00X+030112Y+075400X0200Y    R180 S0      
317PVDDCR_CPU0_P1   VIA   -    MD0100PA00X+030112Y+075150X0200Y    R180 S0      
317PVDDCR_CPU0_P1   VIA   -    MD0100PA00X+030112Y+074900X0200Y    R180 S0      
317PVDDCR_CPU0_P1   VIA   -    MD0100PA00X+029612Y+075648X0200Y         S0      
317PVDDCR_CPU0_P1   VIA   -    MD0100PA00X+029862Y+075648X0200Y         S0      
317PVDDCR_CPU0_P1   VIA   -    MD0100PA00X+029612Y+074898X0200Y         S0      
317PVDDCR_CPU0_P1   VIA   -    MD0100PA00X+029612Y+075148X0200Y         S0      
317PVDDCR_CPU0_P1   VIA   -    MD0100PA00X+029612Y+075398X0200Y         S0      
317PVDDCR_CPU0_P1   VIA   -    MD0100PA00X+029862Y+075398X0200Y         S0      
317PVDDCR_CPU0_P1   VIA   -    MD0100PA00X+031809Y+078166X0200Y    R180 S0      
317PVDDCR_CPU0_P1   VIA   -    MD0100PA00X+031809Y+077916X0200Y    R180 S0      
317PVDDCR_CPU0_P1   VIA   -    MD0100PA00X+031809Y+078416X0200Y    R180 S0      
317PVDDCR_CPU0_P1   VIA   -    MD0100PA00X+031809Y+078666X0200Y    R180 S0      
317PVDDCR_CPU0_P1   VIA   -    MD0100PA00X+031309Y+077916X0200Y    R180 S0      
317PVDDCR_CPU0_P1   VIA   -    MD0100PA00X+031559Y+078166X0200Y    R180 S0      
317PVDDCR_CPU0_P1   VIA   -    MD0100PA00X+031309Y+078166X0200Y    R180 S0      
317PVDDCR_CPU0_P1   VIA   -    MD0100PA00X+031559Y+078666X0200Y    R180 S0      
317PVDDCR_CPU0_P1   VIA   -    MD0100PA00X+031309Y+078666X0200Y    R180 S0      
317PVDDCR_CPU0_P1   VIA   -    MD0100PA00X+031559Y+078416X0200Y    R180 S0      
317PVDDCR_CPU0_P1   VIA   -    MD0100PA00X+031309Y+078416X0200Y    R180 S0      
317PVDDCR_CPU0_P1   VIA   -    MD0100PA00X+031559Y+077916X0200Y    R180 S0      
317PVDDCR_CPU0_P1   VIA   -    MD0100PA00X+031559Y+078916X0200Y    R180 S0      
317PVDDCR_CPU0_P1   VIA   -    MD0100PA00X+031309Y+078916X0200Y    R180 S0      
317PVDDCR_CPU0_P1   VIA   -    MD0100PA00X+031809Y+078916X0200Y    R180 S0      
317PVDDCR_CPU0_P1   VIA   -    MD0100PA00X+031559Y+079166X0200Y    R180 S0      
317PVDDCR_CPU0_P1   VIA   -    MD0100PA00X+031309Y+079166X0200Y    R180 S0      
317PVDDCR_CPU0_P1   VIA   -    MD0100PA00X+031809Y+079166X0200Y    R180 S0      
317PVDDCR_CPU0_P1   VIA   -    MD0100PA00X+031809Y+076663X0200Y    R180 S0      
317PVDDCR_CPU0_P1   VIA   -    MD0100PA00X+031559Y+076663X0200Y    R180 S0      
317PVDDCR_CPU0_P1   VIA   -    MD0100PA00X+031309Y+076663X0200Y    R180 S0      
317PVDDCR_CPU0_P1   VIA   -    MD0100PA00X+031559Y+077663X0200Y         S0      
317PVDDCR_CPU0_P1   VIA   -    MD0100PA00X+031809Y+077663X0200Y         S0      
317PVDDCR_CPU0_P1   VIA   -    MD0100PA00X+031559Y+076913X0200Y         S0      
317PVDDCR_CPU0_P1   VIA   -    MD0100PA00X+031559Y+077163X0200Y         S0      
317PVDDCR_CPU0_P1   VIA   -    MD0100PA00X+031559Y+077413X0200Y         S0      
317PVDDCR_CPU0_P1   VIA   -    MD0100PA00X+031809Y+077413X0200Y         S0      
317PVDDCR_CPU0_P1   VIA   -    MD0100PA00X+031809Y+077163X0200Y         S0      
317PVDDCR_CPU0_P1   VIA   -    MD0100PA00X+031809Y+076913X0200Y         S0      
317PVDDCR_CPU0_P1   VIA   -    MD0100PA00X+031309Y+077666X0200Y    R180 S0      
317PVDDCR_CPU0_P1   VIA   -    MD0100PA00X+031309Y+077416X0200Y    R180 S0      
317PVDDCR_CPU0_P1   VIA   -    MD0100PA00X+031309Y+077166X0200Y    R180 S0      
317PVDDCR_CPU0_P1   VIA   -    MD0100PA00X+031309Y+076916X0200Y    R180 S0      
317PVDDCR_CPU0_P1   VIA   -    MD0100PA00X+033139Y+078416X0200Y    R180 S0      
317PVDDCR_CPU0_P1   VIA   -    MD0100PA00X+032889Y+078416X0200Y    R180 S0      
317PVDDCR_CPU0_P1   VIA   -    MD0100PA00X+033389Y+078416X0200Y    R180 S0      
317PVDDCR_CPU0_P1   VIA   -    MD0100PA00X+033139Y+078666X0200Y    R180 S0      
317PVDDCR_CPU0_P1   VIA   -    MD0100PA00X+032889Y+078666X0200Y    R180 S0      
317PVDDCR_CPU0_P1   VIA   -    MD0100PA00X+033389Y+078666X0200Y    R180 S0      
317PVDDCR_CPU0_P1   VIA   -    MD0100PA00X+033139Y+078166X0200Y    R180 S0      
317PVDDCR_CPU0_P1   VIA   -    MD0100PA00X+032889Y+078166X0200Y    R180 S0      
317PVDDCR_CPU0_P1   VIA   -    MD0100PA00X+032889Y+077916X0200Y    R180 S0      
317PVDDCR_CPU0_P1   VIA   -    MD0100PA00X+033139Y+077916X0200Y    R180 S0      
317PVDDCR_CPU0_P1   VIA   -    MD0100PA00X+033389Y+078166X0200Y    R180 S0      
317PVDDCR_CPU0_P1   VIA   -    MD0100PA00X+033389Y+077916X0200Y    R180 S0      
317PVDDCR_CPU0_P1   VIA   -    MD0100PA00X+033139Y+078916X0200Y    R180 S0      
317PVDDCR_CPU0_P1   VIA   -    MD0100PA00X+032889Y+078916X0200Y    R180 S0      
317PVDDCR_CPU0_P1   VIA   -    MD0100PA00X+033389Y+078916X0200Y    R180 S0      
317PVDDCR_CPU0_P1   VIA   -    MD0100PA00X+033139Y+079166X0200Y    R180 S0      
317PVDDCR_CPU0_P1   VIA   -    MD0100PA00X+032889Y+079166X0200Y    R180 S0      
317PVDDCR_CPU0_P1   VIA   -    MD0100PA00X+033389Y+079166X0200Y    R180 S0      
317PVDDCR_CPU0_P1   VIA   -    MD0100PA00X+033389Y+076915X0200Y    R180 S0      
317PVDDCR_CPU0_P1   VIA   -    MD0100PA00X+033389Y+077165X0200Y    R180 S0      
317PVDDCR_CPU0_P1   VIA   -    MD0100PA00X+033389Y+077415X0200Y    R180 S0      
317PVDDCR_CPU0_P1   VIA   -    MD0100PA00X+033389Y+077665X0200Y    R180 S0      
317PVDDCR_CPU0_P1   VIA   -    MD0100PA00X+033139Y+076663X0200Y    R180 S0      
317PVDDCR_CPU0_P1   VIA   -    MD0100PA00X+032889Y+076663X0200Y    R180 S0      
317PVDDCR_CPU0_P1   VIA   -    MD0100PA00X+033389Y+076663X0200Y    R180 S0      
317PVDDCR_CPU0_P1   VIA   -    MD0100PA00X+032889Y+077663X0200Y         S0      
317PVDDCR_CPU0_P1   VIA   -    MD0100PA00X+033139Y+077663X0200Y         S0      
317PVDDCR_CPU0_P1   VIA   -    MD0100PA00X+032889Y+076913X0200Y         S0      
317PVDDCR_CPU0_P1   VIA   -    MD0100PA00X+032889Y+077163X0200Y         S0      
317PVDDCR_CPU0_P1   VIA   -    MD0100PA00X+032889Y+077413X0200Y         S0      
317PVDDCR_CPU0_P1   VIA   -    MD0100PA00X+033139Y+077413X0200Y         S0      
317PVDDCR_CPU0_P1   VIA   -    MD0100PA00X+033139Y+077163X0200Y         S0      
317PVDDCR_CPU0_P1   VIA   -    MD0100PA00X+033139Y+076913X0200Y         S0      
317PVDDCR_CPU0_P1   VIA   -    MD0100PA00X+035105Y+078156X0200Y    R180 S0      
317PVDDCR_CPU0_P1   VIA   -    MD0100PA00X+035105Y+077906X0200Y    R180 S0      
317PVDDCR_CPU0_P1   VIA   -    MD0100PA00X+035105Y+078656X0200Y    R180 S0      
317PVDDCR_CPU0_P1   VIA   -    MD0100PA00X+035105Y+078406X0200Y    R180 S0      
317PVDDCR_CPU0_P1   VIA   -    MD0100PA00X+035105Y+078906X0200Y    R180 S0      
317PVDDCR_CPU0_P1   VIA   -    MD0100PA00X+034855Y+078156X0200Y    R180 S0      
317PVDDCR_CPU0_P1   VIA   -    MD0100PA00X+034605Y+078156X0200Y    R180 S0      
317PVDDCR_CPU0_P1   VIA   -    MD0100PA00X+034855Y+077906X0200Y    R180 S0      
317PVDDCR_CPU0_P1   VIA   -    MD0100PA00X+034605Y+077906X0200Y    R180 S0      
317PVDDCR_CPU0_P1   VIA   -    MD0100PA00X+034855Y+078656X0200Y    R180 S0      
317PVDDCR_CPU0_P1   VIA   -    MD0100PA00X+034605Y+078656X0200Y    R180 S0      
317PVDDCR_CPU0_P1   VIA   -    MD0100PA00X+034855Y+078406X0200Y    R180 S0      
317PVDDCR_CPU0_P1   VIA   -    MD0100PA00X+034605Y+078406X0200Y    R180 S0      
317PVDDCR_CPU0_P1   VIA   -    MD0100PA00X+034855Y+078906X0200Y    R180 S0      
317PVDDCR_CPU0_P1   VIA   -    MD0100PA00X+034605Y+078906X0200Y    R180 S0      
317PVDDCR_CPU0_P1   VIA   -    MD0100PA00X+035105Y+079156X0200Y    R180 S0      
317PVDDCR_CPU0_P1   VIA   -    MD0100PA00X+034855Y+079156X0200Y    R180 S0      
317PVDDCR_CPU0_P1   VIA   -    MD0100PA00X+034605Y+079156X0200Y    R180 S0      
317PVDDCR_CPU0_P1   VIA   -    MD0100PA00X+034615Y+076654X0200Y    R180 S0      
317PVDDCR_CPU0_P1   VIA   -    MD0100PA00X+034865Y+076654X0200Y    R180 S0      
317PVDDCR_CPU0_P1   VIA   -    MD0100PA00X+035115Y+076654X0200Y    R180 S0      
317PVDDCR_CPU0_P1   VIA   -    MD0100PA00X+034865Y+077654X0200Y         S0      
317PVDDCR_CPU0_P1   VIA   -    MD0100PA00X+035115Y+077654X0200Y         S0      
317PVDDCR_CPU0_P1   VIA   -    MD0100PA00X+034865Y+076904X0200Y         S0      
317PVDDCR_CPU0_P1   VIA   -    MD0100PA00X+034865Y+077154X0200Y         S0      
317PVDDCR_CPU0_P1   VIA   -    MD0100PA00X+034865Y+077404X0200Y         S0      
317PVDDCR_CPU0_P1   VIA   -    MD0100PA00X+035115Y+077404X0200Y         S0      
317PVDDCR_CPU0_P1   VIA   -    MD0100PA00X+035115Y+077154X0200Y         S0      
317PVDDCR_CPU0_P1   VIA   -    MD0100PA00X+035115Y+076904X0200Y         S0      
317PVDDCR_CPU0_P1   VIA   -    MD0100PA00X+034605Y+077656X0200Y    R180 S0      
317PVDDCR_CPU0_P1   VIA   -    MD0100PA00X+034605Y+077406X0200Y    R180 S0      
317PVDDCR_CPU0_P1   VIA   -    MD0100PA00X+034605Y+077156X0200Y    R180 S0      
317PVDDCR_CPU0_P1   VIA   -    MD0100PA00X+034605Y+076906X0200Y    R180 S0      
317PVDDCR_CPU0_P1   VIA   -    MD0100PA00X+036195Y+078406X0200Y    R180 S0      
317PVDDCR_CPU0_P1   VIA   -    MD0100PA00X+036195Y+077906X0200Y    R180 S0      
317PVDDCR_CPU0_P1   VIA   -    MD0100PA00X+036445Y+078156X0200Y    R180 S0      
317PVDDCR_CPU0_P1   VIA   -    MD0100PA00X+036445Y+077906X0200Y    R180 S0      
317PVDDCR_CPU0_P1   VIA   -    MD0100PA00X+036195Y+078156X0200Y    R180 S0      
317PVDDCR_CPU0_P1   VIA   -    MD0100PA00X+036445Y+078406X0200Y    R180 S0      
317PVDDCR_CPU0_P1   VIA   -    MD0100PA00X+036195Y+078656X0200Y    R180 S0      
317PVDDCR_CPU0_P1   VIA   -    MD0100PA00X+036195Y+078906X0200Y    R180 S0      
317PVDDCR_CPU0_P1   VIA   -    MD0100PA00X+036445Y+078906X0200Y    R180 S0      
317PVDDCR_CPU0_P1   VIA   -    MD0100PA00X+036445Y+078656X0200Y    R180 S0      
317PVDDCR_CPU0_P1   VIA   -    MD0100PA00X+036195Y+079156X0200Y    R180 S0      
317PVDDCR_CPU0_P1   VIA   -    MD0100PA00X+036445Y+079156X0200Y    R180 S0      
317PVDDCR_CPU0_P1   VIA   -    MD0100PA00X+036195Y+076654X0200Y    R180 S0      
317PVDDCR_CPU0_P1   VIA   -    MD0100PA00X+036445Y+076654X0200Y    R180 S0      
317PVDDCR_CPU0_P1   VIA   -    MD0100PA00X+036195Y+077654X0200Y         S0      
317PVDDCR_CPU0_P1   VIA   -    MD0100PA00X+036445Y+077654X0200Y         S0      
317PVDDCR_CPU0_P1   VIA   -    MD0100PA00X+036195Y+076904X0200Y         S0      
317PVDDCR_CPU0_P1   VIA   -    MD0100PA00X+036195Y+077154X0200Y         S0      
317PVDDCR_CPU0_P1   VIA   -    MD0100PA00X+036195Y+077404X0200Y         S0      
317PVDDCR_CPU0_P1   VIA   -    MD0100PA00X+036445Y+077404X0200Y         S0      
317PVDDCR_CPU0_P1   VIA   -    MD0100PA00X+036445Y+077154X0200Y         S0      
317PVDDCR_CPU0_P1   VIA   -    MD0100PA00X+036445Y+076904X0200Y         S0      
317PVDDCR_CPU0_P1   VIA   -    MD0100PA00X+036695Y+077906X0200Y    R180 S0      
317PVDDCR_CPU0_P1   VIA   -    MD0100PA00X+037919Y+079146X0200Y    R180 S0      
317PVDDCR_CPU0_P1   VIA   -    MD0100PA00X+036695Y+079156X0200Y    R180 S0      
317PVDDCR_CPU0_P1   VIA   -    MD0100PA00X+036695Y+076654X0200Y    R180 S0      
317PVDDCR_CPU0_P1   VIA   -    MD0100PA00X+037919Y+077646X0200Y    R180 S0      
317PVDDCR_CPU0_P1   VIA   -    MD0100PA00X+037919Y+077396X0200Y    R180 S0      
317PVDDCR_CPU0_P1   VIA   -    MD0100PA00X+037919Y+077146X0200Y    R180 S0      
317PVDDCR_CPU0_P1   VIA   -    MD0100PA00X+037919Y+076896X0200Y    R180 S0      
317PVDDCR_CPU0_P1   VIA   -    MD0100PA00X+037919Y+076643X0200Y    R180 S0      
317PVDDCR_CPU0_P1   VIA   -    MD0100PA00X+036695Y+077656X0200Y    R180 S0      
317PVDDCR_CPU0_P1   VIA   -    MD0100PA00X+036695Y+077406X0200Y    R180 S0      
317PVDDCR_CPU0_P1   VIA   -    MD0100PA00X+036695Y+077156X0200Y    R180 S0      
317PVDDCR_CPU0_P1   VIA   -    MD0100PA00X+036695Y+076906X0200Y    R180 S0      
317PVDDCR_CPU0_P1   VIA   -    MD0100PA00X+037919Y+078146X0200Y    R180 S0      
317PVDDCR_CPU0_P1   VIA   -    MD0100PA00X+037919Y+077896X0200Y    R180 S0      
317PVDDCR_CPU0_P1   VIA   -    MD0100PA00X+037919Y+078896X0200Y    R180 S0      
317PVDDCR_CPU0_P1   VIA   -    MD0100PA00X+037919Y+078396X0200Y    R180 S0      
317PVDDCR_CPU0_P1   VIA   -    MD0100PA00X+037919Y+078646X0200Y    R180 S0      
317PVDDCR_CPU0_P1   VIA   -    MD0100PA00X+036695Y+078406X0200Y    R180 S0      
317PVDDCR_CPU0_P1   VIA   -    MD0100PA00X+036695Y+078906X0200Y    R180 S0      
317PVDDCR_CPU0_P1   VIA   -    MD0100PA00X+036695Y+078656X0200Y    R180 S0      
317PVDDCR_CPU0_P1   VIA   -    MD0100PA00X+036695Y+078156X0200Y    R180 S0      
317PVDDCR_CPU0_P1   VIA   -    MD0100PA00X+038419Y+078146X0200Y    R180 S0      
317PVDDCR_CPU0_P1   VIA   -    MD0100PA00X+038419Y+077896X0200Y    R180 S0      
317PVDDCR_CPU0_P1   VIA   -    MD0100PA00X+038419Y+078396X0200Y    R180 S0      
317PVDDCR_CPU0_P1   VIA   -    MD0100PA00X+038419Y+078646X0200Y    R180 S0      
317PVDDCR_CPU0_P1   VIA   -    MD0100PA00X+038419Y+078896X0200Y    R180 S0      
317PVDDCR_CPU0_P1   VIA   -    MD0100PA00X+038169Y+078146X0200Y    R180 S0      
317PVDDCR_CPU0_P1   VIA   -    MD0100PA00X+038169Y+078896X0200Y    R180 S0      
317PVDDCR_CPU0_P1   VIA   -    MD0100PA00X+038169Y+078396X0200Y    R180 S0      
317PVDDCR_CPU0_P1   VIA   -    MD0100PA00X+038169Y+078646X0200Y    R180 S0      
317PVDDCR_CPU0_P1   VIA   -    MD0100PA00X+038169Y+077896X0200Y    R180 S0      
317PVDDCR_CPU0_P1   VIA   -    MD0100PA00X+039499Y+078656X0200Y    R180 S0      
317PVDDCR_CPU0_P1   VIA   -    MD0100PA00X+039499Y+078906X0200Y    R180 S0      
317PVDDCR_CPU0_P1   VIA   -    MD0100PA00X+039499Y+078156X0200Y    R180 S0      
317PVDDCR_CPU0_P1   VIA   -    MD0100PA00X+039499Y+077906X0200Y    R180 S0      
317PVDDCR_CPU0_P1   VIA   -    MD0100PA00X+039499Y+078406X0200Y    R180 S0      
317PVDDCR_CPU0_P1   VIA   -    MD0100PA00X+038419Y+079146X0200Y    R180 S0      
317PVDDCR_CPU0_P1   VIA   -    MD0100PA00X+038169Y+079146X0200Y    R180 S0      
317PVDDCR_CPU0_P1   VIA   -    MD0100PA00X+038169Y+077643X0200Y         S0      
317PVDDCR_CPU0_P1   VIA   -    MD0100PA00X+038419Y+077643X0200Y         S0      
317PVDDCR_CPU0_P1   VIA   -    MD0100PA00X+038169Y+076893X0200Y         S0      
317PVDDCR_CPU0_P1   VIA   -    MD0100PA00X+038169Y+077143X0200Y         S0      
317PVDDCR_CPU0_P1   VIA   -    MD0100PA00X+038169Y+077393X0200Y         S0      
317PVDDCR_CPU0_P1   VIA   -    MD0100PA00X+038419Y+077393X0200Y         S0      
317PVDDCR_CPU0_P1   VIA   -    MD0100PA00X+038419Y+077143X0200Y         S0      
317PVDDCR_CPU0_P1   VIA   -    MD0100PA00X+038419Y+076893X0200Y         S0      
317PVDDCR_CPU0_P1   VIA   -    MD0100PA00X+039499Y+077643X0200Y         S0      
317PVDDCR_CPU0_P1   VIA   -    MD0100PA00X+039499Y+076893X0200Y         S0      
317PVDDCR_CPU0_P1   VIA   -    MD0100PA00X+039499Y+077143X0200Y         S0      
317PVDDCR_CPU0_P1   VIA   -    MD0100PA00X+039499Y+077393X0200Y         S0      
317PVDDCR_CPU0_P1   VIA   -    MD0100PA00X+038419Y+076643X0200Y    R180 S0      
317PVDDCR_CPU0_P1   VIA   -    MD0100PA00X+038169Y+076643X0200Y    R180 S0      
317PVDDCR_CPU0_P1   VIA   -    MD0100PA00X+039499Y+076643X0200Y    R180 S0      
317PVDDCR_CPU0_P1   VIA   -    MD0100PA00X+039999Y+077406X0200Y    R180 S0      
317PVDDCR_CPU0_P1   VIA   -    MD0100PA00X+039999Y+076643X0200Y    R180 S0      
317PVDDCR_CPU0_P1   VIA   -    MD0100PA00X+039999Y+076906X0200Y    R180 S0      
317PVDDCR_CPU0_P1   VIA   -    MD0100PA00X+039999Y+077156X0200Y    R180 S0      
317PVDDCR_CPU0_P1   VIA   -    MD0100PA00X+039749Y+076643X0200Y    R180 S0      
317PVDDCR_CPU0_P1   VIA   -    MD0100PA00X+039999Y+078156X0200Y    R180 S0      
317PVDDCR_CPU0_P1   VIA   -    MD0100PA00X+039999Y+077906X0200Y    R180 S0      
317PVDDCR_CPU0_P1   VIA   -    MD0100PA00X+039999Y+078406X0200Y    R180 S0      
317PVDDCR_CPU0_P1   VIA   -    MD0100PA00X+039749Y+078406X0200Y    R180 S0      
317PVDDCR_CPU0_P1   VIA   -    MD0100PA00X+039749Y+078656X0200Y    R180 S0      
317PVDDCR_CPU0_P1   VIA   -    MD0100PA00X+039749Y+078156X0200Y    R180 S0      
317PVDDCR_CPU0_P1   VIA   -    MD0100PA00X+039749Y+077906X0200Y    R180 S0      
317PVDDCR_CPU0_P1   VIA   -    MD0100PA00X+039749Y+077643X0200Y         S0      
317PVDDCR_CPU0_P1   VIA   -    MD0100PA00X+039749Y+077393X0200Y         S0      
317PVDDCR_CPU0_P1   VIA   -    MD0100PA00X+039749Y+077143X0200Y         S0      
317PVDDCR_CPU0_P1   VIA   -    MD0100PA00X+039749Y+076893X0200Y         S0      
317PVDDCR_CPU0_P1   VIA   -    MD0100PA00X+039999Y+077656X0200Y    R180 S0      
317PVDDCR_CPU0_P1   VIA   -    MD0100PA00X+041516Y+076618X0200Y    R180 S0      
317PVDDCR_CPU0_P1   VIA   -    MD0100PA00X+041516Y+076368X0200Y    R180 S0      
317PVDDCR_CPU0_P1   VIA   -    MD0100PA00X+041766Y+075864X0200Y         S0      
317PVDDCR_CPU0_P1   VIA   -    MD0100PA00X+042016Y+075864X0200Y         S0      
317PVDDCR_CPU0_P1   VIA   -    MD0100PA00X+041766Y+075114X0200Y         S0      
317PVDDCR_CPU0_P1   VIA   -    MD0100PA00X+041766Y+075364X0200Y         S0      
317PVDDCR_CPU0_P1   VIA   -    MD0100PA00X+041766Y+075614X0200Y         S0      
317PVDDCR_CPU0_P1   VIA   -    MD0100PA00X+042016Y+075614X0200Y         S0      
317PVDDCR_CPU0_P1   VIA   -    MD0100PA00X+042016Y+075364X0200Y         S0      
317PVDDCR_CPU0_P1   VIA   -    MD0100PA00X+042016Y+075114X0200Y         S0      
317PVDDCR_CPU0_P1   VIA   -    MD0100PA00X+041516Y+075868X0200Y    R180 S0      
317PVDDCR_CPU0_P1   VIA   -    MD0100PA00X+041766Y+076118X0200Y    R180 S0      
317PVDDCR_CPU0_P1   VIA   -    MD0100PA00X+042016Y+076118X0200Y    R180 S0      
317PVDDCR_CPU0_P1   VIA   -    MD0100PA00X+041516Y+076118X0200Y    R180 S0      
317PVDDCR_CPU0_P1   VIA   -    MD0100PA00X+041516Y+074864X0200Y    R180 S0      
317PVDDCR_CPU0_P1   VIA   -    MD0100PA00X+041766Y+074864X0200Y    R180 S0      
317PVDDCR_CPU0_P1   VIA   -    MD0100PA00X+041516Y+075368X0200Y    R180 S0      
317PVDDCR_CPU0_P1   VIA   -    MD0100PA00X+041516Y+075118X0200Y    R180 S0      
317PVDDCR_CPU0_P1   VIA   -    MD0100PA00X+041516Y+075618X0200Y    R180 S0      
317PVDDCR_CPU0_P1   VIA   -    MD0100PA00X+042016Y+074864X0200Y    R180 S0      
317PVDDCR_CPU0_P1   VIA   -    MD0100PA00X+041766Y+076618X0200Y    R180 S0      
317PVDDCR_CPU0_P1   VIA   -    MD0100PA00X+041766Y+076368X0200Y    R180 S0      
317PVDDCR_CPU0_P1   VIA   -    MD0100PA00X+041516Y+076868X0200Y    R180 S0      
317PVDDCR_CPU0_P1   VIA   -    MD0100PA00X+041766Y+076868X0200Y    R180 S0      
317PVDDCR_CPU0_P1   VIA   -    MD0100PA00X+042016Y+076618X0200Y    R180 S0      
317PVDDCR_CPU0_P1   VIA   -    MD0100PA00X+042016Y+076368X0200Y    R180 S0      
317PVDDCR_CPU0_P1   VIA   -    MD0100PA00X+041516Y+077118X0200Y    R180 S0      
317PVDDCR_CPU0_P1   VIA   -    MD0100PA00X+043096Y+075864X0200Y         S0      
317PVDDCR_CPU0_P1   VIA   -    MD0100PA00X+043096Y+075114X0200Y         S0      
317PVDDCR_CPU0_P1   VIA   -    MD0100PA00X+043096Y+075364X0200Y         S0      
317PVDDCR_CPU0_P1   VIA   -    MD0100PA00X+043096Y+075614X0200Y         S0      
317PVDDCR_CPU0_P1   VIA   -    MD0100PA00X+043346Y+075614X0200Y         S0      
317PVDDCR_CPU0_P1   VIA   -    MD0100PA00X+043346Y+075364X0200Y         S0      
317PVDDCR_CPU0_P1   VIA   -    MD0100PA00X+043346Y+075114X0200Y         S0      
317PVDDCR_CPU0_P1   VIA   -    MD0100PA00X+043346Y+074864X0200Y    R180 S0      
317PVDDCR_CPU0_P1   VIA   -    MD0100PA00X+043096Y+074864X0200Y    R180 S0      
317PVDDCR_CPU0_P1   VIA   -    MD0100PA00X+044016Y+098534X0190Y    R090 S0      
317PVDDCR_CPU0_P1   VIA   -    MD0100PA00X+044016Y+097784X0190Y    R090 S0      
317PVDDCR_CPU0_P1   VIA   -    MD0100PA00X+044016Y+097034X0190Y    R090 S0      
327PVDDCR_CPU0_P1   PL28  -4   M      A01X+032349Y+077288X0950Y1780R090 S1      
327PVDDCR_CPU0_P1   PL29  -4   M      A01X+035655Y+077279X0950Y1780R090 S1      
327PVDDCR_CPU0_P1   PL31  -4   M      A01X+038959Y+077268X0950Y1780R090 S1      
317PVDDCR_CPU0_P1   VIA   -    MD0100PA00X+027146Y+065018X0200Y    R180 S0      
327PVDDCR_CPU0_P1   PR425 -2          A18X+027287Y+065300X0198Y0197R090 S2      
327PVDDCR_CPU0_P1   PR192 -2          A18X+037143Y+070713X0198Y0197R090 S2      
317PVDDCR_CPU0_P1   VIA   -    MD0100PA00X+037002Y+070431X0200Y    R180 S0      
317PVDDCR_CPU0_P1   VIA   -    MD0100PA00X+043606Y+068658X0200Y    R180 S0      
327PVDDCR_CPU0_P1   PR200 -2          A18X+043747Y+068940X0198Y0197R090 S2      
317PVDDCR_CPU0_P1   VIA   -    MD0100PA00X+025259Y+071224X0200Y    R180 S0      
317PVDDCR_CPU0_P1   VIA   -    MD0100PA00X+025009Y+071224X0200Y    R180 S0      
317PVDDCR_CPU0_P1   VIA   -    MD0100PA00X+024759Y+071224X0200Y    R180 S0      
317PVDDCR_CPU0_P1   VIA   -    MD0100PA00X+026589Y+071224X0200Y    R180 S0      
317PVDDCR_CPU0_P1   VIA   -    MD0100PA00X+026339Y+071224X0200Y    R180 S0      
317PVDDCR_CPU0_P1   VIA   -    MD0100PA00X+025009Y+071474X0200Y         S0      
317PVDDCR_CPU0_P1   VIA   -    MD0100PA00X+025009Y+071724X0200Y         S0      
317PVDDCR_CPU0_P1   VIA   -    MD0100PA00X+025009Y+071974X0200Y         S0      
317PVDDCR_CPU0_P1   VIA   -    MD0100PA00X+025259Y+071974X0200Y         S0      
317PVDDCR_CPU0_P1   VIA   -    MD0100PA00X+025259Y+071724X0200Y         S0      
317PVDDCR_CPU0_P1   VIA   -    MD0100PA00X+025259Y+071474X0200Y         S0      
317PVDDCR_CPU0_P1   VIA   -    MD0100PA00X+026339Y+071474X0200Y         S0      
317PVDDCR_CPU0_P1   VIA   -    MD0100PA00X+026339Y+071724X0200Y         S0      
317PVDDCR_CPU0_P1   VIA   -    MD0100PA00X+026339Y+071974X0200Y         S0      
317PVDDCR_CPU0_P1   VIA   -    MD0100PA00X+026589Y+071974X0200Y         S0      
317PVDDCR_CPU0_P1   VIA   -    MD0100PA00X+026589Y+071724X0200Y         S0      
317PVDDCR_CPU0_P1   VIA   -    MD0100PA00X+026589Y+071474X0200Y         S0      
327PVDDCR_CPU0_P1   PL32  -4   M      A01X+042556Y+075489X0950Y1780R090 S1      
327PVDDCR_CPU0_P1   PL33  -4   M      A01X+029072Y+075273X0950Y1780R090 S1      
327PVDDCR_CPU0_P1   PL8   -4   M      A01X+025799Y+071849X0950Y1780R090 S1      
327PVDDCR_CPU0_P1   PC278 -1          A01X+023984Y+071532X0198Y0197R270 S1      
327PVDDCR_CPU0_P1   PR161 -1          A01X+023582Y+071582X0198Y0197R180 S1      
317PVDDCR_CPU0_P1   VIA   -    MD0100PA00X+024759Y+071726X0200Y    R180 S0      
317PVDDCR_CPU0_P1   VIA   -    MD0100PA00X+024759Y+071476X0200Y    R180 S0      
317PVDDCR_CPU0_P1   VIA   -    MD0100PA00X+024759Y+071976X0200Y    R180 S0      
327PVDDCR_CPU0_P1   PR199 -2          A18X+040447Y+070720X0198Y0197R090 S2      
317PVDDCR_CPU0_P1   VIA   -    MD0100PA00X+040306Y+070438X0200Y    R180 S0      
327PVDDCR_CPU0_P1   PR191 -2          A18X+033837Y+070740X0198Y0197R090 S2      
317PVDDCR_CPU0_P1   VIA   -    MD0100PA00X+033696Y+070458X0200Y    R180 S0      
327PVDDCR_CPU0_P1   PR204 -2          A18X+030560Y+068725X0198Y0197R090 S2      
317PVDDCR_CPU0_P1   VIA   -    MD0100PA00X+030419Y+068442X0200Y    R180 S0      
327m3916            PU10  -1          A01X+137846Y+062545X0090Y0240R270 S1      
327m3916            PR433 -1          A18X+138342Y+062549X0198Y0197R090 S2      
317m3916            VIA   -    MD0100PA00X+137973Y+062304X0200Y    R180 S0      
327m3917            PU48  -1          A01X+141116Y+065835X0090Y0240R270 S1      
327m3917            PR355 -1          A18X+141612Y+065839X0198Y0197R090 S2      
317m3917            VIA   -    MD0100PA00X+141243Y+065594X0200Y    R180 S0      
327m3918            PR351 -1          A18X+154752Y+071055X0198Y0197R090 S2      
327m3918            PU47  -1          A01X+154256Y+071051X0090Y0240R270 S1      
317m3918            VIA   -    MD0100PA00X+154383Y+070810X0200Y    R180 S0      
327m3919            PU46  -1          A01X+150976Y+071068X0090Y0240R270 S1      
327m3919            PR350 -1          A18X+151472Y+071055X0198Y0197R090 S2      
317m3919            VIA   -    MD0100PA00X+151103Y+070810X0200Y    R180 S0      
327m3920            PU43  -1          A01X+147667Y+071051X0090Y0240R270 S1      
327m3920            PR325 -1          A18X+148164Y+071055X0198Y0197R090 S2      
317m3920            VIA   -    MD0100PA00X+147795Y+070810X0200Y    R180 S0      
327m3921            PU6   -1          A01X+144376Y+069093X0090Y0240R270 S1      
327m3921            PR324 -1          A18X+144872Y+069097X0198Y0197R090 S2      
317m3921            VIA   -    MD0100PA00X+144503Y+068852X0200Y    R180 S0      
317m3922            VIA   -    M      A01X+150764Y+055437X0200Y    R180 S2      
017m3922            VIA   -    M      A18X+150764Y+055437X0260Y    R180 S2      
017m3922                  -    MD0100PA00X+150764Y+055437                       
327m3922            PR5   -1          A01X+150383Y+055648X0198Y0197R180 S1      
327m3922            PR290 -2          A01X+151068Y+055198X0198Y0197R180 S1      
327m3922            PU42  -45         A18X+150108Y+055654X0070Y0260R270 S2      
327m3922            PC462 -1          A18X+151068Y+055198X0198Y0197R180 S2      
317m3923            VIA   -    M      A01X+150711Y+055006X0300Y    R180 S1      
017m3923            VIA   -    M      A18X+150711Y+055006X0200Y    R180 S1      
017m3923                  -    MD0100PA00X+150711Y+055006                       
327m3923            PR314 -2   M      A01X+151068Y+054798X0198Y0197R180 S1      
327m3923            PR599 -1          A01X+151068Y+054398X0198Y0197     S1      
327m3923            PC7   -1          A18X+151068Y+054798X0198Y0197R180 S2      
327m3923            PU42  -46         A18X+150108Y+055496X0070Y0260R270 S2      
317m3924            VIA   -    MD0100PA00X+144204Y+068234X0200Y    R180 S0      
327m3924            PC473_-1   M      A01X+144491Y+068234X0198Y0197R270 S1      
327m3924            PU6   -39         A01X+144214Y+068847X0090Y0240R180 S1      
327m3924            PU51  -39         A01X+163984Y+063334X0090Y0240R180 S1      
327m3924            PC605_-1   M      A01X+164261Y+062721X0198Y0197     S1      
317m3924            VIA   -    MD0100PA00X+163974Y+062721X0200Y    R180 S0      
317m3924            VIA   -    MD0100PA00X+137674Y+061686X0200Y    R180 S0      
327m3924            PC150_-1   M      A01X+137961Y+061686X0198Y0197R270 S1      
327m3924            PU10  -39         A01X+137684Y+062299X0090Y0240R180 S1      
317m3924            VIA   -    MD0100PA00X+140944Y+064976X0200Y    R180 S0      
327m3924            PC566_-1   M      A01X+141231Y+064976X0198Y0197R270 S1      
327m3924            PU48  -39         A01X+140954Y+065589X0090Y0240R180 S1      
327m3924            PU47  -39         A01X+154094Y+070805X0090Y0240R180 S1      
327m3924            PC545_-1   M      A01X+154371Y+070192X0198Y0197R270 S1      
317m3924            VIA   -    MD0100PA00X+154084Y+070192X0200Y    R180 S0      
317m3924            VIA   -    MD0100PA00X+150804Y+070192X0200Y    R180 S0      
327m3924            PC544_-1   M      A01X+151091Y+070192X0198Y0197R270 S1      
327m3924            PU46  -39         A01X+150814Y+070822X0090Y0240R180 S1      
327m3924            PU50  -39         A01X+160684Y+065234X0090Y0240R180 S1      
327m3924            PC578_-1   M      A01X+160961Y+064621X0198Y0197R270 S1      
317m3924            VIA   -    MD0100PA00X+160674Y+064621X0200Y    R180 S0      
327m3924            PU49  -39         A01X+157407Y+068611X0090Y0240R180 S1      
327m3924            PC577_-1   M      A01X+157684Y+067998X0198Y0197R270 S1      
317m3924            VIA   -    MD0100PA00X+157398Y+067998X0200Y    R180 S0      
317m3924            VIA   -    MD0100PA00X+147496Y+070192X0200Y    R180 S0      
327m3924            PC474_-1   M      A01X+147783Y+070192X0198Y0197R270 S1      
327m3924            PU43  -39         A01X+147506Y+070805X0090Y0240R180 S1      
327m3924            PU42  -48         A18X+150108Y+055182X0070Y0260R270 S2      
327m3924            PC470 -1          A18X+150476Y+054305X0198Y0197R090 S2      
327m3924            PC13  -1          A18X+150076Y+054305X0198Y0197R090 S2      
317m3924            VIA   -    M      A01X+150208Y+054543X0300Y    R180 S1      
017m3924            VIA   -    M      A18X+150208Y+054543X0200Y    R180 S1      
017m3924                  -    MD0100PA00X+150208Y+054543                       
327m3925            VIA   -    M      A18X+137631Y+062350X0260Y         S2      
327m3925            PU10  -3          A01X+137846Y+062899X0090Y0240R270 S1      
327m3925            PU10  -35         A01X+136976Y+062299X0090Y0240R180 S1      
327m3925            PC151 -1          A01X+138351Y+062549X0198Y0197R270 S1      
327m3925            PR430 -2   M      A18X+137810Y+062866X0198Y0197R090 S2      
317m3925            VIA   -    MD0100PA00X+137005Y+061989X0200Y    R180 S0      
317m3925            VIA   -    MD0100PA00X+138351Y+062789X0200Y    R180 S0      
327m3926            VIA   -    M      A18X+140901Y+065640X0260Y         S2      
327m3926            PU48  -3          A01X+141116Y+066189X0090Y0240R270 S1      
327m3926            PC567 -1          A01X+141621Y+065839X0198Y0197R270 S1      
327m3926            PU48  -35         A01X+140246Y+065589X0090Y0240R180 S1      
327m3926            PR352 -2   M      A18X+141080Y+066156X0198Y0197R090 S2      
317m3926            VIA   -    MD0100PA00X+141621Y+066079X0200Y    R180 S0      
317m3926            VIA   -    MD0100PA00X+140275Y+065279X0200Y    R180 S0      
327m3927            VIA   -    M      A18X+154041Y+070856X0260Y         S2      
327m3927            PR345 -2   M      A18X+154220Y+071372X0198Y0197R090 S2      
327m3927            PU47  -35         A01X+153386Y+070805X0090Y0240R180 S1      
327m3927            PU47  -3          A01X+154256Y+071405X0090Y0240R270 S1      
327m3927            PC547 -1          A01X+154761Y+071055X0198Y0197R270 S1      
317m3927            VIA   -    MD0100PA00X+154761Y+071295X0200Y    R180 S0      
317m3927            VIA   -    MD0100PA00X+153415Y+070495X0200Y    R180 S0      
327m3928            VIA   -    M      A18X+150761Y+070856X0260Y         S2      
327m3928            PU46  -35         A01X+150106Y+070822X0090Y0240R180 S1      
327m3928            PR344 -2   M      A18X+150940Y+071372X0198Y0197R090 S2      
327m3928            PC546 -1          A01X+151481Y+071055X0198Y0197R270 S1      
317m3928            VIA   -    MD0100PA00X+151481Y+071295X0200Y    R180 S0      
317m3928            VIA   -    MD0100PA00X+150135Y+070495X0200Y    R180 S0      
327m3928            PU46  -3          A01X+150976Y+071422X0090Y0240R270 S1      
327m3929            VIA   -    M      A18X+147453Y+070856X0260Y         S2      
327m3929            PU43  -3          A01X+147667Y+071405X0090Y0240R270 S1      
327m3929            PC476 -1          A01X+148172Y+071055X0198Y0197R270 S1      
327m3929            PU43  -35         A01X+146797Y+070805X0090Y0240R180 S1      
327m3929            PR319 -2   M      A18X+147632Y+071372X0198Y0197R090 S2      
317m3929            VIA   -    MD0100PA00X+148172Y+071295X0200Y    R180 S0      
317m3929            VIA   -    MD0100PA00X+146827Y+070495X0200Y    R180 S0      
327m3930            VIA   -    M      A18X+144161Y+068898X0260Y         S2      
327m3930            PU6   -3          A01X+144376Y+069447X0090Y0240R270 S1      
327m3930            PU6   -35         A01X+143506Y+068847X0090Y0240R180 S1      
327m3930            PC475 -1          A01X+144881Y+069097X0198Y0197R270 S1      
327m3930            PR318 -2   M      A18X+144340Y+069414X0198Y0197R090 S2      
317m3930            VIA   -    MD0100PA00X+144881Y+069337X0200Y    R180 S0      
317m3930            VIA   -    MD0100PA00X+143535Y+068537X0200Y    R180 S0      
327m3931            PU42  -47         A18X+150108Y+055339X0070Y0260R270 S2      
327m3931            PR316 -1          A18X+151676Y+054305X0198Y0197R090 S2      
327m3931            VIA   -           A18X+150686Y+054646X0260Y    R180 S2      
327m3931            PC471 -1          A18X+151276Y+054305X0198Y0197R090 S2      
327m3931            PC12  -1          A18X+150876Y+054305X0198Y0197R090 S2      
327m3932            PU46  -36         A01X+150283Y+070822X0090Y0240R180 S1      
317m3932            VIA   -    MD0100PA00X+150409Y+070398X0200Y         S0      
327m3932            PU47  -36         A01X+153563Y+070805X0090Y0240R180 S1      
317m3932            VIA   -    MD0100PA00X+153689Y+070398X0200Y    R180 S0      
327m3932            PU48  -36         A01X+140423Y+065589X0090Y0240R180 S1      
317m3932            VIA   -    MD0100PA00X+140549Y+065182X0200Y    R180 S0      
327m3932            PU10  -36         A01X+137153Y+062299X0090Y0240R180 S1      
317m3932            VIA   -    MD0100PA00X+137279Y+061892X0200Y    R180 S0      
327m3932            PU42  -44         A18X+150108Y+055812X0070Y0260R270 S2      
327m3932            PC469 -1   M      A18X+151068Y+055598X0198Y0197R180 S2      
317m3932            VIA   -    M      A01X+151946Y+055634X0300Y    R180 S1      
017m3932            VIA   -    M      A18X+151946Y+055634X0200Y    R180 S1      
017m3932                  -    MD0100PA00X+151946Y+055634                       
327m3932            PU6   -36         A01X+143683Y+068847X0090Y0240R180 S1      
317m3932            VIA   -    MD0100PA00X+143809Y+068440X0200Y    R180 S0      
327m3932            PU43  -36         A01X+146974Y+070805X0090Y0240R180 S1      
317m3932            VIA   -    MD0100PA00X+147101Y+070398X0200Y    R180 S0      
317m3933            VIA   -    M      A01X+147336Y+055838X0200Y    R180 S2      
017m3933            VIA   -    M      A18X+147336Y+055838X0260Y    R180 S2      
017m3933                  -    MD0100PA00X+147336Y+055838                       
327m3933            R8317 -2          A01X+146983Y+055698X0198Y0197     S1      
327m3933            R315  -2          A18X+146983Y+055698X0198Y0197R180 S2      
327m3933            PU42  -18         A18X+147844Y+055969X0070Y0260R270 S2      
317m3934            VIA   -    M      A01X+153969Y+055894X0200Y         S2      
017m3934            VIA   -    M      A18X+153969Y+055894X0260Y         S2      
017m3934                  -    MD0100PA00X+153969Y+055894                       
327m3934            U29   -6          A01X+154012Y+055522X0140Y0440     S1      
327m3934            R315  -1          A18X+146668Y+055698X0198Y0197R180 S2      
317m3934            VIA   -    MD0100PA00X+146250Y+055502X0200Y    R180 S0      
317m3935            VIA   -    MD0100PA00X+136930Y+061732X0200Y    R180 S0      
327m3935            PU10  -34         A01X+136798Y+062299X0090Y0240R180 S1      
317m3935            VIA   -    MD0100PA00X+149060Y+054476X0200Y    R180 S0      
327m3935            PU42  -7          A18X+148897Y+054916X0070Y0260     S2      
317m3936            VIA   -    MD0100PA00X+140200Y+065022X0200Y    R180 S0      
327m3936            PU48  -34         A01X+140068Y+065589X0090Y0240R180 S1      
317m3936            VIA   -    M      A01X+148851Y+054282X0200Y    R180 S2      
017m3936            VIA   -    M      A18X+148851Y+054282X0260Y    R180 S2      
017m3936                  -    MD0100PA00X+148851Y+054282                       
327m3936            PU42  -8          A18X+148740Y+054916X0070Y0260     S2      
327m3937            PU47  -34         A01X+153208Y+070805X0090Y0240R180 S1      
317m3937            VIA   -    MD0100PA00X+153340Y+070238X0200Y    R180 S0      
317m3937            VIA   -    MD0100PA00X+148442Y+054166X0200Y    R180 S0      
327m3937            PU42  -9          A18X+148582Y+054916X0070Y0260     S2      
327m3938            PU46  -34         A01X+149928Y+070822X0090Y0240R180 S1      
317m3938            VIA   -    MD0100PA00X+150060Y+070238X0200Y    R180 S0      
317m3938            VIA   -    MD0100PA00X+148204Y+054252X0200Y    R180 S0      
327m3938            PU42  -10         A18X+148424Y+054916X0070Y0260     S2      
317m3939            VIA   -    MD0100PA00X+146752Y+070238X0200Y    R180 S0      
327m3939            PU43  -34         A01X+146620Y+070805X0090Y0240R180 S1      
317m3939            VIA   -    MD0100PA00X+148126Y+054498X0200Y    R180 S0      
327m3939            PU42  -11         A18X+148267Y+054916X0070Y0260     S2      
317m3940            VIA   -    MD0100PA00X+143460Y+068280X0200Y    R180 S0      
327m3940            PU6   -34         A01X+143328Y+068847X0090Y0240R180 S1      
317m3940            VIA   -    MD0100PA00X+147826Y+054398X0200Y    R180 S0      
327m3940            PU42  -12         A18X+148110Y+054916X0070Y0260     S2      
327m3941            PR345 -1          A18X+154220Y+071687X0198Y0197R090 S2      
317m3941            VIA   -    MD0100PA00X+154761Y+071549X0200Y    R180 S0      
327m3941            PU47  -4          A01X+154256Y+071582X0090Y0240R270 S1      
327m3941            PC549_-1   M      A01X+154761Y+071790X0198Y0197R090 S1      
327m3941            PR344 -1          A18X+150940Y+071687X0198Y0197R090 S2      
317m3941            VIA   -    MD0100PA00X+151481Y+071549X0200Y    R180 S0      
327m3941            PC548_-1   M      A01X+151481Y+071790X0198Y0197R090 S1      
327m3941            PU46  -4          A01X+150976Y+071599X0090Y0240R270 S1      
327m3941            PU51  -4          A01X+164146Y+064111X0090Y0240R270 S1      
327m3941            PR364 -1          A18X+164110Y+064216X0198Y0197R090 S2      
327m3941            PC607_-1   M      A01X+164651Y+064319X0198Y0197R090 S1      
327m3941            PR445 -1          A01X+165415Y+062207X0198Y0197R270 S1      
327m3941            PR446 -1          A01X+164998Y+062212X0198Y0197R270 S1      
317m3941            VIA   -    MD0100PA00X+164651Y+064078X0200Y    R180 S0      
327m3941            VIA   -           A01X+165076Y+062692X0300Y    R180 S1      
327m3941            PC582_-1   M      A01X+161351Y+066219X0198Y0197R090 S1      
327m3941            PU50  -4          A01X+160846Y+066011X0090Y0240R270 S1      
327m3941            PR357 -1          A18X+160810Y+066116X0198Y0197R090 S2      
317m3941            VIA   -    MD0100PA00X+161351Y+065978X0200Y    R180 S0      
327m3941            PU49  -4          A01X+157569Y+069388X0090Y0240R270 S1      
327m3941            PC581_-1   M      A01X+158074Y+069596X0198Y0197R090 S1      
327m3941            PR356 -1          A18X+157534Y+069493X0198Y0197R090 S2      
317m3941            VIA   -    MD0100PA00X+158074Y+069355X0200Y    R180 S0      
327m3941            PC478_-1   M      A01X+148172Y+071790X0198Y0197R090 S1      
327m3941            PU43  -4          A01X+147667Y+071582X0090Y0240R270 S1      
327m3941            PR319 -1          A18X+147632Y+071687X0198Y0197R090 S2      
317m3941            VIA   -    MD0100PA00X+148172Y+071549X0200Y    R180 S0      
327m3941            PC477_-1   M      A01X+144881Y+069832X0198Y0197R090 S1      
327m3941            PU6   -4          A01X+144376Y+069624X0090Y0240R270 S1      
327m3941            PR318 -1          A18X+144340Y+069729X0198Y0197R090 S2      
317m3941            VIA   -    MD0100PA00X+144881Y+069591X0200Y    R180 S0      
327m3941            PC568_-1   M      A01X+141621Y+066574X0198Y0197R090 S1      
327m3941            PU48  -4          A01X+141116Y+066366X0090Y0240R270 S1      
327m3941            PR352 -1          A18X+141080Y+066471X0198Y0197R090 S2      
317m3941            VIA   -    MD0100PA00X+141621Y+066333X0200Y    R180 S0      
327m3941            PC152_-1   M      A01X+138351Y+063284X0198Y0197R090 S1      
327m3941            PU10  -4          A01X+137846Y+063076X0090Y0240R270 S1      
327m3941            PR430 -1          A18X+137810Y+063181X0198Y0197R090 S2      
317m3941            VIA   -    MD0100PA00X+138351Y+063043X0200Y    R180 S0      
327m3942            R8309 -2          A18X+147526Y+054405X0198Y0197R270 S2      
327m3942            PU42  -13         A18X+147844Y+055182X0070Y0260R270 S2      
317m3942            VIA   -    M      A01X+147815Y+054773X0300Y    R180 S1      
017m3942            VIA   -    M      A18X+147815Y+054773X0200Y    R180 S1      
017m3942                  -    MD0100PA00X+147815Y+054773                       
327m3943            R8308 -2          A18X+146983Y+054098X0198Y0197R270 S2      
327m3943            PU42  -14         A18X+147844Y+055339X0070Y0260R270 S2      
317m3943            VIA   -    M      A01X+147265Y+053948X0300Y    R180 S1      
017m3943            VIA   -    M      A18X+147265Y+053948X0200Y    R180 S1      
017m3943                  -    MD0100PA00X+147265Y+053948                       
317m3944            VIA   -    MD0100PA00X+147341Y+054795X0200Y         S2      
327m3944            R8310 -2          A18X+146983Y+054498X0198Y0197R180 S2      
327m3944            PU42  -15         A18X+147844Y+055496X0070Y0260R270 S2      
317m3945            VIA   -    M      A01X+141700Y+046036X0200Y         S2      
017m3945            VIA   -    M      A18X+141700Y+046036X0260Y         S2      
017m3945                  -    MD0100PA00X+141700Y+046036                       
327m3945            R1185 -1          A01X+077923Y+041534X0198Y0197R180 S1      
327m3945            U18   -AB3        A01X+076347Y+042619X0160Y    R090 S1      
317m3945            VIA   -    MD0100PA00X+076501Y+042466X0180Y    R090 S0      
317m3945            VIA   -    MD0100PA00X+102332Y+045111X0200Y         S0      
327m3945            C5011 -1   M      A18X+146583Y+054098X0198Y0197R090 S2      
327m3945            R8310 -1          A18X+146668Y+054498X0198Y0197R180 S2      
317m3946            VIA   -    M      A01X+150747Y+056436X0200Y    R180 S2      
017m3946            VIA   -    M      A18X+150747Y+056436X0260Y    R180 S2      
017m3946                  -    MD0100PA00X+150747Y+056436                       
327m3946            R8313 -2          A01X+151068Y+056398X0198Y0197R180 S1      
327m3946            R8301 -2          A18X+151068Y+056398X0198Y0197     S2      
327m3946            PU42  -41         A18X+150108Y+056284X0070Y0260R270 S2      
317m3947            VIA   -    M      A01X+151912Y+047922X0200Y         S2      
017m3947            VIA   -    M      A18X+151912Y+047922X0260Y         S2      
017m3947                  -    MD0100PA00X+151912Y+047922                       
327m3947            R8301 -1          A18X+151383Y+056398X0198Y0197     S2      
317m3947            VIA   -    MD0100PA00X+151932Y+056198X0200Y    R180 S0      
317m3947            VIA   -    MD0100PA00X+071550Y+038686X0200Y    R090 S0      
327m3947            R231  -1          A01X+071550Y+039329X0198Y0197R090 S1      
327m3948            PR431 -2          A01X+137572Y+061389X0198Y0197     S1      
327m3948            PU10  -37         A01X+137330Y+062299X0090Y0240R180 S1      
327m3948            VIA   -    M      A01X+137476Y+061827X0160Y0041R090 S1      
327m3949            PR353 -2          A01X+140842Y+064679X0198Y0197     S1      
327m3949            PU48  -37         A01X+140600Y+065589X0090Y0240R180 S1      
327m3949            VIA   -    M      A01X+140746Y+065124X0160Y0041R090 S1      
327m3950            PR347 -2          A01X+153982Y+069895X0198Y0197     S1      
327m3950            PU47  -37         A01X+153740Y+070805X0090Y0240R180 S1      
327m3950            VIA   -    M      A01X+153886Y+070345X0160Y0041R090 S1      
327m3951            PU46  -37         A01X+150460Y+070822X0090Y0240R180 S1      
327m3951            PR346 -2          A01X+150702Y+069895X0198Y0197     S1      
327m3951            VIA   -    M      A01X+150606Y+070340X0160Y0041R090 S1      
327m3952            PR321 -2          A01X+147394Y+069895X0198Y0197     S1      
327m3952            PU43  -37         A01X+147152Y+070805X0090Y0240R180 S1      
327m3952            VIA   -    M      A01X+147298Y+070338X0160Y0041R090 S1      
327m3953            PR320 -2          A01X+144102Y+067937X0198Y0197     S1      
327m3953            PU6   -37         A01X+143860Y+068847X0090Y0240R180 S1      
327m3953            VIA   -    M      A01X+144006Y+068384X0160Y0041R090 S1      
327m3954            PU10  -38         A01X+137507Y+062299X0090Y0240R180 S1      
317m3954            VIA   -    MD0100PA00X+137676Y+061950X0200Y    R180 S0      
317m3954            VIA   -    M      A01X+149279Y+057660X0300Y    R180 S1      
017m3954            VIA   -    M      A18X+149279Y+057660X0200Y    R180 S1      
017m3954                  -    MD0100PA00X+149279Y+057660                       
327m3954            PU42  -32         A18X+149212Y+057180X0070Y0260     S2      
327m3955            PU48  -38         A01X+140777Y+065589X0090Y0240R180 S1      
317m3955            VIA   -    MD0100PA00X+140944Y+065227X0200Y    R180 S0      
317m3955            VIA   -    MD0100PA00X+149068Y+058069X0200Y    R180 S0      
327m3955            PU42  -31         A18X+149054Y+057180X0070Y0260     S2      
317m3956            VIA   -    MD0100PA00X+154084Y+070442X0200Y    R180 S0      
327m3956            PU47  -38         A01X+153917Y+070805X0090Y0240R180 S1      
327m3956            PU42  -30         A18X+148897Y+057180X0070Y0260     S2      
317m3956            VIA   -    MD0100PA00X+149168Y+058359X0200Y    R180 S0      
317m3957            VIA   -    M      A01X+148766Y+058575X0200Y    R180 S2      
017m3957            VIA   -    M      A18X+148766Y+058575X0260Y    R180 S2      
017m3957                  -    MD0100PA00X+148766Y+058575                       
327m3957            PU42  -29         A18X+148740Y+057180X0070Y0260     S2      
317m3957            VIA   -    MD0100PA00X+150804Y+070442X0200Y    R180 S0      
327m3957            PU46  -38         A01X+150637Y+070822X0090Y0240R180 S1      
317m3958            VIA   -    MD0100PA00X+147501Y+070449X0200Y    R180 S0      
327m3958            PU43  -38         A01X+147329Y+070805X0090Y0240R180 S1      
317m3958            VIA   -    M      A01X+148435Y+058039X0300Y    R180 S1      
017m3958            VIA   -    M      A18X+148435Y+058039X0200Y    R180 S1      
017m3958                  -    MD0100PA00X+148435Y+058039                       
327m3958            PU42  -28         A18X+148582Y+057180X0070Y0260     S2      
317m3959            VIA   -    M      A01X+148190Y+058548X0200Y    R180 S2      
017m3959            VIA   -    M      A18X+148190Y+058548X0260Y    R180 S2      
017m3959                  -    MD0100PA00X+148190Y+058548                       
317m3959            VIA   -    MD0100PA00X+144209Y+068485X0200Y    R180 S0      
327m3959            PU42  -27         A18X+148424Y+057180X0070Y0260     S2      
327m3959            PU6   -38         A01X+144037Y+068847X0090Y0240R180 S1      
327m3960            R8312 -2          A01X+146983Y+055298X0198Y0197     S1      
327m3960            C468  -1          A18X+146983Y+055298X0198Y0197     S2      
327m3960            PU42  -17         A18X+147844Y+055812X0070Y0260R270 S2      
317m3960            VIA   -    M      A01X+147344Y+055521X0300Y    R180 S1      
017m3960            VIA   -    M      A18X+147344Y+055521X0200Y    R180 S1      
017m3960                  -    MD0100PA00X+147344Y+055521                       
317m3961            VIA   -    M      A01X+145650Y+045700X0200Y         S2      
017m3961            VIA   -    M      A18X+145650Y+045700X0260Y         S2      
017m3961                  -    MD0100PA00X+145650Y+045700                       
317m3961            VIA   -    MD0100PA00X+069895Y+047182X0180Y    R090 S0      
327m3961            U18   -B17        A01X+070048Y+047029X0160Y    R090 S1      
327m3961            R8312 -1          A01X+146668Y+055298X0198Y0197     S1      
317PVDDCR_CPU0_P0   VIA   -    MD0080PA00X+138107Y+090832X0160Y    R180 S0      
317PVDDCR_CPU0_P0   VIA   -    MD0080PA00X+134776Y+087643X0160Y    R180 S0      
317PVDDCR_CPU0_P0   VIA   -    MD0080PA00X+134406Y+087643X0160Y    R180 S0      
317PVDDCR_CPU0_P0   VIA   -    MD0080PA00X+134776Y+088281X0160Y    R180 S0      
317PVDDCR_CPU0_P0   VIA   -    MD0080PA00X+135516Y+088919X0160Y    R180 S0      
317PVDDCR_CPU0_P0   VIA   -    MD0080PA00X+135886Y+089557X0160Y    R180 S0      
317PVDDCR_CPU0_P0   VIA   -    MD0080PA00X+136256Y+089557X0160Y    R180 S0      
317PVDDCR_CPU0_P0   VIA   -    MD0080PA00X+135701Y+088600X0160Y    R180 S0      
317PVDDCR_CPU0_P0   VIA   -    MD0080PA00X+135146Y+088281X0160Y    R180 S0      
317PVDDCR_CPU0_P0   VIA   -    MD0080PA00X+135516Y+087643X0160Y    R180 S0      
317PVDDCR_CPU0_P0   VIA   -    MD0080PA00X+135886Y+087643X0160Y    R180 S0      
317PVDDCR_CPU0_P0   VIA   -    MD0080PA00X+135886Y+090832X0160Y    R180 S0      
317PVDDCR_CPU0_P0   VIA   -    MD0080PA00X+136256Y+090832X0160Y    R180 S0      
317PVDDCR_CPU0_P0   VIA   -    MD0080PA00X+135886Y+094021X0160Y    R180 S0      
317PVDDCR_CPU0_P0   VIA   -    MD0080PA00X+136256Y+094021X0160Y    R180 S0      
317PVDDCR_CPU0_P0   VIA   -    MD0080PA00X+136256Y+092108X0160Y    R180 S0      
317PVDDCR_CPU0_P0   VIA   -    MD0080PA00X+135886Y+092108X0160Y    R180 S0      
317PVDDCR_CPU0_P0   VIA   -    MD0080PA00X+135886Y+096572X0160Y    R180 S0      
317PVDDCR_CPU0_P0   VIA   -    MD0080PA00X+136256Y+096572X0160Y    R180 S0      
317PVDDCR_CPU0_P0   VIA   -    MD0080PA00X+135886Y+095297X0160Y    R180 S0      
317PVDDCR_CPU0_P0   VIA   -    MD0080PA00X+136256Y+095297X0160Y    R180 S0      
317PVDDCR_CPU0_P0   VIA   -    MD0080PA00X+135886Y+097848X0160Y    R180 S0      
317PVDDCR_CPU0_P0   VIA   -    MD0080PA00X+136256Y+097848X0160Y    R180 S0      
317PVDDCR_CPU0_P0   VIA   -    MD0080PA00X+137367Y+090832X0160Y    R180 S0      
317PVDDCR_CPU0_P0   VIA   -    MD0080PA00X+136996Y+090832X0160Y    R180 S0      
317PVDDCR_CPU0_P0   VIA   -    MD0080PA00X+137922Y+088600X0160Y    R180 S0      
317PVDDCR_CPU0_P0   VIA   -    MD0080PA00X+137737Y+088919X0160Y    R180 S0      
317PVDDCR_CPU0_P0   VIA   -    MD0080PA00X+136626Y+088919X0160Y    R180 S0      
317PVDDCR_CPU0_P0   VIA   -    MD0080PA00X+137367Y+089557X0160Y    R180 S0      
317PVDDCR_CPU0_P0   VIA   -    MD0080PA00X+136996Y+089557X0160Y    R180 S0      
317PVDDCR_CPU0_P0   VIA   -    MD0080PA00X+136812Y+088600X0160Y    R180 S0      
317PVDDCR_CPU0_P0   VIA   -    MD0080PA00X+137737Y+087643X0160Y    R180 S0      
317PVDDCR_CPU0_P0   VIA   -    MD0080PA00X+136626Y+087643X0160Y    R180 S0      
317PVDDCR_CPU0_P0   VIA   -    MD0080PA00X+136996Y+087643X0160Y    R180 S0      
317PVDDCR_CPU0_P0   VIA   -    MD0080PA00X+137367Y+096572X0160Y    R180 S0      
317PVDDCR_CPU0_P0   VIA   -    MD0080PA00X+136996Y+096572X0160Y    R180 S0      
317PVDDCR_CPU0_P0   VIA   -    MD0080PA00X+137367Y+095297X0160Y    R180 S0      
317PVDDCR_CPU0_P0   VIA   -    MD0080PA00X+136996Y+095297X0160Y    R180 S0      
317PVDDCR_CPU0_P0   VIA   -    MD0080PA00X+137367Y+094021X0160Y    R180 S0      
317PVDDCR_CPU0_P0   VIA   -    MD0080PA00X+136996Y+094021X0160Y    R180 S0      
317PVDDCR_CPU0_P0   VIA   -    MD0080PA00X+137367Y+092108X0160Y    R180 S0      
317PVDDCR_CPU0_P0   VIA   -    MD0080PA00X+136996Y+092108X0160Y    R180 S0      
317PVDDCR_CPU0_P0   VIA   -    MD0080PA00X+137922Y+098805X0160Y    R180 S0      
317PVDDCR_CPU0_P0   VIA   -    MD0080PA00X+137367Y+098486X0160Y    R180 S0      
317PVDDCR_CPU0_P0   VIA   -    MD0080PA00X+137922Y+098167X0160Y    R180 S0      
317PVDDCR_CPU0_P0   VIA   -    MD0080PA00X+137182Y+098167X0160Y    R180 S0      
317PVDDCR_CPU0_P0   VIA   -    MD0080PA00X+137367Y+097848X0160Y    R180 S0      
317PVDDCR_CPU0_P0   VIA   -    MD0080PA00X+136996Y+097848X0160Y    R180 S0      
317PVDDCR_CPU0_P0   VIA   -    MD0080PA00X+138847Y+088919X0160Y    R180 S0      
317PVDDCR_CPU0_P0   VIA   -    MD0080PA00X+139217Y+089557X0160Y    R180 S0      
317PVDDCR_CPU0_P0   VIA   -    MD0080PA00X+139032Y+088600X0160Y    R180 S0      
317PVDDCR_CPU0_P0   VIA   -    MD0080PA00X+138477Y+089557X0160Y    R180 S0      
317PVDDCR_CPU0_P0   VIA   -    MD0080PA00X+138107Y+089557X0160Y    R180 S0      
317PVDDCR_CPU0_P0   VIA   -    MD0080PA00X+138107Y+087643X0160Y    R180 S0      
317PVDDCR_CPU0_P0   VIA   -    MD0080PA00X+139217Y+087643X0160Y    R180 S0      
317PVDDCR_CPU0_P0   VIA   -    MD0080PA00X+138847Y+087643X0160Y    R180 S0      
317PVDDCR_CPU0_P0   VIA   -    MD0080PA00X+139217Y+094021X0160Y    R180 S0      
317PVDDCR_CPU0_P0   VIA   -    MD0080PA00X+139402Y+093065X0160Y    R180 S0      
317PVDDCR_CPU0_P0   VIA   -    MD0080PA00X+138107Y+094021X0160Y    R180 S0      
317PVDDCR_CPU0_P0   VIA   -    MD0080PA00X+138477Y+094021X0160Y    R180 S0      
317PVDDCR_CPU0_P0   VIA   -    MD0080PA00X+138662Y+093065X0160Y    R180 S0      
317PVDDCR_CPU0_P0   VIA   -    MD0080PA00X+138292Y+093065X0160Y    R180 S0      
317PVDDCR_CPU0_P0   VIA   -    MD0080PA00X+139217Y+092108X0160Y    R180 S0      
317PVDDCR_CPU0_P0   VIA   -    MD0080PA00X+138107Y+092108X0160Y    R180 S0      
317PVDDCR_CPU0_P0   VIA   -    MD0080PA00X+138477Y+092108X0160Y    R180 S0      
317PVDDCR_CPU0_P0   VIA   -    MD0080PA00X+139217Y+090832X0160Y    R180 S0      
317PVDDCR_CPU0_P0   VIA   -    MD0080PA00X+138477Y+090832X0160Y    R180 S0      
317PVDDCR_CPU0_P0   VIA   -    MD0080PA00X+139402Y+098805X0160Y    R180 S0      
317PVDDCR_CPU0_P0   VIA   -    MD0080PA00X+138662Y+098805X0160Y    R180 S0      
317PVDDCR_CPU0_P0   VIA   -    MD0080PA00X+138847Y+098486X0160Y    R180 S0      
317PVDDCR_CPU0_P0   VIA   -    MD0080PA00X+139402Y+098167X0160Y    R180 S0      
317PVDDCR_CPU0_P0   VIA   -    MD0080PA00X+139217Y+097848X0160Y    R180 S0      
317PVDDCR_CPU0_P0   VIA   -    MD0080PA00X+138107Y+098486X0160Y    R180 S0      
317PVDDCR_CPU0_P0   VIA   -    MD0080PA00X+138662Y+098167X0160Y    R180 S0      
317PVDDCR_CPU0_P0   VIA   -    MD0080PA00X+138477Y+097848X0160Y    R180 S0      
317PVDDCR_CPU0_P0   VIA   -    MD0080PA00X+138107Y+097848X0160Y    R180 S0      
317PVDDCR_CPU0_P0   VIA   -    MD0080PA00X+139217Y+096572X0160Y    R180 S0      
317PVDDCR_CPU0_P0   VIA   -    MD0080PA00X+138107Y+096572X0160Y    R180 S0      
317PVDDCR_CPU0_P0   VIA   -    MD0080PA00X+138477Y+096572X0160Y    R180 S0      
317PVDDCR_CPU0_P0   VIA   -    MD0080PA00X+139217Y+095297X0160Y    R180 S0      
317PVDDCR_CPU0_P0   VIA   -    MD0080PA00X+138107Y+095297X0160Y    R180 S0      
317PVDDCR_CPU0_P0   VIA   -    MD0080PA00X+138477Y+095297X0160Y    R180 S0      
317PVDDCR_CPU0_P0   VIA   -    MD0080PA00X+140512Y+089238X0160Y    R180 S0      
317PVDDCR_CPU0_P0   VIA   -    MD0080PA00X+140882Y+089238X0160Y    R180 S0      
317PVDDCR_CPU0_P0   VIA   -    MD0080PA00X+139957Y+088919X0160Y    R180 S0      
317PVDDCR_CPU0_P0   VIA   -    MD0080PA00X+139587Y+089557X0160Y    R180 S0      
317PVDDCR_CPU0_P0   VIA   -    MD0080PA00X+140142Y+088600X0160Y    R180 S0      
317PVDDCR_CPU0_P0   VIA   -    MD0080PA00X+140327Y+087643X0160Y    R180 S0      
317PVDDCR_CPU0_P0   VIA   -    MD0080PA00X+139957Y+087643X0160Y    R180 S0      
317PVDDCR_CPU0_P0   VIA   -    MD0080PA00X+140327Y+093384X0160Y    R180 S0      
317PVDDCR_CPU0_P0   VIA   -    MD0080PA00X+140697Y+093384X0160Y    R180 S0      
317PVDDCR_CPU0_P0   VIA   -    MD0080PA00X+139587Y+094021X0160Y    R180 S0      
317PVDDCR_CPU0_P0   VIA   -    MD0080PA00X+139772Y+093065X0160Y    R180 S0      
317PVDDCR_CPU0_P0   VIA   -    MD0080PA00X+140512Y+092427X0160Y    R180 S0      
317PVDDCR_CPU0_P0   VIA   -    MD0080PA00X+140882Y+092427X0160Y    R180 S0      
317PVDDCR_CPU0_P0   VIA   -    MD0080PA00X+139587Y+092108X0160Y    R180 S0      
317PVDDCR_CPU0_P0   VIA   -    MD0080PA00X+140512Y+089876X0160Y    R180 S0      
317PVDDCR_CPU0_P0   VIA   -    MD0080PA00X+140882Y+089876X0160Y    R180 S0      
317PVDDCR_CPU0_P0   VIA   -    MD0080PA00X+140512Y+091151X0160Y    R180 S0      
317PVDDCR_CPU0_P0   VIA   -    MD0080PA00X+140882Y+091151X0160Y    R180 S0      
317PVDDCR_CPU0_P0   VIA   -    MD0080PA00X+139587Y+090832X0160Y    R180 S0      
317PVDDCR_CPU0_P0   VIA   -    MD0080PA00X+140142Y+098805X0160Y    R180 S0      
317PVDDCR_CPU0_P0   VIA   -    MD0080PA00X+140327Y+098486X0160Y    R180 S0      
317PVDDCR_CPU0_P0   VIA   -    MD0080PA00X+140882Y+098167X0160Y    R180 S0      
317PVDDCR_CPU0_P0   VIA   -    MD0080PA00X+139587Y+098486X0160Y    R180 S0      
317PVDDCR_CPU0_P0   VIA   -    MD0080PA00X+140142Y+098167X0160Y    R180 S0      
317PVDDCR_CPU0_P0   VIA   -    MD0080PA00X+139587Y+097848X0160Y    R180 S0      
317PVDDCR_CPU0_P0   VIA   -    MD0080PA00X+140882Y+096891X0160Y    R180 S0      
317PVDDCR_CPU0_P0   VIA   -    MD0080PA00X+139587Y+096572X0160Y    R180 S0      
317PVDDCR_CPU0_P0   VIA   -    MD0080PA00X+140512Y+096891X0160Y    R180 S0      
317PVDDCR_CPU0_P0   VIA   -    MD0080PA00X+140882Y+095616X0160Y    R180 S0      
317PVDDCR_CPU0_P0   VIA   -    MD0080PA00X+140512Y+095616X0160Y    R180 S0      
317PVDDCR_CPU0_P0   VIA   -    MD0080PA00X+140882Y+094340X0160Y    R180 S0      
317PVDDCR_CPU0_P0   VIA   -    MD0080PA00X+140512Y+094340X0160Y    R180 S0      
317PVDDCR_CPU0_P0   VIA   -    MD0080PA00X+139587Y+095297X0160Y    R180 S0      
317PVDDCR_CPU0_P0   VIA   -    MD0080PA00X+142360Y+092427X0160Y    R180 S0      
317PVDDCR_CPU0_P0   VIA   -    MD0080PA00X+142360Y+089876X0160Y    R180 S0      
317PVDDCR_CPU0_P0   VIA   -    MD0080PA00X+142360Y+091151X0160Y    R180 S0      
317PVDDCR_CPU0_P0   VIA   -    MD0080PA00X+142360Y+089238X0160Y    R180 S0      
317PVDDCR_CPU0_P0   VIA   -    MD0080PA00X+141067Y+098486X0160Y    R180 S0      
317PVDDCR_CPU0_P0   VIA   -    MD0080PA00X+142360Y+096891X0160Y    R180 S0      
317PVDDCR_CPU0_P0   VIA   -    MD0080PA00X+142360Y+095616X0160Y    R180 S0      
317PVDDCR_CPU0_P0   VIA   -    MD0080PA00X+142360Y+094340X0160Y    R180 S0      
317PVDDCR_CPU0_P0   VIA   -    MD0080PA00X+143655Y+089557X0160Y    R180 S0      
317PVDDCR_CPU0_P0   VIA   -    MD0080PA00X+143285Y+088919X0160Y    R180 S0      
317PVDDCR_CPU0_P0   VIA   -    MD0080PA00X+142730Y+089238X0160Y    R180 S0      
317PVDDCR_CPU0_P0   VIA   -    MD0080PA00X+142730Y+088600X0160Y    R180 S0      
317PVDDCR_CPU0_P0   VIA   -    MD0080PA00X+143100Y+088600X0160Y    R180 S0      
317PVDDCR_CPU0_P0   VIA   -    MD0080PA00X+143285Y+087643X0160Y    R180 S0      
317PVDDCR_CPU0_P0   VIA   -    MD0080PA00X+142915Y+087643X0160Y    R180 S0      
317PVDDCR_CPU0_P0   VIA   -    MD0080PA00X+142730Y+089876X0160Y    R180 S0      
317PVDDCR_CPU0_P0   VIA   -    MD0080PA00X+143655Y+090832X0160Y    R180 S0      
317PVDDCR_CPU0_P0   VIA   -    MD0080PA00X+142730Y+091151X0160Y    R180 S0      
317PVDDCR_CPU0_P0   VIA   -    MD0080PA00X+143655Y+094021X0160Y    R180 S0      
317PVDDCR_CPU0_P0   VIA   -    MD0080PA00X+143840Y+093065X0160Y    R180 S0      
317PVDDCR_CPU0_P0   VIA   -    MD0080PA00X+143470Y+093065X0160Y    R180 S0      
317PVDDCR_CPU0_P0   VIA   -    MD0080PA00X+142545Y+093384X0160Y    R180 S0      
317PVDDCR_CPU0_P0   VIA   -    MD0080PA00X+142915Y+093384X0160Y    R180 S0      
317PVDDCR_CPU0_P0   VIA   -    MD0080PA00X+143655Y+092108X0160Y    R180 S0      
317PVDDCR_CPU0_P0   VIA   -    MD0080PA00X+142730Y+092427X0160Y    R180 S0      
317PVDDCR_CPU0_P0   VIA   -    MD0080PA00X+143655Y+095297X0160Y    R180 S0      
317PVDDCR_CPU0_P0   VIA   -    MD0080PA00X+142730Y+095616X0160Y    R180 S0      
317PVDDCR_CPU0_P0   VIA   -    MD0080PA00X+142730Y+094340X0160Y    R180 S0      
317PVDDCR_CPU0_P0   VIA   -    MD0080PA00X+143655Y+096572X0160Y    R180 S0      
317PVDDCR_CPU0_P0   VIA   -    MD0080PA00X+142730Y+096891X0160Y    R180 S0      
317PVDDCR_CPU0_P0   VIA   -    MD0080PA00X+143470Y+098805X0160Y    R180 S0      
317PVDDCR_CPU0_P0   VIA   -    MD0080PA00X+143655Y+097848X0160Y    R180 S0      
317PVDDCR_CPU0_P0   VIA   -    MD0080PA00X+143285Y+098486X0160Y    R180 S0      
317PVDDCR_CPU0_P0   VIA   -    MD0080PA00X+142545Y+098486X0160Y    R180 S0      
317PVDDCR_CPU0_P0   VIA   -    MD0080PA00X+143470Y+098167X0160Y    R180 S0      
317PVDDCR_CPU0_P0   VIA   -    MD0080PA00X+142730Y+098167X0160Y    R180 S0      
317PVDDCR_CPU0_P0   VIA   -    MD0080PA00X+145136Y+087643X0160Y    R180 S0      
317PVDDCR_CPU0_P0   VIA   -    MD0080PA00X+144026Y+087643X0160Y    R180 S0      
317PVDDCR_CPU0_P0   VIA   -    MD0080PA00X+144396Y+087643X0160Y    R180 S0      
317PVDDCR_CPU0_P0   VIA   -    MD0080PA00X+145136Y+090832X0160Y    R180 S0      
317PVDDCR_CPU0_P0   VIA   -    MD0080PA00X+144026Y+090832X0160Y    R180 S0      
317PVDDCR_CPU0_P0   VIA   -    MD0080PA00X+144766Y+090832X0160Y    R180 S0      
317PVDDCR_CPU0_P0   VIA   -    MD0080PA00X+145136Y+089557X0160Y    R180 S0      
317PVDDCR_CPU0_P0   VIA   -    MD0080PA00X+145321Y+088600X0160Y    R180 S0      
317PVDDCR_CPU0_P0   VIA   -    MD0080PA00X+144026Y+089557X0160Y    R180 S0      
317PVDDCR_CPU0_P0   VIA   -    MD0080PA00X+144766Y+089557X0160Y    R180 S0      
317PVDDCR_CPU0_P0   VIA   -    MD0080PA00X+144396Y+088919X0160Y    R180 S0      
317PVDDCR_CPU0_P0   VIA   -    MD0080PA00X+144211Y+088600X0160Y    R180 S0      
317PVDDCR_CPU0_P0   VIA   -    MD0080PA00X+145136Y+095297X0160Y    R180 S0      
317PVDDCR_CPU0_P0   VIA   -    MD0080PA00X+144026Y+095297X0160Y    R180 S0      
317PVDDCR_CPU0_P0   VIA   -    MD0080PA00X+144766Y+095297X0160Y    R180 S0      
317PVDDCR_CPU0_P0   VIA   -    MD0080PA00X+145136Y+094021X0160Y    R180 S0      
317PVDDCR_CPU0_P0   VIA   -    MD0080PA00X+144026Y+094021X0160Y    R180 S0      
317PVDDCR_CPU0_P0   VIA   -    MD0080PA00X+144766Y+094021X0160Y    R180 S0      
317PVDDCR_CPU0_P0   VIA   -    MD0080PA00X+144951Y+093065X0160Y    R180 S0      
317PVDDCR_CPU0_P0   VIA   -    MD0080PA00X+144581Y+093065X0160Y    R180 S0      
317PVDDCR_CPU0_P0   VIA   -    MD0080PA00X+145136Y+092108X0160Y    R180 S0      
317PVDDCR_CPU0_P0   VIA   -    MD0080PA00X+144026Y+092108X0160Y    R180 S0      
317PVDDCR_CPU0_P0   VIA   -    MD0080PA00X+144766Y+092108X0160Y    R180 S0      
317PVDDCR_CPU0_P0   VIA   -    MD0080PA00X+144951Y+098805X0160Y    R180 S0      
317PVDDCR_CPU0_P0   VIA   -    MD0080PA00X+145136Y+097848X0160Y    R180 S0      
317PVDDCR_CPU0_P0   VIA   -    MD0080PA00X+144026Y+098486X0160Y    R180 S0      
317PVDDCR_CPU0_P0   VIA   -    MD0080PA00X+144766Y+098486X0160Y    R180 S0      
317PVDDCR_CPU0_P0   VIA   -    MD0080PA00X+144951Y+098167X0160Y    R180 S0      
317PVDDCR_CPU0_P0   VIA   -    MD0080PA00X+144211Y+098167X0160Y    R180 S0      
317PVDDCR_CPU0_P0   VIA   -    MD0080PA00X+144766Y+097848X0160Y    R180 S0      
317PVDDCR_CPU0_P0   VIA   -    MD0080PA00X+144026Y+097848X0160Y    R180 S0      
317PVDDCR_CPU0_P0   VIA   -    MD0080PA00X+145136Y+096572X0160Y    R180 S0      
317PVDDCR_CPU0_P0   VIA   -    MD0080PA00X+144766Y+096572X0160Y    R180 S0      
317PVDDCR_CPU0_P0   VIA   -    MD0080PA00X+144026Y+096572X0160Y    R180 S0      
317PVDDCR_CPU0_P0   VIA   -    MD0080PA00X+145506Y+088919X0160Y    R180 S0      
317PVDDCR_CPU0_P0   VIA   -    MD0080PA00X+146616Y+088919X0160Y    R180 S0      
317PVDDCR_CPU0_P0   VIA   -    MD0080PA00X+146246Y+089557X0160Y    R180 S0      
317PVDDCR_CPU0_P0   VIA   -    MD0080PA00X+145876Y+089557X0160Y    R180 S0      
317PVDDCR_CPU0_P0   VIA   -    MD0080PA00X+146431Y+088600X0160Y    R180 S0      
317PVDDCR_CPU0_P0   VIA   -    MD0080PA00X+146616Y+087643X0160Y    R180 S0      
317PVDDCR_CPU0_P0   VIA   -    MD0080PA00X+145506Y+087643X0160Y    R180 S0      
317PVDDCR_CPU0_P0   VIA   -    MD0080PA00X+146246Y+087643X0160Y    R180 S0      
317PVDDCR_CPU0_P0   VIA   -    MD0080PA00X+146246Y+090832X0160Y    R180 S0      
317PVDDCR_CPU0_P0   VIA   -    MD0080PA00X+145876Y+090832X0160Y    R180 S0      
317PVDDCR_CPU0_P0   VIA   -    MD0080PA00X+145876Y+094021X0160Y    R180 S0      
317PVDDCR_CPU0_P0   VIA   -    MD0080PA00X+146246Y+094021X0160Y    R180 S0      
317PVDDCR_CPU0_P0   VIA   -    MD0080PA00X+146246Y+092108X0160Y    R180 S0      
317PVDDCR_CPU0_P0   VIA   -    MD0080PA00X+145876Y+092108X0160Y    R180 S0      
317PVDDCR_CPU0_P0   VIA   -    MD0080PA00X+145876Y+096572X0160Y    R180 S0      
317PVDDCR_CPU0_P0   VIA   -    MD0080PA00X+146246Y+096572X0160Y    R180 S0      
317PVDDCR_CPU0_P0   VIA   -    MD0080PA00X+146246Y+095297X0160Y    R180 S0      
317PVDDCR_CPU0_P0   VIA   -    MD0080PA00X+145876Y+095297X0160Y    R180 S0      
317PVDDCR_CPU0_P0   VIA   -    MD0080PA00X+146431Y+098805X0160Y    R180 S0      
317PVDDCR_CPU0_P0   VIA   -    MD0080PA00X+145506Y+098486X0160Y    R180 S0      
317PVDDCR_CPU0_P0   VIA   -    MD0080PA00X+146246Y+098486X0160Y    R180 S0      
317PVDDCR_CPU0_P0   VIA   -    MD0080PA00X+145691Y+098167X0160Y    R180 S0      
317PVDDCR_CPU0_P0   VIA   -    MD0080PA00X+146431Y+098167X0160Y    R180 S0      
317PVDDCR_CPU0_P0   VIA   -    MD0080PA00X+145876Y+097848X0160Y    R180 S0      
317PVDDCR_CPU0_P0   VIA   -    MD0080PA00X+146246Y+097848X0160Y    R180 S0      
317PVDDCR_CPU0_P0   VIA   -    MD0080PA00X+147726Y+087643X0160Y    R180 S0      
317PVDDCR_CPU0_P0   VIA   -    MD0080PA00X+147356Y+087643X0160Y    R180 S0      
317PVDDCR_CPU0_P0   VIA   -    MD0080PA00X+148281Y+087962X0160Y    R180 S0      
317PVDDCR_CPU0_P0   VIA   -    MD0080PA00X+147356Y+090832X0160Y    R180 S0      
317PVDDCR_CPU0_P0   VIA   -    MD0080PA00X+146986Y+090832X0160Y    R180 S0      
317PVDDCR_CPU0_P0   VIA   -    MD0080PA00X+146986Y+089557X0160Y    R180 S0      
317PVDDCR_CPU0_P0   VIA   -    MD0080PA00X+147356Y+089557X0160Y    R180 S0      
317PVDDCR_CPU0_P0   VIA   -    MD0080PA00X+147726Y+088919X0160Y    R180 S0      
317PVDDCR_CPU0_P0   VIA   -    MD0080PA00X+147541Y+088600X0160Y    R180 S0      
317PVDDCR_CPU0_P0   VIA   -    MD0080PA00X+147356Y+094021X0160Y    R180 S0      
317PVDDCR_CPU0_P0   VIA   -    MD0080PA00X+146986Y+094021X0160Y    R180 S0      
317PVDDCR_CPU0_P0   VIA   -    MD0080PA00X+146986Y+092108X0160Y    R180 S0      
317PVDDCR_CPU0_P0   VIA   -    MD0080PA00X+147356Y+092108X0160Y    R180 S0      
317PVDDCR_CPU0_P0   VIA   -    MD0080PA00X+146986Y+095297X0160Y    R180 S0      
317PVDDCR_CPU0_P0   VIA   -    MD0080PA00X+147356Y+095297X0160Y    R180 S0      
317PVDDCR_CPU0_P0   VIA   -    MD0080PA00X+146986Y+098486X0160Y    R180 S0      
317PVDDCR_CPU0_P0   VIA   -    MD0080PA00X+146986Y+097848X0160Y    R180 S0      
317PVDDCR_CPU0_P0   VIA   -    MD0080PA00X+147356Y+097848X0160Y    R180 S0      
317PVDDCR_CPU0_P0   VIA   -    MD0080PA00X+147171Y+098167X0160Y    R180 S0      
317PVDDCR_CPU0_P0   VIA   -    MD0080PA00X+146986Y+096572X0160Y    R180 S0      
317PVDDCR_CPU0_P0   VIA   -    MD0080PA00X+147356Y+096572X0160Y    R180 S0      
317PVDDCR_CPU0_P0   VIA   -    MD0080PA00X+148836Y+087643X0160Y    R180 S0      
317PVDDCR_CPU0_P0   VIA   -    MD0080PA00X+148466Y+087643X0160Y    R180 S0      
327PVDDCR_CPU0_P0   C245  -1   M      A18X+139225Y+096649X0198Y0197     S2      
327PVDDCR_CPU0_P0   C246  -1   M      A18X+143438Y+098176X0198Y0197     S2      
327PVDDCR_CPU0_P0   C251  -1   M      A18X+141630Y+097034X0198Y0197R090 S2      
327PVDDCR_CPU0_P0   C252  -1   M      A18X+139610Y+096649X0198Y0197R180 S2      
327PVDDCR_CPU0_P0   C263  -1   M      A18X+139623Y+097826X0198Y0197R180 S2      
327PVDDCR_CPU0_P0   C267  -1   M      A18X+143625Y+096649X0198Y0197     S2      
327PVDDCR_CPU0_P0   C268  -1   M      A18X+140160Y+098176X0198Y0197R180 S2      
327PVDDCR_CPU0_P0   C270  -1   M      A18X+140347Y+098526X0198Y0197     S2      
327PVDDCR_CPU0_P0   C271  -1   M      A18X+144938Y+098776X0198Y0197     S2      
327PVDDCR_CPU0_P0   C272  -1   M      A18X+147138Y+098176X0198Y0197     S2      
327PVDDCR_CPU0_P0   C273  -1   M      A18X+139460Y+098176X0198Y0197R180 S2      
327PVDDCR_CPU0_P0   C274  -1   M      A18X+146438Y+098176X0198Y0197     S2      
327PVDDCR_CPU0_P0   C275  -1   M      A18X+136240Y+097826X0198Y0197R180 S2      
327PVDDCR_CPU0_P0   C276  -1   M      A18X+137960Y+098776X0198Y0197R180 S2      
327PVDDCR_CPU0_P0   C277  -1   M      A18X+144060Y+096649X0198Y0197R180 S2      
327PVDDCR_CPU0_P0   C278  -1   M      A18X+138710Y+098176X0198Y0197R180 S2      
327PVDDCR_CPU0_P0   C279  -1   M      A18X+141038Y+098526X0198Y0197     S2      
327PVDDCR_CPU0_P0   C1922 -1   M      A18X+137960Y+098176X0198Y0197R180 S2      
327PVDDCR_CPU0_P0   C2165 -1   M      A18X+138660Y+098776X0198Y0197R180 S2      
327PVDDCR_CPU0_P0   C2166 -1   M      A18X+146438Y+098776X0198Y0197     S2      
327PVDDCR_CPU0_P0   C2167 -1   M      A18X+137210Y+098176X0198Y0197R180 S2      
327PVDDCR_CPU0_P0   C2169 -1   M      A18X+144023Y+097826X0198Y0197R180 S2      
327PVDDCR_CPU0_P0   C2170 -1   M      A18X+139380Y+098776X0198Y0197R180 S2      
327PVDDCR_CPU0_P0   C2171 -1   M      A18X+142359Y+096890X0198Y0197R300 S2      
327PVDDCR_CPU0_P0   C2173 -1   M      A18X+144938Y+098176X0198Y0197     S2      
327PVDDCR_CPU0_P0   C2174 -1   M      A18X+143638Y+097826X0198Y0197     S2      
327PVDDCR_CPU0_P0   C2175 -1   M      A18X+142697Y+098176X0198Y0197     S2      
327PVDDCR_CPU0_P0   C2177 -1   M      A18X+145658Y+098176X0198Y0197     S2      
327PVDDCR_CPU0_P0   C2178 -1   M      A18X+139188Y+097826X0198Y0197     S2      
327PVDDCR_CPU0_P0   C2181 -1   M      A18X+146975Y+097826X0198Y0197     S2      
327PVDDCR_CPU0_P0   C2182 -1   M      A18X+140889Y+098135X0198Y0197R120 S2      
327PVDDCR_CPU0_P0   C2183 -1   M      A18X+136968Y+096641X0198Y0197R270 S2      
327PVDDCR_CPU0_P0   C2185 -1          A18X+142760Y+096999X0198Y0197R180 S2      
327PVDDCR_CPU0_P0   C2186 -1   M      A18X+141630Y+098534X0198Y0197R090 S2      
327PVDDCR_CPU0_P0   C2189 -1   M      A18X+137410Y+096649X0198Y0197R180 S2      
327PVDDCR_CPU0_P0   C2190 -1   M      A18X+140901Y+096890X0198Y0197R240 S2      
327PVDDCR_CPU0_P0   C2192 -1   M      A18X+145875Y+096649X0198Y0197     S2      
327PVDDCR_CPU0_P0   C2193 -1   M      A18X+141630Y+097784X0198Y0197R090 S2      
327PVDDCR_CPU0_P0   C2195 -1   M      A18X+145845Y+097826X0198Y0197     S2      
327PVDDCR_CPU0_P0   C2196 -1   M      A18X+142538Y+098526X0198Y0197     S2      
327PVDDCR_CPU0_P0   C2198 -1   M      A18X+146318Y+096641X0198Y0197R270 S2      
327PVDDCR_CPU0_P0   C2199 -1          A18X+140475Y+096999X0198Y0197     S2      
327PVDDCR_CPU0_P0   C4178 -1   M      A18X+137370Y+097826X0198Y0197R180 S2      
327PVDDCR_CPU0_P0   C4179 -1   M      A18X+143438Y+098776X0198Y0197     S2      
327PVDDCR_CPU0_P0   C10179-1   M      A18X+144188Y+098176X0198Y0197     S2      
327PVDDCR_CPU0_P0   U25   -M47        A01X+138290Y+090937X0177Y    R180 S1      
327PVDDCR_CPU0_P0   U25   -AB23       A01X+147172Y+094126X0177Y    R180 S1      
327PVDDCR_CPU0_P0   U25   -AB24       A01X+146802Y+094126X0177Y    R180 S1      
327PVDDCR_CPU0_P0   U25   -AB26       A01X+146062Y+094126X0177Y    R180 S1      
327PVDDCR_CPU0_P0   U25   -AB27       A01X+145692Y+094126X0177Y    R180 S1      
327PVDDCR_CPU0_P0   U25   -AB29       A01X+144952Y+094126X0177Y    R180 S1      
327PVDDCR_CPU0_P0   U25   -AB30       A01X+144582Y+094126X0177Y    R180 S1      
327PVDDCR_CPU0_P0   U25   -AB32       A01X+143842Y+094126X0177Y    R180 S1      
327PVDDCR_CPU0_P0   U25   -AB33       A01X+143472Y+094126X0177Y    R180 S1      
327PVDDCR_CPU0_P0   U25   -AB43       A01X+139771Y+094126X0177Y    R180 S1      
327PVDDCR_CPU0_P0   U25   -AB44       A01X+139401Y+094126X0177Y    R180 S1      
327PVDDCR_CPU0_P0   U25   -AB46       A01X+138661Y+094126X0177Y    R180 S1      
327PVDDCR_CPU0_P0   U25   -AB47       A01X+138290Y+094126X0177Y    R180 S1      
327PVDDCR_CPU0_P0   U25   -AB49       A01X+137550Y+094126X0177Y    R180 S1      
327PVDDCR_CPU0_P0   U25   -AB50       A01X+137180Y+094126X0177Y    R180 S1      
327PVDDCR_CPU0_P0   U25   -AB52       A01X+136440Y+094126X0177Y    R180 S1      
327PVDDCR_CPU0_P0   U25   -AB53       A01X+136070Y+094126X0177Y    R180 S1      
327PVDDCR_CPU0_P0   U25   -AC35       A01X+142546Y+094445X0177Y    R180 S1      
327PVDDCR_CPU0_P0   U25   -AC36       A01X+142176Y+094445X0177Y    R180 S1      
327PVDDCR_CPU0_P0   U25   -AC40       A01X+141066Y+094445X0177Y    R180 S1      
327PVDDCR_CPU0_P0   U25   -AC41       A01X+140696Y+094445X0177Y    R180 S1      
327PVDDCR_CPU0_P0   U25   -AF23       A01X+147172Y+095402X0177Y    R180 S1      
327PVDDCR_CPU0_P0   U25   -AF24       A01X+146802Y+095402X0177Y    R180 S1      
327PVDDCR_CPU0_P0   U25   -AF26       A01X+146062Y+095402X0177Y    R180 S1      
327PVDDCR_CPU0_P0   U25   -AF27       A01X+145692Y+095402X0177Y    R180 S1      
327PVDDCR_CPU0_P0   U25   -AF29       A01X+144952Y+095402X0177Y    R180 S1      
327PVDDCR_CPU0_P0   U25   -AF30       A01X+144582Y+095402X0177Y    R180 S1      
327PVDDCR_CPU0_P0   U25   -AF32       A01X+143842Y+095402X0177Y    R180 S1      
327PVDDCR_CPU0_P0   U25   -AF33       A01X+143472Y+095402X0177Y    R180 S1      
327PVDDCR_CPU0_P0   U25   -AF43       A01X+139771Y+095402X0177Y    R180 S1      
327PVDDCR_CPU0_P0   U25   -AF44       A01X+139401Y+095402X0177Y    R180 S1      
327PVDDCR_CPU0_P0   U25   -AF46       A01X+138661Y+095402X0177Y    R180 S1      
327PVDDCR_CPU0_P0   U25   -AF47       A01X+138290Y+095402X0177Y    R180 S1      
327PVDDCR_CPU0_P0   U25   -AF49       A01X+137550Y+095402X0177Y    R180 S1      
327PVDDCR_CPU0_P0   U25   -AF50       A01X+137180Y+095402X0177Y    R180 S1      
327PVDDCR_CPU0_P0   U25   -AF52       A01X+136440Y+095402X0177Y    R180 S1      
327PVDDCR_CPU0_P0   U25   -AF53       A01X+136070Y+095402X0177Y    R180 S1      
327PVDDCR_CPU0_P0   U25   -AG35       A01X+142546Y+095720X0177Y    R180 S1      
327PVDDCR_CPU0_P0   U25   -AG36       A01X+142176Y+095720X0177Y    R180 S1      
327PVDDCR_CPU0_P0   U25   -AG40       A01X+141066Y+095720X0177Y    R180 S1      
327PVDDCR_CPU0_P0   U25   -AG41       A01X+140696Y+095720X0177Y    R180 S1      
327PVDDCR_CPU0_P0   U25   -AK23       A01X+147172Y+096677X0177Y    R180 S1      
327PVDDCR_CPU0_P0   U25   -AK24       A01X+146802Y+096677X0177Y    R180 S1      
327PVDDCR_CPU0_P0   U25   -AK26       A01X+146062Y+096677X0177Y    R180 S1      
327PVDDCR_CPU0_P0   U25   -AK27       A01X+145692Y+096677X0177Y    R180 S1      
327PVDDCR_CPU0_P0   U25   -AK29       A01X+144952Y+096677X0177Y    R180 S1      
327PVDDCR_CPU0_P0   U25   -AK30       A01X+144582Y+096677X0177Y    R180 S1      
327PVDDCR_CPU0_P0   U25   -AK32       A01X+143842Y+096677X0177Y    R180 S1      
327PVDDCR_CPU0_P0   U25   -AK33       A01X+143472Y+096677X0177Y    R180 S1      
327PVDDCR_CPU0_P0   U25   -AK43       A01X+139771Y+096677X0177Y    R180 S1      
327PVDDCR_CPU0_P0   U25   -AK44       A01X+139401Y+096677X0177Y    R180 S1      
327PVDDCR_CPU0_P0   U25   -AK46       A01X+138661Y+096677X0177Y    R180 S1      
327PVDDCR_CPU0_P0   U25   -AK47       A01X+138290Y+096677X0177Y    R180 S1      
327PVDDCR_CPU0_P0   U25   -AK49       A01X+137550Y+096677X0177Y    R180 S1      
327PVDDCR_CPU0_P0   U25   -AK50       A01X+137180Y+096677X0177Y    R180 S1      
327PVDDCR_CPU0_P0   U25   -AK52       A01X+136440Y+096677X0177Y    R180 S1      
327PVDDCR_CPU0_P0   U25   -AK53       A01X+136070Y+096677X0177Y    R180 S1      
327PVDDCR_CPU0_P0   U25   -AL35       A01X+142546Y+096996X0177Y    R180 S1      
327PVDDCR_CPU0_P0   U25   -AL36       A01X+142176Y+096996X0177Y    R180 S1      
327PVDDCR_CPU0_P0   U25   -AL40       A01X+141066Y+096996X0177Y    R180 S1      
327PVDDCR_CPU0_P0   U25   -AL41       A01X+140696Y+096996X0177Y    R180 S1      
327PVDDCR_CPU0_P0   U25   -AP23       A01X+147172Y+097953X0177Y    R180 S1      
327PVDDCR_CPU0_P0   U25   -AP24       A01X+146802Y+097953X0177Y    R180 S1      
327PVDDCR_CPU0_P0   U25   -AP26       A01X+146062Y+097953X0177Y    R180 S1      
327PVDDCR_CPU0_P0   U25   -AP27       A01X+145692Y+097953X0177Y    R180 S1      
327PVDDCR_CPU0_P0   U25   -AP29       A01X+144952Y+097953X0177Y    R180 S1      
327PVDDCR_CPU0_P0   U25   -AP30       A01X+144582Y+097953X0177Y    R180 S1      
327PVDDCR_CPU0_P0   U25   -AP32       A01X+143842Y+097953X0177Y    R180 S1      
327PVDDCR_CPU0_P0   U25   -AP33       A01X+143472Y+097953X0177Y    R180 S1      
327PVDDCR_CPU0_P0   U25   -AP43       A01X+139771Y+097953X0177Y    R180 S1      
327PVDDCR_CPU0_P0   U25   -AP44       A01X+139401Y+097953X0177Y    R180 S1      
327PVDDCR_CPU0_P0   U25   -AP46       A01X+138661Y+097953X0177Y    R180 S1      
327PVDDCR_CPU0_P0   U25   -AP47       A01X+138290Y+097953X0177Y    R180 S1      
327PVDDCR_CPU0_P0   U25   -AP49       A01X+137550Y+097953X0177Y    R180 S1      
327PVDDCR_CPU0_P0   U25   -AP50       A01X+137180Y+097953X0177Y    R180 S1      
327PVDDCR_CPU0_P0   U25   -AP52       A01X+136440Y+097953X0177Y    R180 S1      
327PVDDCR_CPU0_P0   U25   -AP53       A01X+136070Y+097953X0177Y    R180 S1      
327PVDDCR_CPU0_P0   U25   -AR23       A01X+146987Y+098272X0177Y    R180 S1      
327PVDDCR_CPU0_P0   U25   -AR25       A01X+146247Y+098272X0177Y    R180 S1      
327PVDDCR_CPU0_P0   U25   -AR27       A01X+145507Y+098272X0177Y    R180 S1      
327PVDDCR_CPU0_P0   U25   -AR29       A01X+144767Y+098272X0177Y    R180 S1      
327PVDDCR_CPU0_P0   U25   -AR31       A01X+144027Y+098272X0177Y    R180 S1      
327PVDDCR_CPU0_P0   U25   -AR33       A01X+143287Y+098272X0177Y    R180 S1      
327PVDDCR_CPU0_P0   U25   -AR35       A01X+142546Y+098272X0177Y    R180 S1      
327PVDDCR_CPU0_P0   U25   -AR40       A01X+141066Y+098272X0177Y    R180 S1      
327PVDDCR_CPU0_P0   U25   -AR42       A01X+140326Y+098272X0177Y    R180 S1      
327PVDDCR_CPU0_P0   U25   -AR44       A01X+139586Y+098272X0177Y    R180 S1      
327PVDDCR_CPU0_P0   U25   -AR46       A01X+138846Y+098272X0177Y    R180 S1      
327PVDDCR_CPU0_P0   U25   -AR48       A01X+138106Y+098272X0177Y    R180 S1      
327PVDDCR_CPU0_P0   U25   -AR50       A01X+137365Y+098272X0177Y    R180 S1      
327PVDDCR_CPU0_P0   U25   -AT24       A01X+146802Y+098591X0177Y    R180 S1      
327PVDDCR_CPU0_P0   U25   -AT26       A01X+146062Y+098591X0177Y    R180 S1      
327PVDDCR_CPU0_P0   U25   -AT28       A01X+145322Y+098591X0177Y    R180 S1      
327PVDDCR_CPU0_P0   U25   -AT30       A01X+144582Y+098591X0177Y    R180 S1      
327PVDDCR_CPU0_P0   U25   -AT32       A01X+143842Y+098591X0177Y    R180 S1      
327PVDDCR_CPU0_P0   U25   -AT34       A01X+143102Y+098591X0177Y    R180 S1      
327PVDDCR_CPU0_P0   U25   -AT36       A01X+142361Y+098591X0177Y    R180 S1      
327PVDDCR_CPU0_P0   U25   -AT39       A01X+141251Y+098591X0177Y    R180 S1      
327PVDDCR_CPU0_P0   U25   -AT41       A01X+140511Y+098591X0177Y    R180 S1      
327PVDDCR_CPU0_P0   U25   -AT43       A01X+139771Y+098591X0177Y    R180 S1      
327PVDDCR_CPU0_P0   U25   -AT45       A01X+139031Y+098591X0177Y    R180 S1      
327PVDDCR_CPU0_P0   U25   -AT47       A01X+138290Y+098591X0177Y    R180 S1      
327PVDDCR_CPU0_P0   U25   -AT49       A01X+137550Y+098591X0177Y    R180 S1      
327PVDDCR_CPU0_P0   U25   -AU25       A01X+146247Y+098910X0177Y    R180 S1      
327PVDDCR_CPU0_P0   U25   -AU29       A01X+144767Y+098910X0177Y    R180 S1      
327PVDDCR_CPU0_P0   U25   -AU33       A01X+143287Y+098910X0177Y    R180 S1      
327PVDDCR_CPU0_P0   U25   -AU42       A01X+140326Y+098910X0177Y    R180 S1      
327PVDDCR_CPU0_P0   U25   -AU44       A01X+139586Y+098910X0177Y    R180 S1      
327PVDDCR_CPU0_P0   U25   -AU46       A01X+138846Y+098910X0177Y    R180 S1      
327PVDDCR_CPU0_P0   U25   -AU48       A01X+138106Y+098910X0177Y    R180 S1      
327PVDDCR_CPU0_P0   U25   -B19        A01X+148653Y+087748X0177Y    R180 S1      
327PVDDCR_CPU0_P0   U25   -B20        A01X+148283Y+087748X0177Y    R180 S1      
327PVDDCR_CPU0_P0   U25   -B22        A01X+147542Y+087748X0177Y    R180 S1      
327PVDDCR_CPU0_P0   U25   -B23        A01X+147172Y+087748X0177Y    R180 S1      
327PVDDCR_CPU0_P0   U25   -B25        A01X+146432Y+087748X0177Y    R180 S1      
327PVDDCR_CPU0_P0   U25   -B26        A01X+146062Y+087748X0177Y    R180 S1      
327PVDDCR_CPU0_P0   U25   -B28        A01X+145322Y+087748X0177Y    R180 S1      
327PVDDCR_CPU0_P0   U25   -B29        A01X+144952Y+087748X0177Y    R180 S1      
327PVDDCR_CPU0_P0   U25   -B31        A01X+144212Y+087748X0177Y    R180 S1      
327PVDDCR_CPU0_P0   U25   -B32        A01X+143842Y+087748X0177Y    R180 S1      
327PVDDCR_CPU0_P0   U25   -B34        A01X+143102Y+087748X0177Y    R180 S1      
327PVDDCR_CPU0_P0   U25   -B35        A01X+142732Y+087748X0177Y    R180 S1      
327PVDDCR_CPU0_P0   U25   -B41        A01X+140511Y+087748X0177Y    R180 S1      
327PVDDCR_CPU0_P0   U25   -B42        A01X+140141Y+087748X0177Y    R180 S1      
327PVDDCR_CPU0_P0   U25   -B44        A01X+139401Y+087748X0177Y    R180 S1      
327PVDDCR_CPU0_P0   U25   -B45        A01X+139031Y+087748X0177Y    R180 S1      
327PVDDCR_CPU0_P0   U25   -B47        A01X+138290Y+087748X0177Y    R180 S1      
327PVDDCR_CPU0_P0   U25   -B48        A01X+137920Y+087748X0177Y    R180 S1      
327PVDDCR_CPU0_P0   U25   -B50        A01X+137180Y+087748X0177Y    R180 S1      
327PVDDCR_CPU0_P0   U25   -B51        A01X+136810Y+087748X0177Y    R180 S1      
327PVDDCR_CPU0_P0   U25   -B53        A01X+136070Y+087748X0177Y    R180 S1      
327PVDDCR_CPU0_P0   U25   -B54        A01X+135700Y+087748X0177Y    R180 S1      
327PVDDCR_CPU0_P0   U25   -B56        A01X+134960Y+087748X0177Y    R180 S1      
327PVDDCR_CPU0_P0   U25   -B57        A01X+134590Y+087748X0177Y    R180 S1      
327PVDDCR_CPU0_P0   U25   -C20        A01X+148098Y+088067X0177Y    R180 S1      
327PVDDCR_CPU0_P0   U25   -D55        A01X+135330Y+088386X0177Y    R180 S1      
327PVDDCR_CPU0_P0   U25   -D56        A01X+134960Y+088386X0177Y    R180 S1      
327PVDDCR_CPU0_P0   U25   -E22        A01X+147358Y+088705X0177Y    R180 S1      
327PVDDCR_CPU0_P0   U25   -E25        A01X+146247Y+088705X0177Y    R180 S1      
327PVDDCR_CPU0_P0   U25   -E28        A01X+145137Y+088705X0177Y    R180 S1      
327PVDDCR_CPU0_P0   U25   -E31        A01X+144027Y+088705X0177Y    R180 S1      
327PVDDCR_CPU0_P0   U25   -E34        A01X+142916Y+088705X0177Y    R180 S1      
327PVDDCR_CPU0_P0   U25   -E35        A01X+142546Y+088705X0177Y    R180 S1      
327PVDDCR_CPU0_P0   U25   -E42        A01X+140326Y+088705X0177Y    R180 S1      
327PVDDCR_CPU0_P0   U25   -E45        A01X+139216Y+088705X0177Y    R180 S1      
327PVDDCR_CPU0_P0   U25   -E48        A01X+138106Y+088705X0177Y    R180 S1      
327PVDDCR_CPU0_P0   U25   -E51        A01X+136995Y+088705X0177Y    R180 S1      
327PVDDCR_CPU0_P0   U25   -E54        A01X+135885Y+088705X0177Y    R180 S1      
327PVDDCR_CPU0_P0   U25   -F22        A01X+147542Y+089024X0177Y    R180 S1      
327PVDDCR_CPU0_P0   U25   -F25        A01X+146432Y+089024X0177Y    R180 S1      
327PVDDCR_CPU0_P0   U25   -F28        A01X+145322Y+089024X0177Y    R180 S1      
327PVDDCR_CPU0_P0   U25   -F31        A01X+144212Y+089024X0177Y    R180 S1      
327PVDDCR_CPU0_P0   U25   -F34        A01X+143102Y+089024X0177Y    R180 S1      
327PVDDCR_CPU0_P0   U25   -F42        A01X+140141Y+089024X0177Y    R180 S1      
327PVDDCR_CPU0_P0   U25   -F45        A01X+139031Y+089024X0177Y    R180 S1      
327PVDDCR_CPU0_P0   U25   -F48        A01X+137920Y+089024X0177Y    R180 S1      
327PVDDCR_CPU0_P0   U25   -F51        A01X+136810Y+089024X0177Y    R180 S1      
327PVDDCR_CPU0_P0   U25   -F54        A01X+135700Y+089024X0177Y    R180 S1      
327PVDDCR_CPU0_P0   U25   -G35        A01X+142546Y+089343X0177Y    R180 S1      
327PVDDCR_CPU0_P0   U25   -G36        A01X+142176Y+089343X0177Y    R180 S1      
327PVDDCR_CPU0_P0   U25   -G40        A01X+141066Y+089343X0177Y    R180 S1      
327PVDDCR_CPU0_P0   U25   -G41        A01X+140696Y+089343X0177Y    R180 S1      
327PVDDCR_CPU0_P0   U25   -H23        A01X+147172Y+089662X0177Y    R180 S1      
327PVDDCR_CPU0_P0   U25   -H24        A01X+146802Y+089662X0177Y    R180 S1      
327PVDDCR_CPU0_P0   U25   -H26        A01X+146062Y+089662X0177Y    R180 S1      
327PVDDCR_CPU0_P0   U25   -H27        A01X+145692Y+089662X0177Y    R180 S1      
327PVDDCR_CPU0_P0   U25   -H29        A01X+144952Y+089662X0177Y    R180 S1      
327PVDDCR_CPU0_P0   U25   -H30        A01X+144582Y+089662X0177Y    R180 S1      
327PVDDCR_CPU0_P0   U25   -H32        A01X+143842Y+089662X0177Y    R180 S1      
327PVDDCR_CPU0_P0   U25   -H33        A01X+143472Y+089662X0177Y    R180 S1      
327PVDDCR_CPU0_P0   U25   -H43        A01X+139771Y+089662X0177Y    R180 S1      
327PVDDCR_CPU0_P0   U25   -H44        A01X+139401Y+089662X0177Y    R180 S1      
327PVDDCR_CPU0_P0   U25   -H46        A01X+138661Y+089662X0177Y    R180 S1      
327PVDDCR_CPU0_P0   U25   -H47        A01X+138290Y+089662X0177Y    R180 S1      
327PVDDCR_CPU0_P0   U25   -H49        A01X+137550Y+089662X0177Y    R180 S1      
327PVDDCR_CPU0_P0   U25   -H50        A01X+137180Y+089662X0177Y    R180 S1      
327PVDDCR_CPU0_P0   U25   -H52        A01X+136440Y+089662X0177Y    R180 S1      
327PVDDCR_CPU0_P0   U25   -H53        A01X+136070Y+089662X0177Y    R180 S1      
327PVDDCR_CPU0_P0   U25   -J35        A01X+142546Y+089980X0177Y    R180 S1      
327PVDDCR_CPU0_P0   U25   -J36        A01X+142176Y+089980X0177Y    R180 S1      
327PVDDCR_CPU0_P0   U25   -J40        A01X+141066Y+089980X0177Y    R180 S1      
327PVDDCR_CPU0_P0   U25   -J41        A01X+140696Y+089980X0177Y    R180 S1      
327PVDDCR_CPU0_P0   U25   -M23        A01X+147172Y+090937X0177Y    R180 S1      
327PVDDCR_CPU0_P0   U25   -M24        A01X+146802Y+090937X0177Y    R180 S1      
327PVDDCR_CPU0_P0   U25   -M26        A01X+146062Y+090937X0177Y    R180 S1      
327PVDDCR_CPU0_P0   U25   -M27        A01X+145692Y+090937X0177Y    R180 S1      
327PVDDCR_CPU0_P0   U25   -M29        A01X+144952Y+090937X0177Y    R180 S1      
327PVDDCR_CPU0_P0   U25   -M30        A01X+144582Y+090937X0177Y    R180 S1      
327PVDDCR_CPU0_P0   U25   -M32        A01X+143842Y+090937X0177Y    R180 S1      
327PVDDCR_CPU0_P0   U25   -M33        A01X+143472Y+090937X0177Y    R180 S1      
327PVDDCR_CPU0_P0   U25   -M43        A01X+139771Y+090937X0177Y    R180 S1      
327PVDDCR_CPU0_P0   U25   -M44        A01X+139401Y+090937X0177Y    R180 S1      
327PVDDCR_CPU0_P0   U25   -M46        A01X+138661Y+090937X0177Y    R180 S1      
327PVDDCR_CPU0_P0   U25   -M49        A01X+137550Y+090937X0177Y    R180 S1      
327PVDDCR_CPU0_P0   U25   -M50        A01X+137180Y+090937X0177Y    R180 S1      
327PVDDCR_CPU0_P0   U25   -M52        A01X+136440Y+090937X0177Y    R180 S1      
327PVDDCR_CPU0_P0   U25   -M53        A01X+136070Y+090937X0177Y    R180 S1      
327PVDDCR_CPU0_P0   U25   -N35        A01X+142546Y+091256X0177Y    R180 S1      
327PVDDCR_CPU0_P0   U25   -N36        A01X+142176Y+091256X0177Y    R180 S1      
327PVDDCR_CPU0_P0   U25   -N40        A01X+141066Y+091256X0177Y    R180 S1      
327PVDDCR_CPU0_P0   U25   -N41        A01X+140696Y+091256X0177Y    R180 S1      
327PVDDCR_CPU0_P0   U25   -T23        A01X+147172Y+092213X0177Y    R180 S1      
327PVDDCR_CPU0_P0   U25   -T24        A01X+146802Y+092213X0177Y    R180 S1      
327PVDDCR_CPU0_P0   U25   -T26        A01X+146062Y+092213X0177Y    R180 S1      
327PVDDCR_CPU0_P0   U25   -T27        A01X+145692Y+092213X0177Y    R180 S1      
327PVDDCR_CPU0_P0   U25   -T29        A01X+144952Y+092213X0177Y    R180 S1      
327PVDDCR_CPU0_P0   U25   -T30        A01X+144582Y+092213X0177Y    R180 S1      
327PVDDCR_CPU0_P0   U25   -T32        A01X+143842Y+092213X0177Y    R180 S1      
327PVDDCR_CPU0_P0   U25   -T33        A01X+143472Y+092213X0177Y    R180 S1      
327PVDDCR_CPU0_P0   U25   -T43        A01X+139771Y+092213X0177Y    R180 S1      
327PVDDCR_CPU0_P0   U25   -T44        A01X+139401Y+092213X0177Y    R180 S1      
327PVDDCR_CPU0_P0   U25   -T46        A01X+138661Y+092213X0177Y    R180 S1      
327PVDDCR_CPU0_P0   U25   -T47        A01X+138290Y+092213X0177Y    R180 S1      
327PVDDCR_CPU0_P0   U25   -T49        A01X+137550Y+092213X0177Y    R180 S1      
327PVDDCR_CPU0_P0   U25   -T50        A01X+137180Y+092213X0177Y    R180 S1      
327PVDDCR_CPU0_P0   U25   -T52        A01X+136440Y+092213X0177Y    R180 S1      
327PVDDCR_CPU0_P0   U25   -T53        A01X+136070Y+092213X0177Y    R180 S1      
327PVDDCR_CPU0_P0   U25   -U35        A01X+142546Y+092532X0177Y    R180 S1      
327PVDDCR_CPU0_P0   U25   -U36        A01X+142176Y+092532X0177Y    R180 S1      
327PVDDCR_CPU0_P0   U25   -U40        A01X+141066Y+092532X0177Y    R180 S1      
327PVDDCR_CPU0_P0   U25   -U41        A01X+140696Y+092532X0177Y    R180 S1      
327PVDDCR_CPU0_P0   U25   -W29        A01X+144767Y+093169X0177Y    R180 S1      
327PVDDCR_CPU0_P0   U25   -W30        A01X+144397Y+093169X0177Y    R180 S1      
327PVDDCR_CPU0_P0   U25   -W32        A01X+143657Y+093169X0177Y    R180 S1      
327PVDDCR_CPU0_P0   U25   -W33        A01X+143287Y+093169X0177Y    R180 S1      
327PVDDCR_CPU0_P0   U25   -W43        A01X+139956Y+093169X0177Y    R180 S1      
327PVDDCR_CPU0_P0   U25   -W44        A01X+139586Y+093169X0177Y    R180 S1      
327PVDDCR_CPU0_P0   U25   -W46        A01X+138846Y+093169X0177Y    R180 S1      
327PVDDCR_CPU0_P0   U25   -W47        A01X+138476Y+093169X0177Y    R180 S1      
327PVDDCR_CPU0_P0   U25   -Y35        A01X+142732Y+093488X0177Y    R180 S1      
327PVDDCR_CPU0_P0   U25   -Y36        A01X+142361Y+093488X0177Y    R180 S1      
327PVDDCR_CPU0_P0   U25   -Y40        A01X+140881Y+093488X0177Y    R180 S1      
327PVDDCR_CPU0_P0   U25   -Y41        A01X+140511Y+093488X0177Y    R180 S1      
327PVDDCR_CPU0_P0   VIA   -           A18X+150529Y+078971X0260Y         S2      
327PVDDCR_CPU0_P0   VIA   -           A18X+144176Y+077513X0260Y         S2      
327PVDDCR_CPU0_P0   VIA   -           A18X+140667Y+074252X0260Y         S2      
317PVDDCR_CPU0_P0   VIA   -    MD0100PA00X+140664Y+072197X0200Y         S0      
317PVDDCR_CPU0_P0   VIA   -    MD0100PA00X+140664Y+072447X0200Y         S0      
317PVDDCR_CPU0_P0   VIA   -    MD0100PA00X+139584Y+072197X0200Y         S0      
317PVDDCR_CPU0_P0   VIA   -    MD0100PA00X+139584Y+072447X0200Y         S0      
317PVDDCR_CPU0_P0   VIA   -    MD0100PA00X+140914Y+072197X0200Y         S0      
317PVDDCR_CPU0_P0   VIA   -    MD0100PA00X+140914Y+072447X0200Y         S0      
317PVDDCR_CPU0_P0   VIA   -    MD0100PA00X+140917Y+072702X0200Y    R180 S0      
317PVDDCR_CPU0_P0   VIA   -    MD0100PA00X+140667Y+072952X0200Y    R180 S0      
317PVDDCR_CPU0_P0   VIA   -    MD0100PA00X+140667Y+073202X0200Y    R180 S0      
317PVDDCR_CPU0_P0   VIA   -    MD0100PA00X+140917Y+072952X0200Y    R180 S0      
317PVDDCR_CPU0_P0   VIA   -    MD0100PA00X+140917Y+073202X0200Y    R180 S0      
317PVDDCR_CPU0_P0   VIA   -    MD0100PA00X+140667Y+072702X0200Y    R180 S0      
317PVDDCR_CPU0_P0   VIA   -    MD0100PA00X+139587Y+072952X0200Y    R180 S0      
317PVDDCR_CPU0_P0   VIA   -    MD0100PA00X+139587Y+072702X0200Y    R180 S0      
317PVDDCR_CPU0_P0   VIA   -    MD0100PA00X+139587Y+073202X0200Y    R180 S0      
317PVDDCR_CPU0_P0   VIA   -    MD0100PA00X+139085Y+072705X0200Y    R180 S0      
317PVDDCR_CPU0_P0   VIA   -    MD0100PA00X+139081Y+072455X0200Y    R180 S0      
317PVDDCR_CPU0_P0   VIA   -    MD0100PA00X+139081Y+072205X0200Y    R180 S0      
317PVDDCR_CPU0_P0   VIA   -    MD0100PA00X+139334Y+072197X0200Y         S0      
317PVDDCR_CPU0_P0   VIA   -    MD0100PA00X+139334Y+072447X0200Y         S0      
317PVDDCR_CPU0_P0   VIA   -    MD0100PA00X+139337Y+072952X0200Y    R180 S0      
317PVDDCR_CPU0_P0   VIA   -    MD0100PA00X+139337Y+072702X0200Y    R180 S0      
317PVDDCR_CPU0_P0   VIA   -    MD0100PA00X+134830Y+087126X0200Y         S0      
317PVDDCR_CPU0_P0   VIA   -    MD0100PA00X+134480Y+087126X0200Y         S0      
317PVDDCR_CPU0_P0   VIA   -    MD0100PA00X+134130Y+087126X0200Y         S0      
317PVDDCR_CPU0_P0   VIA   -    MD0100PA00X+140667Y+073952X0200Y    R180 S0      
317PVDDCR_CPU0_P0   VIA   -    MD0100PA00X+140667Y+073702X0200Y    R180 S0      
317PVDDCR_CPU0_P0   VIA   -    MD0100PA00X+140667Y+073452X0200Y    R180 S0      
317PVDDCR_CPU0_P0   VIA   -    MD0100PA00X+140917Y+073702X0200Y    R180 S0      
317PVDDCR_CPU0_P0   VIA   -    MD0100PA00X+140917Y+073452X0200Y    R180 S0      
317PVDDCR_CPU0_P0   VIA   -    MD0100PA00X+140917Y+073952X0200Y    R180 S0      
317PVDDCR_CPU0_P0   VIA   -    MD0100PA00X+142341Y+075463X0200Y    R180 S0      
317PVDDCR_CPU0_P0   VIA   -    MD0100PA00X+142341Y+075213X0200Y    R180 S0      
317PVDDCR_CPU0_P0   VIA   -    MD0100PA00X+142341Y+074963X0200Y    R180 S0      
317PVDDCR_CPU0_P0   VIA   -    MD0100PA00X+142341Y+075713X0200Y    R180 S0      
317PVDDCR_CPU0_P0   VIA   -    MD0100PA00X+142342Y+074705X0200Y    R180 S0      
317PVDDCR_CPU0_P0   VIA   -    MD0100PA00X+141630Y+098534X0190Y    R090 S0      
317PVDDCR_CPU0_P0   VIA   -    MD0100PA00X+141630Y+097784X0190Y    R090 S0      
317PVDDCR_CPU0_P0   VIA   -    MD0100PA00X+141630Y+097034X0190Y    R090 S0      
317PVDDCR_CPU0_P0   VIA   -    MD0100PA00X+143926Y+076713X0200Y    R180 S0      
317PVDDCR_CPU0_P0   VIA   -    MD0100PA00X+143926Y+076963X0200Y    R180 S0      
317PVDDCR_CPU0_P0   VIA   -    MD0100PA00X+143926Y+076463X0200Y    R180 S0      
317PVDDCR_CPU0_P0   VIA   -    MD0100PA00X+143924Y+075455X0200Y         S0      
317PVDDCR_CPU0_P0   VIA   -    MD0100PA00X+143924Y+075205X0200Y         S0      
317PVDDCR_CPU0_P0   VIA   -    MD0100PA00X+143924Y+074955X0200Y         S0      
317PVDDCR_CPU0_P0   VIA   -    MD0100PA00X+143924Y+075705X0200Y         S0      
317PVDDCR_CPU0_P0   VIA   -    MD0100PA00X+142844Y+074955X0200Y         S0      
317PVDDCR_CPU0_P0   VIA   -    MD0100PA00X+142844Y+075205X0200Y         S0      
317PVDDCR_CPU0_P0   VIA   -    MD0100PA00X+142844Y+075455X0200Y         S0      
317PVDDCR_CPU0_P0   VIA   -    MD0100PA00X+142594Y+075455X0200Y         S0      
317PVDDCR_CPU0_P0   VIA   -    MD0100PA00X+142594Y+075205X0200Y         S0      
317PVDDCR_CPU0_P0   VIA   -    MD0100PA00X+142594Y+074955X0200Y         S0      
317PVDDCR_CPU0_P0   VIA   -    MD0100PA00X+142844Y+075705X0200Y         S0      
317PVDDCR_CPU0_P0   VIA   -    MD0100PA00X+142594Y+075705X0200Y         S0      
317PVDDCR_CPU0_P0   VIA   -    MD0100PA00X+143926Y+075963X0200Y    R180 S0      
317PVDDCR_CPU0_P0   VIA   -    MD0100PA00X+143926Y+076213X0200Y    R180 S0      
317PVDDCR_CPU0_P0   VIA   -    MD0100PA00X+142591Y+075963X0200Y    R180 S0      
317PVDDCR_CPU0_P0   VIA   -    MD0100PA00X+142841Y+075963X0200Y    R180 S0      
317PVDDCR_CPU0_P0   VIA   -    MD0100PA00X+142841Y+076213X0200Y    R180 S0      
317PVDDCR_CPU0_P0   VIA   -    MD0100PA00X+142842Y+074705X0200Y    R180 S0      
317PVDDCR_CPU0_P0   VIA   -    MD0100PA00X+142592Y+074705X0200Y    R180 S0      
317PVDDCR_CPU0_P0   VIA   -    MD0100PA00X+143923Y+074705X0200Y    R180 S0      
317PVDDCR_CPU0_P0   VIA   -    MD0100PA00X+144176Y+076713X0200Y    R180 S0      
317PVDDCR_CPU0_P0   VIA   -    MD0100PA00X+144176Y+076963X0200Y    R180 S0      
317PVDDCR_CPU0_P0   VIA   -    MD0100PA00X+144176Y+076463X0200Y    R180 S0      
317PVDDCR_CPU0_P0   VIA   -    MD0100PA00X+144176Y+077213X0200Y    R180 S0      
317PVDDCR_CPU0_P0   VIA   -    MD0100PA00X+144426Y+076713X0200Y    R180 S0      
317PVDDCR_CPU0_P0   VIA   -    MD0100PA00X+144426Y+076963X0200Y    R180 S0      
317PVDDCR_CPU0_P0   VIA   -    MD0100PA00X+144426Y+076463X0200Y    R180 S0      
317PVDDCR_CPU0_P0   VIA   -    MD0100PA00X+144426Y+077213X0200Y    R180 S0      
317PVDDCR_CPU0_P0   VIA   -    MD0100PA00X+144174Y+074955X0200Y         S0      
317PVDDCR_CPU0_P0   VIA   -    MD0100PA00X+144174Y+075205X0200Y         S0      
317PVDDCR_CPU0_P0   VIA   -    MD0100PA00X+144174Y+075455X0200Y         S0      
317PVDDCR_CPU0_P0   VIA   -    MD0100PA00X+144174Y+075705X0200Y         S0      
317PVDDCR_CPU0_P0   VIA   -    MD0100PA00X+144176Y+076213X0200Y    R180 S0      
317PVDDCR_CPU0_P0   VIA   -    MD0100PA00X+144176Y+075963X0200Y    R180 S0      
317PVDDCR_CPU0_P0   VIA   -    MD0100PA00X+144426Y+076213X0200Y    R180 S0      
317PVDDCR_CPU0_P0   VIA   -    MD0100PA00X+144426Y+075963X0200Y    R180 S0      
317PVDDCR_CPU0_P0   VIA   -    MD0100PA00X+144426Y+075713X0200Y    R180 S0      
317PVDDCR_CPU0_P0   VIA   -    MD0100PA00X+144173Y+074705X0200Y    R180 S0      
317PVDDCR_CPU0_P0   VIA   -    MD0100PA00X+145634Y+076921X0200Y    R180 S0      
317PVDDCR_CPU0_P0   VIA   -    MD0100PA00X+145634Y+077421X0200Y    R180 S0      
317PVDDCR_CPU0_P0   VIA   -    MD0100PA00X+145634Y+077671X0200Y    R180 S0      
317PVDDCR_CPU0_P0   VIA   -    MD0100PA00X+145884Y+076663X0200Y    R180 S0      
317PVDDCR_CPU0_P0   VIA   -    MD0100PA00X+146134Y+076663X0200Y    R180 S0      
317PVDDCR_CPU0_P0   VIA   -    MD0100PA00X+146136Y+076913X0200Y         S0      
317PVDDCR_CPU0_P0   VIA   -    MD0100PA00X+146136Y+077163X0200Y         S0      
317PVDDCR_CPU0_P0   VIA   -    MD0100PA00X+146136Y+077413X0200Y         S0      
317PVDDCR_CPU0_P0   VIA   -    MD0100PA00X+145886Y+077413X0200Y         S0      
317PVDDCR_CPU0_P0   VIA   -    MD0100PA00X+145886Y+077163X0200Y         S0      
317PVDDCR_CPU0_P0   VIA   -    MD0100PA00X+145886Y+076913X0200Y         S0      
317PVDDCR_CPU0_P0   VIA   -    MD0100PA00X+146136Y+077663X0200Y         S0      
317PVDDCR_CPU0_P0   VIA   -    MD0100PA00X+145886Y+077663X0200Y         S0      
317PVDDCR_CPU0_P0   VIA   -    MD0100PA00X+145637Y+078421X0200Y    R180 S0      
317PVDDCR_CPU0_P0   VIA   -    MD0100PA00X+145637Y+078171X0200Y    R180 S0      
317PVDDCR_CPU0_P0   VIA   -    MD0100PA00X+145637Y+077921X0200Y    R180 S0      
317PVDDCR_CPU0_P0   VIA   -    MD0100PA00X+146137Y+078170X0200Y    R180 S0      
317PVDDCR_CPU0_P0   VIA   -    MD0100PA00X+146137Y+078670X0200Y    R180 S0      
317PVDDCR_CPU0_P0   VIA   -    MD0100PA00X+146137Y+078420X0200Y    R180 S0      
317PVDDCR_CPU0_P0   VIA   -    MD0100PA00X+145887Y+078670X0200Y    R180 S0      
317PVDDCR_CPU0_P0   VIA   -    MD0100PA00X+145887Y+078170X0200Y    R180 S0      
317PVDDCR_CPU0_P0   VIA   -    MD0100PA00X+145887Y+078420X0200Y    R180 S0      
317PVDDCR_CPU0_P0   VIA   -    MD0100PA00X+146137Y+077920X0200Y    R180 S0      
317PVDDCR_CPU0_P0   VIA   -    MD0100PA00X+145887Y+077920X0200Y    R180 S0      
317PVDDCR_CPU0_P0   VIA   -    MD0100PA00X+146137Y+078920X0200Y    R180 S0      
317PVDDCR_CPU0_P0   VIA   -    MD0100PA00X+146137Y+079170X0200Y    R180 S0      
317PVDDCR_CPU0_P0   VIA   -    MD0100PA00X+145634Y+076663X0200Y    R180 S0      
317PVDDCR_CPU0_P0   VIA   -    MD0100PA00X+145634Y+077171X0200Y    R180 S0      
317PVDDCR_CPU0_P0   VIA   -    MD0100PA00X+147467Y+078420X0200Y    R180 S0      
317PVDDCR_CPU0_P0   VIA   -    MD0100PA00X+147717Y+078420X0200Y    R180 S0      
317PVDDCR_CPU0_P0   VIA   -    MD0100PA00X+147467Y+077920X0200Y    R180 S0      
317PVDDCR_CPU0_P0   VIA   -    MD0100PA00X+147717Y+077920X0200Y    R180 S0      
317PVDDCR_CPU0_P0   VIA   -    MD0100PA00X+147467Y+078920X0200Y    R180 S0      
317PVDDCR_CPU0_P0   VIA   -    MD0100PA00X+147717Y+078920X0200Y    R180 S0      
317PVDDCR_CPU0_P0   VIA   -    MD0100PA00X+147217Y+078170X0200Y    R180 S0      
317PVDDCR_CPU0_P0   VIA   -    MD0100PA00X+147217Y+078670X0200Y    R180 S0      
317PVDDCR_CPU0_P0   VIA   -    MD0100PA00X+147217Y+078420X0200Y    R180 S0      
317PVDDCR_CPU0_P0   VIA   -    MD0100PA00X+147217Y+077920X0200Y    R180 S0      
317PVDDCR_CPU0_P0   VIA   -    MD0100PA00X+147217Y+078920X0200Y    R180 S0      
317PVDDCR_CPU0_P0   VIA   -    MD0100PA00X+147467Y+078170X0200Y    R180 S0      
317PVDDCR_CPU0_P0   VIA   -    MD0100PA00X+147717Y+078170X0200Y    R180 S0      
317PVDDCR_CPU0_P0   VIA   -    MD0100PA00X+147467Y+078670X0200Y    R180 S0      
317PVDDCR_CPU0_P0   VIA   -    MD0100PA00X+147717Y+078670X0200Y    R180 S0      
317PVDDCR_CPU0_P0   VIA   -    MD0100PA00X+147217Y+079170X0200Y    R180 S0      
317PVDDCR_CPU0_P0   VIA   -    MD0100PA00X+147467Y+079170X0200Y    R180 S0      
317PVDDCR_CPU0_P0   VIA   -    MD0100PA00X+147717Y+079170X0200Y    R180 S0      
317PVDDCR_CPU0_P0   VIA   -    MD0100PA00X+147714Y+076663X0200Y    R180 S0      
317PVDDCR_CPU0_P0   VIA   -    MD0100PA00X+147464Y+076663X0200Y    R180 S0      
317PVDDCR_CPU0_P0   VIA   -    MD0100PA00X+147214Y+076663X0200Y    R180 S0      
317PVDDCR_CPU0_P0   VIA   -    MD0100PA00X+147216Y+077413X0200Y         S0      
317PVDDCR_CPU0_P0   VIA   -    MD0100PA00X+147216Y+077163X0200Y         S0      
317PVDDCR_CPU0_P0   VIA   -    MD0100PA00X+147216Y+076913X0200Y         S0      
317PVDDCR_CPU0_P0   VIA   -    MD0100PA00X+147216Y+077663X0200Y         S0      
317PVDDCR_CPU0_P0   VIA   -    MD0100PA00X+147466Y+076913X0200Y         S0      
317PVDDCR_CPU0_P0   VIA   -    MD0100PA00X+147466Y+077163X0200Y         S0      
317PVDDCR_CPU0_P0   VIA   -    MD0100PA00X+147466Y+077413X0200Y         S0      
317PVDDCR_CPU0_P0   VIA   -    MD0100PA00X+147466Y+077663X0200Y         S0      
317PVDDCR_CPU0_P0   VIA   -    MD0100PA00X+147717Y+077670X0200Y    R180 S0      
317PVDDCR_CPU0_P0   VIA   -    MD0100PA00X+147717Y+076920X0200Y    R180 S0      
317PVDDCR_CPU0_P0   VIA   -    MD0100PA00X+147717Y+077170X0200Y    R180 S0      
317PVDDCR_CPU0_P0   VIA   -    MD0100PA00X+147717Y+077420X0200Y    R180 S0      
317PVDDCR_CPU0_P0   VIA   -    MD0100PA00X+148949Y+078171X0200Y    R180 S0      
317PVDDCR_CPU0_P0   VIA   -    MD0100PA00X+148949Y+078671X0200Y    R180 S0      
317PVDDCR_CPU0_P0   VIA   -    MD0100PA00X+148949Y+078421X0200Y    R180 S0      
317PVDDCR_CPU0_P0   VIA   -    MD0100PA00X+148949Y+077921X0200Y    R180 S0      
317PVDDCR_CPU0_P0   VIA   -    MD0100PA00X+149199Y+078171X0200Y    R180 S0      
317PVDDCR_CPU0_P0   VIA   -    MD0100PA00X+149199Y+078671X0200Y    R180 S0      
317PVDDCR_CPU0_P0   VIA   -    MD0100PA00X+149199Y+078421X0200Y    R180 S0      
317PVDDCR_CPU0_P0   VIA   -    MD0100PA00X+149199Y+077921X0200Y    R180 S0      
317PVDDCR_CPU0_P0   VIA   -    MD0100PA00X+149449Y+078171X0200Y    R180 S0      
317PVDDCR_CPU0_P0   VIA   -    MD0100PA00X+149449Y+078671X0200Y    R180 S0      
317PVDDCR_CPU0_P0   VIA   -    MD0100PA00X+149449Y+078421X0200Y    R180 S0      
317PVDDCR_CPU0_P0   VIA   -    MD0100PA00X+149449Y+077921X0200Y    R180 S0      
317PVDDCR_CPU0_P0   VIA   -    MD0100PA00X+148942Y+076663X0200Y    R180 S0      
317PVDDCR_CPU0_P0   VIA   -    MD0100PA00X+148942Y+077171X0200Y    R180 S0      
317PVDDCR_CPU0_P0   VIA   -    MD0100PA00X+148942Y+076921X0200Y    R180 S0      
317PVDDCR_CPU0_P0   VIA   -    MD0100PA00X+148942Y+077421X0200Y    R180 S0      
317PVDDCR_CPU0_P0   VIA   -    MD0100PA00X+148942Y+077671X0200Y    R180 S0      
317PVDDCR_CPU0_P0   VIA   -    MD0100PA00X+149192Y+076663X0200Y    R180 S0      
317PVDDCR_CPU0_P0   VIA   -    MD0100PA00X+149442Y+076663X0200Y    R180 S0      
317PVDDCR_CPU0_P0   VIA   -    MD0100PA00X+149444Y+076913X0200Y         S0      
317PVDDCR_CPU0_P0   VIA   -    MD0100PA00X+149444Y+077163X0200Y         S0      
317PVDDCR_CPU0_P0   VIA   -    MD0100PA00X+149444Y+077413X0200Y         S0      
317PVDDCR_CPU0_P0   VIA   -    MD0100PA00X+149194Y+077413X0200Y         S0      
317PVDDCR_CPU0_P0   VIA   -    MD0100PA00X+149194Y+077163X0200Y         S0      
317PVDDCR_CPU0_P0   VIA   -    MD0100PA00X+149194Y+076913X0200Y         S0      
317PVDDCR_CPU0_P0   VIA   -    MD0100PA00X+149444Y+077663X0200Y         S0      
317PVDDCR_CPU0_P0   VIA   -    MD0100PA00X+149194Y+077663X0200Y         S0      
317PVDDCR_CPU0_P0   VIA   -    MD0100PA00X+150779Y+078421X0200Y    R180 S0      
317PVDDCR_CPU0_P0   VIA   -    MD0100PA00X+150779Y+077921X0200Y    R180 S0      
317PVDDCR_CPU0_P0   VIA   -    MD0100PA00X+151029Y+078171X0200Y    R180 S0      
317PVDDCR_CPU0_P0   VIA   -    MD0100PA00X+151029Y+078671X0200Y    R180 S0      
317PVDDCR_CPU0_P0   VIA   -    MD0100PA00X+151029Y+078421X0200Y    R180 S0      
317PVDDCR_CPU0_P0   VIA   -    MD0100PA00X+151029Y+077921X0200Y    R180 S0      
317PVDDCR_CPU0_P0   VIA   -    MD0100PA00X+150529Y+078171X0200Y    R180 S0      
317PVDDCR_CPU0_P0   VIA   -    MD0100PA00X+150529Y+078671X0200Y    R180 S0      
317PVDDCR_CPU0_P0   VIA   -    MD0100PA00X+150529Y+078421X0200Y    R180 S0      
317PVDDCR_CPU0_P0   VIA   -    MD0100PA00X+150529Y+077921X0200Y    R180 S0      
317PVDDCR_CPU0_P0   VIA   -    MD0100PA00X+150779Y+078171X0200Y    R180 S0      
317PVDDCR_CPU0_P0   VIA   -    MD0100PA00X+150779Y+078671X0200Y    R180 S0      
317PVDDCR_CPU0_P0   VIA   -    MD0100PA00X+151023Y+076663X0200Y    R180 S0      
317PVDDCR_CPU0_P0   VIA   -    MD0100PA00X+150773Y+076663X0200Y    R180 S0      
317PVDDCR_CPU0_P0   VIA   -    MD0100PA00X+150523Y+076663X0200Y    R180 S0      
317PVDDCR_CPU0_P0   VIA   -    MD0100PA00X+150524Y+077413X0200Y         S0      
317PVDDCR_CPU0_P0   VIA   -    MD0100PA00X+150524Y+077163X0200Y         S0      
317PVDDCR_CPU0_P0   VIA   -    MD0100PA00X+150524Y+076913X0200Y         S0      
317PVDDCR_CPU0_P0   VIA   -    MD0100PA00X+150524Y+077663X0200Y         S0      
317PVDDCR_CPU0_P0   VIA   -    MD0100PA00X+150774Y+076913X0200Y         S0      
317PVDDCR_CPU0_P0   VIA   -    MD0100PA00X+150774Y+077163X0200Y         S0      
317PVDDCR_CPU0_P0   VIA   -    MD0100PA00X+150774Y+077413X0200Y         S0      
317PVDDCR_CPU0_P0   VIA   -    MD0100PA00X+150774Y+077663X0200Y         S0      
317PVDDCR_CPU0_P0   VIA   -    MD0100PA00X+151029Y+077671X0200Y    R180 S0      
317PVDDCR_CPU0_P0   VIA   -    MD0100PA00X+151029Y+077421X0200Y    R180 S0      
317PVDDCR_CPU0_P0   VIA   -    MD0100PA00X+151029Y+076921X0200Y    R180 S0      
317PVDDCR_CPU0_P0   VIA   -    MD0100PA00X+151029Y+077171X0200Y    R180 S0      
317PVDDCR_CPU0_P0   VIA   -    MD0100PA00X+152222Y+078171X0200Y    R180 S0      
317PVDDCR_CPU0_P0   VIA   -    MD0100PA00X+152472Y+078171X0200Y    R180 S0      
317PVDDCR_CPU0_P0   VIA   -    MD0100PA00X+152222Y+078671X0200Y    R180 S0      
317PVDDCR_CPU0_P0   VIA   -    MD0100PA00X+152222Y+078421X0200Y    R180 S0      
317PVDDCR_CPU0_P0   VIA   -    MD0100PA00X+152472Y+078671X0200Y    R180 S0      
317PVDDCR_CPU0_P0   VIA   -    MD0100PA00X+152472Y+078421X0200Y    R180 S0      
317PVDDCR_CPU0_P0   VIA   -    MD0100PA00X+152222Y+077921X0200Y    R180 S0      
317PVDDCR_CPU0_P0   VIA   -    MD0100PA00X+152472Y+077921X0200Y    R180 S0      
317PVDDCR_CPU0_P0   VIA   -    MD0100PA00X+152722Y+078171X0200Y    R180 S0      
317PVDDCR_CPU0_P0   VIA   -    MD0100PA00X+152722Y+078671X0200Y    R180 S0      
317PVDDCR_CPU0_P0   VIA   -    MD0100PA00X+152722Y+078421X0200Y    R180 S0      
317PVDDCR_CPU0_P0   VIA   -    MD0100PA00X+152722Y+077921X0200Y    R180 S0      
317PVDDCR_CPU0_P0   VIA   -    MD0100PA00X+152724Y+076913X0200Y         S0      
317PVDDCR_CPU0_P0   VIA   -    MD0100PA00X+152724Y+077163X0200Y         S0      
317PVDDCR_CPU0_P0   VIA   -    MD0100PA00X+152724Y+077413X0200Y         S0      
317PVDDCR_CPU0_P0   VIA   -    MD0100PA00X+152474Y+077413X0200Y         S0      
317PVDDCR_CPU0_P0   VIA   -    MD0100PA00X+152474Y+077163X0200Y         S0      
317PVDDCR_CPU0_P0   VIA   -    MD0100PA00X+152474Y+076913X0200Y         S0      
317PVDDCR_CPU0_P0   VIA   -    MD0100PA00X+152724Y+077663X0200Y         S0      
317PVDDCR_CPU0_P0   VIA   -    MD0100PA00X+152474Y+077663X0200Y         S0      
317PVDDCR_CPU0_P0   VIA   -    MD0100PA00X+152222Y+077671X0200Y    R180 S0      
317PVDDCR_CPU0_P0   VIA   -    MD0100PA00X+152222Y+077421X0200Y    R180 S0      
317PVDDCR_CPU0_P0   VIA   -    MD0100PA00X+152222Y+076663X0200Y    R180 S0      
317PVDDCR_CPU0_P0   VIA   -    MD0100PA00X+152472Y+076663X0200Y    R180 S0      
317PVDDCR_CPU0_P0   VIA   -    MD0100PA00X+152222Y+076921X0200Y    R180 S0      
317PVDDCR_CPU0_P0   VIA   -    MD0100PA00X+152722Y+076663X0200Y    R180 S0      
317PVDDCR_CPU0_P0   VIA   -    MD0100PA00X+152222Y+077171X0200Y    R180 S0      
317PVDDCR_CPU0_P0   VIA   -    MD0100PA00X+154053Y+078171X0200Y    R180 S0      
317PVDDCR_CPU0_P0   VIA   -    MD0100PA00X+153803Y+078171X0200Y    R180 S0      
317PVDDCR_CPU0_P0   VIA   -    MD0100PA00X+154053Y+077921X0200Y    R180 S0      
317PVDDCR_CPU0_P0   VIA   -    MD0100PA00X+153803Y+077921X0200Y    R180 S0      
317PVDDCR_CPU0_P0   VIA   -    MD0100PA00X+153803Y+078471X0200Y    R180 S0      
317PVDDCR_CPU0_P0   VIA   -    MD0100PA00X+153804Y+077413X0200Y         S0      
317PVDDCR_CPU0_P0   VIA   -    MD0100PA00X+153804Y+077163X0200Y         S0      
317PVDDCR_CPU0_P0   VIA   -    MD0100PA00X+153804Y+076913X0200Y         S0      
317PVDDCR_CPU0_P0   VIA   -    MD0100PA00X+153804Y+077663X0200Y         S0      
317PVDDCR_CPU0_P0   VIA   -    MD0100PA00X+154054Y+076913X0200Y         S0      
317PVDDCR_CPU0_P0   VIA   -    MD0100PA00X+154054Y+077163X0200Y         S0      
317PVDDCR_CPU0_P0   VIA   -    MD0100PA00X+154054Y+077413X0200Y         S0      
317PVDDCR_CPU0_P0   VIA   -    MD0100PA00X+154054Y+077663X0200Y         S0      
317PVDDCR_CPU0_P0   VIA   -    MD0100PA00X+154053Y+076663X0200Y    R180 S0      
317PVDDCR_CPU0_P0   VIA   -    MD0100PA00X+153803Y+076663X0200Y    R180 S0      
327PVDDCR_CPU0_P0   PC496 -1          A18X+153103Y+075852X0950Y1110R090 S2      
327PVDDCR_CPU0_P0   PC108 -1          A18X+149665Y+075851X0950Y1110R090 S2      
327PVDDCR_CPU0_P0   PC498 -1          A18X+146779Y+075868X0950Y1110R090 S2      
327PVDDCR_CPU0_P0   PC499_-1          A18X+142339Y+073667X0400Y0500R270 S2      
327PVDDCR_CPU0_P0   PL52  -4   M      A01X+146676Y+077288X0950Y1780R090 S1      
327PVDDCR_CPU0_P0   PC501_-1          A18X+145233Y+075674X0400Y0500R270 S2      
327PVDDCR_CPU0_P0   PC564_-1          A18X+148290Y+075644X0400Y0500R270 S2      
327PVDDCR_CPU0_P0   PL59  -4   M      A01X+149984Y+077288X0950Y1780R090 S1      
327PVDDCR_CPU0_P0   PC565_-1          A18X+151730Y+075677X0400Y0500R270 S2      
327PVDDCR_CPU0_P0   PC562_-1          A18X+151045Y+075679X0400Y0500R270 S2      
327PVDDCR_CPU0_P0   PL60  -4   M      A01X+153264Y+077288X0950Y1780R090 S1      
327PVDDCR_CPU0_P0   PC563_-1          A18X+154605Y+077449X0400Y0500R270 S2      
317PVDDCR_CPU0_P0   VIA   -    MD0100PA00X+138201Y+061952X0200Y         S0      
327PVDDCR_CPU0_P0   PR433 -2          A18X+138342Y+062234X0198Y0197R090 S2      
327PVDDCR_CPU0_P0   PR324 -2          A18X+144872Y+068782X0198Y0197R090 S2      
317PVDDCR_CPU0_P0   VIA   -    MD0100PA00X+144731Y+068500X0200Y    R180 S0      
317PVDDCR_CPU0_P0   VIA   -    MD0100PA00X+136094Y+068157X0200Y    R180 S0      
317PVDDCR_CPU0_P0   VIA   -    MD0100PA00X+135844Y+068157X0200Y    R180 S0      
317PVDDCR_CPU0_P0   VIA   -    MD0100PA00X+137674Y+068157X0200Y    R180 S0      
317PVDDCR_CPU0_P0   VIA   -    MD0100PA00X+136344Y+068157X0200Y    R180 S0      
317PVDDCR_CPU0_P0   VIA   -    MD0100PA00X+137424Y+068157X0200Y    R180 S0      
317PVDDCR_CPU0_P0   VIA   -    MD0100PA00X+140663Y+071447X0200Y    R180 S0      
317PVDDCR_CPU0_P0   VIA   -    MD0100PA00X+139332Y+071447X0200Y    R180 S0      
317PVDDCR_CPU0_P0   VIA   -    MD0100PA00X+139582Y+071447X0200Y    R180 S0      
317PVDDCR_CPU0_P0   VIA   -    MD0100PA00X+140913Y+071447X0200Y    R180 S0      
317PVDDCR_CPU0_P0   VIA   -    MD0100PA00X+139082Y+071447X0200Y    R180 S0      
317PVDDCR_CPU0_P0   VIA   -    MD0100PA00X+139081Y+071705X0200Y    R180 S0      
317PVDDCR_CPU0_P0   VIA   -    MD0100PA00X+139081Y+071955X0200Y    R180 S0      
317PVDDCR_CPU0_P0   VIA   -    MD0100PA00X+137426Y+068907X0200Y         S0      
317PVDDCR_CPU0_P0   VIA   -    MD0100PA00X+137426Y+068657X0200Y         S0      
317PVDDCR_CPU0_P0   VIA   -    MD0100PA00X+137426Y+068407X0200Y         S0      
317PVDDCR_CPU0_P0   VIA   -    MD0100PA00X+137426Y+069157X0200Y         S0      
317PVDDCR_CPU0_P0   VIA   -    MD0100PA00X+136346Y+068407X0200Y         S0      
317PVDDCR_CPU0_P0   VIA   -    MD0100PA00X+136346Y+068657X0200Y         S0      
317PVDDCR_CPU0_P0   VIA   -    MD0100PA00X+136346Y+068907X0200Y         S0      
317PVDDCR_CPU0_P0   VIA   -    MD0100PA00X+136096Y+068907X0200Y         S0      
317PVDDCR_CPU0_P0   VIA   -    MD0100PA00X+136096Y+068657X0200Y         S0      
317PVDDCR_CPU0_P0   VIA   -    MD0100PA00X+136096Y+068407X0200Y         S0      
317PVDDCR_CPU0_P0   VIA   -    MD0100PA00X+136346Y+069157X0200Y         S0      
317PVDDCR_CPU0_P0   VIA   -    MD0100PA00X+136096Y+069157X0200Y         S0      
317PVDDCR_CPU0_P0   VIA   -    MD0100PA00X+137676Y+068407X0200Y         S0      
317PVDDCR_CPU0_P0   VIA   -    MD0100PA00X+137676Y+068657X0200Y         S0      
317PVDDCR_CPU0_P0   VIA   -    MD0100PA00X+137676Y+068907X0200Y         S0      
317PVDDCR_CPU0_P0   VIA   -    MD0100PA00X+137676Y+069157X0200Y         S0      
317PVDDCR_CPU0_P0   VIA   -    MD0100PA00X+140664Y+071947X0200Y         S0      
317PVDDCR_CPU0_P0   VIA   -    MD0100PA00X+140664Y+071697X0200Y         S0      
317PVDDCR_CPU0_P0   VIA   -    MD0100PA00X+139584Y+071697X0200Y         S0      
317PVDDCR_CPU0_P0   VIA   -    MD0100PA00X+139584Y+071947X0200Y         S0      
317PVDDCR_CPU0_P0   VIA   -    MD0100PA00X+139334Y+071947X0200Y         S0      
317PVDDCR_CPU0_P0   VIA   -    MD0100PA00X+139334Y+071697X0200Y         S0      
317PVDDCR_CPU0_P0   VIA   -    MD0100PA00X+140914Y+071697X0200Y         S0      
317PVDDCR_CPU0_P0   VIA   -    MD0100PA00X+140914Y+071947X0200Y         S0      
327PVDDCR_CPU0_P0   VIA   -           A18X+137426Y+070965X0260Y         S2      
327PVDDCR_CPU0_P0   PR294 -1          A01X+134637Y+067839X0198Y0197R180 S1      
327PVDDCR_CPU0_P0   PC497 -1   M      A01X+135077Y+067774X0198Y0197R270 S1      
327PVDDCR_CPU0_P0   PL51  -4   M      A01X+143384Y+075330X0950Y1780R090 S1      
327PVDDCR_CPU0_P0   PL61  -4   M      A01X+140124Y+072072X0950Y1780R090 S1      
327PVDDCR_CPU0_P0   PL70  -4   M      A01X+136886Y+068782X0950Y1780R090 S1      
327PVDDCR_CPU0_P0   PC494 -1          A18X+143726Y+073893X0950Y1110R090 S2      
327PVDDCR_CPU0_P0   PC575_-1          A18X+141504Y+071088X0400Y0500R270 S2      
327PVDDCR_CPU0_P0   PC495 -1          A18X+140129Y+070647X0950Y1110R090 S2      
327PVDDCR_CPU0_P0   PC576_-1          A18X+138750Y+070394X0400Y0500R270 S2      
327PVDDCR_CPU0_P0   PC502_-1          A18X+137964Y+067811X0400Y0500R270 S2      
327PVDDCR_CPU0_P0   PC500_-1          A18X+136860Y+067195X0400Y0500R270 S2      
327PVDDCR_CPU0_P0   PC166_-1          A18X+136028Y+067195X0400Y0500R270 S2      
327PVDDCR_CPU0_P0   PC163_-1          A18X+135193Y+067195X0400Y0500R270 S2      
327PVDDCR_CPU0_P0   PR447 -1          A18X+134672Y+066946X0198Y0197R090 S2      
317PVDDCR_CPU0_P0   VIA   -    MD0100PA00X+135846Y+068665X0200Y    R180 S0      
317PVDDCR_CPU0_P0   VIA   -    MD0100PA00X+135846Y+068415X0200Y    R180 S0      
317PVDDCR_CPU0_P0   VIA   -    MD0100PA00X+136346Y+069915X0200Y    R180 S0      
317PVDDCR_CPU0_P0   VIA   -    MD0100PA00X+136096Y+069665X0200Y    R180 S0      
317PVDDCR_CPU0_P0   VIA   -    MD0100PA00X+136346Y+069665X0200Y    R180 S0      
317PVDDCR_CPU0_P0   VIA   -    MD0100PA00X+135846Y+069165X0200Y    R180 S0      
317PVDDCR_CPU0_P0   VIA   -    MD0100PA00X+135846Y+068915X0200Y    R180 S0      
317PVDDCR_CPU0_P0   VIA   -    MD0100PA00X+136096Y+069415X0200Y    R180 S0      
317PVDDCR_CPU0_P0   VIA   -    MD0100PA00X+136346Y+069415X0200Y    R180 S0      
317PVDDCR_CPU0_P0   VIA   -    MD0100PA00X+135846Y+069415X0200Y    R180 S0      
317PVDDCR_CPU0_P0   VIA   -    MD0100PA00X+137426Y+070415X0200Y    R180 S0      
317PVDDCR_CPU0_P0   VIA   -    MD0100PA00X+137426Y+070165X0200Y    R180 S0      
317PVDDCR_CPU0_P0   VIA   -    MD0100PA00X+137426Y+070665X0200Y    R180 S0      
317PVDDCR_CPU0_P0   VIA   -    MD0100PA00X+137676Y+070415X0200Y    R180 S0      
317PVDDCR_CPU0_P0   VIA   -    MD0100PA00X+137676Y+070165X0200Y    R180 S0      
317PVDDCR_CPU0_P0   VIA   -    MD0100PA00X+137676Y+070665X0200Y    R180 S0      
317PVDDCR_CPU0_P0   VIA   -    MD0100PA00X+137426Y+069915X0200Y    R180 S0      
317PVDDCR_CPU0_P0   VIA   -    MD0100PA00X+137676Y+069915X0200Y    R180 S0      
317PVDDCR_CPU0_P0   VIA   -    MD0100PA00X+137426Y+069665X0200Y    R180 S0      
317PVDDCR_CPU0_P0   VIA   -    MD0100PA00X+137676Y+069665X0200Y    R180 S0      
317PVDDCR_CPU0_P0   VIA   -    MD0100PA00X+137426Y+069415X0200Y    R180 S0      
317PVDDCR_CPU0_P0   VIA   -    MD0100PA00X+137676Y+069415X0200Y    R180 S0      
317PVDDCR_CPU0_P0   VIA   -    MD0100PA00X+154611Y+070458X0200Y    R180 S0      
327PVDDCR_CPU0_P0   PR351 -2          A18X+154752Y+070740X0198Y0197R090 S2      
317PVDDCR_CPU0_P0   VIA   -    MD0100PA00X+151331Y+070458X0200Y    R180 S0      
327PVDDCR_CPU0_P0   PR350 -2          A18X+151472Y+070740X0198Y0197R090 S2      
327PVDDCR_CPU0_P0   PR325 -2          A18X+148164Y+070740X0198Y0197R090 S2      
317PVDDCR_CPU0_P0   VIA   -    MD0100PA00X+148023Y+070458X0200Y    R180 S0      
327PVDDCR_CPU0_P0   PR355 -2          A18X+141612Y+065524X0198Y0197R090 S2      
317PVDDCR_CPU0_P0   VIA   -    MD0100PA00X+141471Y+065301X0200Y    R180 S0      
317PVDD33_S5_EN     VIA   -    M      A01X+081177Y+135549X0200Y    R180 S2      
017PVDD33_S5_EN     VIA   -    M      A18X+081177Y+135549X0260Y    R180 S2      
017PVDD33_S5_EN           -    MD0100PA00X+081177Y+135549                       
327PVDD33_S5_EN     PU55  -8          A01X+079628Y+134589X0070Y0320R270 S1      
327PVDD33_S5_EN     C348  -1   M      A01X+080470Y+135199X0198Y0197     S1      
317PVDD33_S5_EN     VIA   -    MD0100PA00X+075453Y+073586X0200Y         S0      
317PVDD33_S5_EN     VIA   -    MD0100PA00X+085448Y+064744X0200Y         S0      
327PVDD33_S5_EN     R224  -1          A18X+078283Y+043850X0198Y0197     S2      
317PVDD33_S5_EN     VIA   -    MD0100PA00X+083381Y+042326X0200Y         S0      
317PVDD33_S5_EN     VIA   -    MD0100PA00X+071216Y+067691X0200Y         S0      
327m3962            PR399 -2          A01X+023282Y+056400X0198Y0197R270 S1      
327m3962            VIA   -    M      A01X+024631Y+056151X0160Y0041R180 S1      
327m3962            PR401 -1   M      A01X+028000Y+057040X0198Y0197R180 S1      
327m3962            PU3   -6          A01X+027658Y+059422X0070Y0320R180 S1      
327m3962            PC62  -2   M      A01X+027998Y+058518X0198Y0197     S1      
327m3962            PR147 -2          A01X+028373Y+058518X0198Y0197R180 S1      
327m3962            PC6006-2   M      A01X+028057Y+057402X0198Y0197R180 S1      
327m3963            PC20  -1          A01X+026784Y+061117X0198Y0197     S1      
327m3963            PU3   -19         A01X+026831Y+060525X0120Y0320     S1      
327m3963            PR397 -2          A18X+029732Y+058603X0198Y0197R270 S2      
317m3963            VIA   -    M      A01X+026760Y+060838X0200Y         S2      
017m3963            VIA   -    M      A18X+026760Y+060838X0260Y         S2      
017m3963                  -    MD0100PA00X+026760Y+060838                       
327m3964            R289  -2          A18X+077508Y+041934X0198Y0197     S2      
317m3964            VIA   -    MD0100PA00X+077172Y+042680X0200Y         S0      
327m3964            U18   -V8         A01X+075087Y+044194X0160Y    R090 S1      
317m3964            VIA   -    MD0100PA00X+075241Y+044040X0180Y    R090 S2      
327m3965            VIA   -    M      A01X+027556Y+058940X0160Y0041R110 S1      
327m3965            PU3   -5          A01X+027500Y+059422X0070Y0320R180 S1      
327m3965            PC153 -1          A01X+027680Y+058165X0198Y0197R270 S1      
327m3965            PC62  -1   M      A01X+027683Y+058518X0198Y0197     S1      
317m3966            VIA   -    MD0100PA00X+027321Y+058824X0200Y         S2      
327m3966            PU3   -4          A01X+027343Y+059422X0070Y0320R180 S1      
327m3966            PR398 -2          A01X+027307Y+058514X0198Y0197R090 S1      
327m3967            PR402 -2          A01X+022868Y+056403X0198Y0197R270 S1      
327m3967            VIA   -    M      A01X+026521Y+055951X0160Y0041R180 S1      
327m3967            PR400 -1   M      A01X+028372Y+057040X0198Y0197     S1      
327m3967            PC6006-1   M      A01X+028372Y+057402X0198Y0197R180 S1      
327m3967            PC64  -2   M      A01X+028372Y+057770X0198Y0197R180 S1      
327m3967            PR148 -2          A01X+028372Y+058130X0198Y0197R180 S1      
327m3968            PU3   -7          A01X+027816Y+059422X0070Y0320R180 S1      
327m3968            PR147 -1   M      A01X+028688Y+058518X0198Y0197R180 S1      
327m3968            PR148 -1   M      A01X+028687Y+058130X0198Y0197R180 S1      
327m3968            PC64  -1          A01X+028687Y+057770X0198Y0197R180 S1      
327m3969            R289  -1          A18X+077823Y+041934X0198Y0197     S2      
317m3969            VIA   -    MD0100PA00X+080341Y+040398X0200Y         S0      
317m3969            VIA   -    MD0100PA00X+078553Y+027046X0200Y         S0      
327m3969            PU3   -8          A01X+027973Y+059422X0070Y0320R180 S1      
327m3969            C675  -1   M      A01X+029270Y+058603X0198Y0197R270 S1      
317m3969            VIA   -    M      A01X+029430Y+057719X0200Y         S2      
017m3969            VIA   -    M      A18X+029430Y+057719X0260Y         S2      
017m3969                  -    MD0100PA00X+029430Y+057719                       
327m3970            VIA   -    M      A01X+027029Y+058946X0160Y0041R060 S1      
327m3970            PU3   -3          A01X+027186Y+059422X0070Y0320R180 S1      
327m3970            PR8   -1          A01X+026940Y+058511X0198Y0197R270 S1      
327PVDD18_S5_P1     U26   -BH27       A01X+048196Y+103339X0177Y    R180 S1      
317PVDD18_S5_P1     VIA   -    MD0080PA00X+048380Y+103443X0160Y         S0      
317PVDD18_S5_P1     VIA   -    MD0100PA00X+036667Y+080359X0200Y    R180 S0      
317PVDD18_S5_P1     VIA   -    MD0100PA00X+037167Y+080359X0200Y    R180 S0      
317PVDD18_S5_P1     VIA   -    MD0100PA00X+051701Y+085649X0200Y         S0      
327PVDD18_S5_P1     R527  -1          A18X+057567Y+080346X0198Y0197R090 S2      
317PVDD18_S5_P1     VIA   -    MD0100PA00X+058850Y+081209X0200Y    R180 S0      
327PVDD18_S5_P1     R528  -1          A18X+058757Y+080356X0198Y0197R090 S2      
327PVDD18_S5_P1     R526  -1          A18X+060326Y+080052X0198Y0197R090 S2      
327PVDD18_S5_P1     R525  -1          A18X+059157Y+079676X0198Y0197R090 S2      
317PVDD18_S5_P1     VIA   -    MD0100PA00X+059682Y+080269X0200Y    R180 S0      
327PVDD18_S5_P1     R523  -1          A18X+060377Y+078596X0198Y0197R090 S2      
327PVDD18_S5_P1     R524  -1          A18X+061557Y+078596X0198Y0197R090 S2      
317PVDD18_S5_P1     VIA   -    MD0100PA00X+061557Y+078845X0200Y    R180 S0      
317PVDD18_S5_P1     VIA   -    MD0100PA00X+060940Y+078868X0200Y    R180 S0      
317PVDD18_S5_P1     VIA   -    MD0100PA00X+060034Y+080065X0200Y    R180 S0      
317PVDD18_S5_P1     VIA   -    MD0100PA00X+059257Y+080909X0200Y    R180 S0      
317PVDD18_S5_P1     VIA   -    MD0100PA00X+037667Y+080359X0200Y    R180 S0      
317PVDD18_S5_P1     VIA   -    MD0100PA00X+035167Y+080359X0200Y    R180 S0      
317PVDD18_S5_P1     VIA   -    MD0100PA00X+035667Y+080359X0200Y    R180 S0      
317PVDD18_S5_P1     VIA   -    MD0100PA00X+036167Y+080359X0200Y    R180 S0      
327PVDD18_S5_P1     R540  -2          A18X+035281Y+080610X0198Y0197R090 S2      
327PVDD18_S5_P1     R539  -2          A18X+035631Y+080610X0198Y0197R090 S2      
327PVDD18_S5_P1     R538  -2          A18X+035981Y+080610X0198Y0197R090 S2      
327PVDD18_S5_P1     R537  -2          A18X+036331Y+080610X0198Y0197R090 S2      
327PVDD18_S5_P1     R533  -2          A18X+037031Y+080610X0198Y0197R090 S2      
327PVDD18_S5_P1     R532  -2          A18X+037381Y+080610X0198Y0197R090 S2      
327PVDD18_S5_P1     R531  -2          A18X+037731Y+080610X0198Y0197R090 S2      
327PVDD18_S5_P1     R534  -2          A18X+036681Y+080610X0198Y0197R090 S2      
317PVDD18_S5_P1     VIA   -    MD0100PA00X+092550Y+090750X0200Y         S0      
327PVDD18_S5_P1     R369  -1          A18X+092550Y+091042X0198Y0197R270 S2      
317PVDD18_S5_P1     VIA   -    MD0100PA00X+093850Y+090750X0200Y         S0      
327PVDD18_S5_P1     R366  -1          A18X+093850Y+091042X0198Y0197R270 S2      
317PVDD18_S5_P1     VIA   -    MD0080PA00X+039012Y+098486X0160Y    R180 S0      
317PVDD18_S5_P1     VIA   -    MD0080PA00X+038827Y+098167X0160Y    R180 S0      
317PVDD18_S5_P1     VIA   -    MD0080PA00X+038272Y+098486X0160Y    R180 S0      
317PVDD18_S5_P1     VIA   -    MD0080PA00X+038087Y+098167X0160Y    R180 S0      
317PVDD18_S5_P1     VIA   -    MD0080PA00X+039012Y+100399X0160Y    R180 S0      
317PVDD18_S5_P1     VIA   -    MD0080PA00X+038827Y+100718X0160Y    R180 S0      
317PVDD18_S5_P1     VIA   -    MD0080PA00X+038272Y+100399X0160Y    R180 S0      
317PVDD18_S5_P1     VIA   -    MD0080PA00X+038087Y+100718X0160Y    R180 S0      
317PVDD18_S5_P1     VIA   -    MD0080PA00X+038827Y+100080X0160Y    R180 S0      
317PVDD18_S5_P1     VIA   -    MD0080PA00X+039012Y+099124X0160Y    R180 S0      
317PVDD18_S5_P1     VIA   -    MD0080PA00X+038827Y+098805X0160Y    R180 S0      
317PVDD18_S5_P1     VIA   -    MD0080PA00X+039012Y+099762X0160Y    R180 S0      
317PVDD18_S5_P1     VIA   -    MD0080PA00X+038827Y+099443X0160Y    R180 S0      
317PVDD18_S5_P1     VIA   -    MD0080PA00X+038087Y+100080X0160Y    R180 S0      
317PVDD18_S5_P1     VIA   -    MD0080PA00X+038272Y+099124X0160Y    R180 S0      
317PVDD18_S5_P1     VIA   -    MD0080PA00X+038272Y+099762X0160Y    R180 S0      
317PVDD18_S5_P1     VIA   -    MD0080PA00X+038087Y+099443X0160Y    R180 S0      
317PVDD18_S5_P1     VIA   -    MD0080PA00X+038087Y+098805X0160Y    R180 S0      
317PVDD18_S5_P1     VIA   -    MD0080PA00X+039567Y+100080X0160Y    R180 S0      
317PVDD18_S5_P1     VIA   -    MD0080PA00X+039567Y+098805X0160Y    R180 S0      
317PVDD18_S5_P1     VIA   -    MD0080PA00X+039567Y+099443X0160Y    R180 S0      
317PVDD18_S5_P1     VIA   -    MD0080PA00X+039752Y+099124X0160Y    R180 S0      
327PVDD18_S5_P1     C2292 -1   M      A18X+039560Y+100027X0198Y0197R180 S2      
327PVDD18_S5_P1     C2293 -1   M      A18X+038858Y+100727X0198Y0197R180 S2      
327PVDD18_S5_P1     C2660 -1          A18X+041559Y+100986X0198Y0197R180 S2      
327PVDD18_S5_P1     C2661 -1   M      A18X+038978Y+100377X0198Y0197     S2      
327PVDD18_S5_P1     C2663 -1   M      A18X+038860Y+099449X0198Y0197R180 S2      
327PVDD18_S5_P1     C2664 -1          A01X+042504Y+101477X0198Y0197     S1      
327PVDD18_S5_P1     C2665 -1   M      A18X+039560Y+099449X0198Y0197R180 S2      
327PVDD18_S5_P1     C2667 -1          A01X+041559Y+100986X0198Y0197     S1      
327PVDD18_S5_P1     C2668 -1          A18X+042504Y+101477X0198Y0197R180 S2      
327PVDD18_S5_P1     C2669 -1   M      A18X+038870Y+098777X0198Y0197R180 S2      
327PVDD18_S5_P1     C2670 -1   M      A18X+038820Y+098177X0198Y0197R180 S2      
327PVDD18_S5_P1     C2671 -1          A01X+041559Y+100612X0198Y0197     S1      
327PVDD18_S5_P1     C2672 -1   M      A18X+038870Y+100027X0198Y0197R180 S2      
327PVDD18_S5_P1     C2673 -1   M      A18X+039620Y+098777X0198Y0197R180 S2      
327PVDD18_S5_P1     C3909 -1          A18X+041559Y+100612X0198Y0197R180 S2      
317PVDD18_S5_P1     VIA   -    MD0100PA00X+021133Y+060692X0200Y    R090 S0      
317PVDD18_S5_P1     VIA   -    MD0100PA00X+020833Y+060692X0200Y    R090 S0      
317PVDD18_S5_P1     VIA   -    MD0100PA00X+022320Y+060968X0200Y    R090 S0      
317PVDD18_S5_P1     VIA   -    MD0100PA00X+022020Y+060968X0200Y    R090 S0      
317PVDD18_S5_P1     VIA   -    MD0100PA00X+021720Y+060968X0200Y    R090 S0      
317PVDD18_S5_P1     VIA   -    MD0100PA00X+021420Y+060968X0200Y    R090 S0      
317PVDD18_S5_P1     VIA   -    MD0100PA00X+022660Y+057097X0200Y    R090 S0      
327PVDD18_S5_P1     R8222 -1          A18X+008692Y+142150X0198Y0197R180 S2      
317PVDD18_S5_P1     VIA   -    MD0100PA00X+015090Y+142550X0200Y         S0      
327PVDD18_S5_P1     R8252 -1          A01X+014808Y+142550X0198Y0197R180 S1      
327PVDD18_S5_P1     PC363 -1   M      A01X+009908Y+143050X0198Y0197R180 S1      
317PVDD18_S5_P1     VIA   -    MD0100PA00X+009780Y+143300X0200Y         S0      
327PVDD18_S5_P1     R8247 -1          A18X+009592Y+143050X0198Y0197R180 S2      
327PVDD18_S5_P1     PU34  -19         A01X+010868Y+143271X0070Y0260R270 S1      
317PVDD18_S5_P1     VIA   -    MD0100PA00X+008683Y+140408X0200Y         S0      
327PVDD18_S5_P1     PR218 -1          A18X+008692Y+140800X0198Y0197R180 S2      
327PVDD18_S5_P1     R8220 -1          A18X+008692Y+141250X0198Y0197R180 S2      
327PVDD18_S5_P1     R8225 -1          A18X+008692Y+141700X0198Y0197R180 S2      
317PVDD18_S5_P1     VIA   -    MD0100PA00X+082444Y+124942X0200Y         S0      
317PVDD18_S5_P1     VIA   -    MD0100PA00X+044376Y+117940X0200Y         S0      
327PVDD18_S5_P1     R551  -2   M      A01X+056845Y+126494X0198Y0197R270 S1      
327PVDD18_S5_P1     R550  -2   M      A18X+057216Y+123816X0198Y0197R180 S2      
327PVDD18_S5_P1     R547  -2   M      A18X+057218Y+124210X0198Y0197R180 S2      
327PVDD18_S5_P1     R536  -2   M      A18X+057214Y+123408X0198Y0197R180 S2      
327PVDD18_S5_P1     R546  -2          A18X+057218Y+124596X0198Y0197R180 S2      
327PVDD18_S5_P1     R736  -1          A01X+060335Y+127860X0198Y0197R180 S1      
317PVDD18_S5_P1     VIA   -    MD0100PA00X+060662Y+127830X0200Y    R180 S0      
327PVDD18_S5_P1     R583  -2          A01X+060335Y+126260X0198Y0197     S1      
327PVDD18_S5_P1     R730  -1          A18X+060177Y+126970X0198Y0197R270 S2      
317PVDD18_S5_P1     VIA   -    M      A01X+060577Y+126310X0200Y    R180 S2      
017PVDD18_S5_P1     VIA   -    M      A18X+060577Y+126310X0260Y    R180 S2      
017PVDD18_S5_P1           -    MD0100PA00X+060577Y+126310                       
327PVDD18_S5_P1     R374  -1          A01X+059075Y+126267X0198Y0197R180 S1      
327PVDD18_S5_P1     R549  -2   M      A18X+061636Y+127867X0198Y0197R180 S2      
327PVDD18_S5_P1     R562  -1          A18X+061636Y+127480X0198Y0197     S2      
317PVDD18_S5_P1     VIA   -    MD0100PA00X+061876Y+127867X0200Y    R180 S0      
327PVDD18_S5_P1     R548  -2   M      A18X+061635Y+126699X0198Y0197R180 S2      
327PVDD18_S5_P1     R559  -1          A18X+061636Y+127089X0198Y0197     S2      
317PVDD18_S5_P1     VIA   -    MD0100PA00X+061876Y+126699X0200Y    R180 S0      
317PVDD18_S5_P1     VIA   -    MD0100PA00X+059553Y+126267X0200Y    R180 S0      
317PVDD18_S5_P1     VIA   -    MD0100PA00X+057420Y+122990X0200Y    R180 S0      
317PVDD18_S5_P1     VIA   -    MD0100PA00X+057078Y+126301X0200Y    R180 S0      
327PVDD18_S5_P1     R1501 -1          A18X+056978Y+125279X0198Y0197R180 S2      
317PVDD18_S5_P1     VIA   -    MD0100PA00X+061663Y+137508X0200Y    R270 S0      
327PVDD18_S5_P1     PR391 -2          A01X+061924Y+137508X0198Y0197R180 S1      
317PVDD18_S5_P1     VIA   -    MD0100PA00X+003504Y+129538X0200Y    R090 S0      
317PVDD18_S5_P1     VIA   -    MD0100PA00X+003508Y+129836X0200Y    R090 S0      
317PVDD18_S5_P1     VIA   -    MD0100PA00X+003504Y+129243X0200Y    R090 S0      
327PVDD18_S5_P1     R518  -1          A18X+036091Y+119813X0198Y0197     S2      
327PVDD18_S5_P1     R544  -2          A18X+037036Y+119215X0198Y0197     S2      
327PVDD18_S5_P1     R545  -2   M      A18X+037042Y+119586X0198Y0197     S2      
327PVDD18_S5_P1     R1424 -1   M      A18X+037970Y+120749X0198Y0197R180 S2      
317PVDD18_S5_P1     VIA   -    MD0100PA00X+037627Y+120749X0200Y    R180 S0      
317PVDD18_S5_P1     VIA   -    MD0100PA00X+036793Y+119698X0200Y         S0      
317PVDD18_S5_P1     VIA   -    MD0100PA00X+037032Y+120467X0200Y    R180 S0      
327PVDD18_S5_P1     R456  -2          A18X+037032Y+120754X0198Y0197     S2      
317PVDD18_S5_P1     VIA   -    MD0100PA00X+036324Y+119963X0200Y         S0      
317PVDD18_S5_P1     VIA   -    MD0100PA00X+034711Y+117434X0200Y         S0      
317PVDD18_S5_P1     VIA   -    MD0100PA00X+005775Y+127047X0200Y         S0      
317PVDD18_S5_P1     VIA   -    MD0100PA00X+003501Y+128948X0200Y    R090 S0      
327PVDD18_S5_P1     R1285 -2          A18X+071484Y+052850X0198Y0197R270 S2      
317PVDD18_S5_P1     VIA   -    MD0100PA00X+021125Y+060324X0200Y    R090 S0      
317PVDD18_S5_P1     VIA   -    MD0100PA00X+020825Y+060324X0200Y    R090 S0      
317PVDD18_S5_P1     VIA   -    MD0100PA00X+020825Y+059514X0200Y    R090 S0      
317PVDD18_S5_P1     VIA   -    MD0100PA00X+021125Y+059514X0200Y    R090 S0      
317PVDD18_S5_P1     VIA   -    MD0100PA00X+022011Y+060378X0200Y    R090 S0      
317PVDD18_S5_P1     VIA   -    MD0100PA00X+022890Y+060969X0200Y    R090 S0      
317PVDD18_S5_P1     VIA   -    MD0100PA00X+022590Y+060969X0200Y    R090 S0      
317PVDD18_S5_P1     VIA   -    MD0100PA00X+022311Y+060378X0200Y    R090 S0      
317PVDD18_S5_P1     VIA   -    MD0100PA00X+021420Y+060694X0200Y    R090 S0      
317PVDD18_S5_P1     VIA   -    MD0100PA00X+022320Y+060694X0200Y    R090 S0      
317PVDD18_S5_P1     VIA   -    MD0100PA00X+022020Y+060694X0200Y    R090 S0      
317PVDD18_S5_P1     VIA   -    MD0100PA00X+021720Y+060694X0200Y    R090 S0      
317PVDD18_S5_P1     VIA   -    MD0100PA00X+022100Y+058567X0200Y    R090 S0      
317PVDD18_S5_P1     VIA   -    MD0100PA00X+022400Y+058567X0200Y    R090 S0      
327PVDD18_S5_P1     PC21  -1          A01X+022906Y+057113X0198Y0197     S1      
327PVDD18_S5_P1     PR402 -1          A01X+022868Y+056718X0198Y0197R270 S1      
327PVDD18_S5_P1     PC65  -1          A18X+022743Y+060560X0400Y0500     S2      
327PVDD18_S5_P1     PC87  -1          A18X+022742Y+059756X0400Y0500     S2      
327PVDD18_S5_P1     PC84  -1          A18X+022742Y+058946X0400Y0500     S2      
327PVDD18_S5_P1     PR403 -1          A18X+022906Y+058395X0198Y0197R180 S2      
317PVDD18_S5_P1     VIA   -    MD0100PA00X+021800Y+058567X0200Y    R090 S0      
327PVDD18_S5_P1     PL57  -2          A01X+022052Y+059441X1380Y1380R180 S1      
327PVDD18_S5_P1     R8160 -1          A01X+035673Y+058242X0198Y0197R180 S1      
327PVDD18_S5_P1     R8156 -1          A01X+035673Y+057842X0198Y0197R180 S1      
327PVDD18_S5_P1     U26   -AR52       A01X+039011Y+098272X0177Y    R180 S1      
327PVDD18_S5_P1     U26   -AR54       A01X+038271Y+098272X0177Y    R180 S1      
327PVDD18_S5_P1     U26   -AT51       A01X+039196Y+098591X0177Y    R180 S1      
327PVDD18_S5_P1     U26   -AT53       A01X+038456Y+098591X0177Y    R180 S1      
327PVDD18_S5_P1     U26   -AU50       A01X+039751Y+098910X0177Y    R180 S1      
327PVDD18_S5_P1     U26   -AU52       A01X+039011Y+098910X0177Y    R180 S1      
327PVDD18_S5_P1     U26   -AU54       A01X+038271Y+098910X0177Y    R180 S1      
327PVDD18_S5_P1     U26   -AV49       A01X+039936Y+099228X0177Y    R180 S1      
327PVDD18_S5_P1     U26   -AV51       A01X+039196Y+099228X0177Y    R180 S1      
327PVDD18_S5_P1     U26   -AV53       A01X+038456Y+099228X0177Y    R180 S1      
327PVDD18_S5_P1     U26   -AW50       A01X+039751Y+099547X0177Y    R180 S1      
327PVDD18_S5_P1     U26   -AW52       A01X+039011Y+099547X0177Y    R180 S1      
327PVDD18_S5_P1     U26   -AW54       A01X+038271Y+099547X0177Y    R180 S1      
327PVDD18_S5_P1     U26   -AY51       A01X+039196Y+099866X0177Y    R180 S1      
327PVDD18_S5_P1     U26   -AY53       A01X+038456Y+099866X0177Y    R180 S1      
327PVDD18_S5_P1     U26   -BA50       A01X+039751Y+100185X0177Y    R180 S1      
327PVDD18_S5_P1     U26   -BA52       A01X+039011Y+100185X0177Y    R180 S1      
327PVDD18_S5_P1     U26   -BA54       A01X+038271Y+100185X0177Y    R180 S1      
327PVDD18_S5_P1     U26   -BB51       A01X+039196Y+100504X0177Y    R180 S1      
327PVDD18_S5_P1     U26   -BB53       A01X+038456Y+100504X0177Y    R180 S1      
327PVDD18_S5_P1     U26   -BC52       A01X+039011Y+100823X0177Y    R180 S1      
327PVDD18_S5_P1     U26   -BC54       A01X+038271Y+100823X0177Y    R180 S1      
317PVDD18_S5_P1     VIA   -    MD0100PA00X+020693Y+073728X0200Y         S0      
317PVDD18_S5_P1     VIA   -    MD0100PA00X+026097Y+077799X0200Y    R180 S0      
327PVDD18_S5_P1     R535  -2          A18X+027470Y+079799X0198Y0197     S2      
327PVDD18_S5_P1     R556  -1          A18X+026987Y+079506X0198Y0197R090 S2      
317PVDD18_S5_P1     VIA   -    MD0100PA00X+027085Y+079760X0200Y    R180 S0      
317PVDD18_S5_P1     VIA   -    MD0100PA00X+028145Y+080961X0200Y    R180 S0      
327PVDD18_S5_P1     R557  -1          A18X+028218Y+080405X0198Y0197R180 S2      
327PVDD18_S5_P1     R553  -2          A18X+026300Y+078479X0198Y0197     S2      
327PVDD18_S5_P1     R558  -2   M      A18X+026300Y+078059X0198Y0197     S2      
327PVDD18_S5_P1     R520  -2          A18X+023320Y+075216X0198Y0197R270 S2      
317PVDD18_S5_P1     VIA   -    MD0100PA00X+042487Y+101474X0190Y    R180 S0      
317PVDD18_S5_P1     VIA   -    MD0100PA00X+041532Y+100602X0190Y    R270 S0      
317PVDD18_S5_P1     VIA   -    MD0100PA00X+041532Y+100976X0190Y    R270 S0      
317PVDD18_S5_P1     VIA   -    MD0100PA00X+045372Y+052656X0200Y         S0      
327PVDD18_S5_P1     R154  -1          A01X+035913Y+058642X0198Y0197R180 S1      
327PVDD18_S5_P1     PU25  -19         A18X+036534Y+057070X0070Y0260R270 S2      
327PVDD18_S5_P1     PC247 -1          A18X+035673Y+057042X0198Y0197     S2      
327PVDD18_S5_P1     PR151 -1          A01X+035913Y+059042X0198Y0197R180 S1      
317PVDD18_S5_P1     VIA   -    MD0100PA00X+035966Y+057070X0200Y    R180 S0      
317PVDD18_S5_P1     VIA   -    MD0100PA00X+040338Y+057352X0200Y    R180 S0      
327PVDD18_S5_P1     R8180 -1          A01X+040067Y+057393X0198Y0197R270 S1      
327PVDD18_S5_P1     R8184 -1          A01X+035358Y+056642X0198Y0197     S1      
317PVDD18_S5_P1     VIA   -    MD0100PA00X+035116Y+056694X0200Y    R180 S0      
317PVDD18_S5_P1     VIA   -    MD0100PA00X+022702Y+062238X0200Y    R090 S0      
317PVDD18_S5_P1     VIA   -    MD0100PA00X+022402Y+062238X0200Y    R090 S0      
317PVDD18_S5_P1     VIA   -    MD0100PA00X+022702Y+063238X0200Y    R090 S0      
317PVDD18_S5_P1     VIA   -    MD0100PA00X+022402Y+063238X0200Y    R090 S0      
317PVDD18_S5_P1     VIA   -    MD0100PA00X+022102Y+062238X0200Y    R090 S0      
317PVDD18_S5_P1     VIA   -    MD0100PA00X+021802Y+062238X0200Y    R090 S0      
317PVDD18_S5_P1     VIA   -    MD0100PA00X+021802Y+063238X0200Y    R090 S0      
317PVDD18_S5_P1     VIA   -    MD0100PA00X+022102Y+063238X0200Y    R090 S0      
317PVDD18_S5_P1     VIA   -    MD0100PA00X+020801Y+061000X0200Y    R090 S0      
317PVDD18_S5_P1     VIA   -    MD0100PA00X+021101Y+061000X0200Y    R090 S0      
317PVDD18_S5_P1     VIA   -    MD0100PA00X+021500Y+058567X0200Y    R090 S0      
327PVDD18_S5_P1     PC89  -1          A01X+022130Y+062756X0630Y1190R270 S1      
327PVDD18_S5_P1     PC83  -1          A01X+020879Y+059924X0400Y0500     S1      
327PVDD18_S5_P1     PC88  -1          A01X+020879Y+059114X0400Y0500     S1      
317PVDD18_S5_P1     VIA   -    MD0100PA00X+071631Y+061013X0200Y         S0      
327PVDD18_S5_P1     R1286 -2          A01X+072050Y+054344X0198Y0197R090 S1      
317PVDD18_S5_P1     VIA   -    MD0100PA00X+072050Y+054621X0200Y         S0      
317PVDD18_S5_P1     VIA   -    MD0100PA00X+052932Y+040378X0200Y         S0      
317PVDD18_S5_P1     VIA   -    MD0100PA00X+109009Y+037042X0200Y         S0      
327PVDD18_S5_P1     U151  -15         A01X+109711Y+037803X0140Y0630R090 S1      
327PVDD18_S5_P1     C1517 -1   M      A01X+109009Y+037319X0198Y0197R180 S1      
317PVDD18_S5_P1     VIA   -    MD0100PA00X+051552Y+033561X0200Y         S0      
327PVDD18_S5_P1     R8011 -1          A18X+065860Y+137008X0198Y0197R090 S2      
317PVDD18_S5_P1     VIA   -    MD0100PA00X+066181Y+137008X0200Y         S0      
317PVDD18_S5_P1     VIA   -    MD0100PA00X+094094Y+129419X0200Y    R180 S0      
327PVDD18_S5_P1     R1236 -1          A18X+093812Y+129419X0198Y0197     S2      
317PVDD18_S5_P1     VIA   -    MD0100PA00X+086629Y+125590X0200Y         S0      
327m3971            PR477 -2          A18X+130724Y+053730X0198Y0197R180 S2      
327m3971            PC212 -1          A01X+133236Y+056177X0198Y0197R270 S1      
327m3971            PU57  -19         A01X+132644Y+056130X0120Y0320R270 S1      
317m3971            VIA   -    M      A01X+132958Y+056181X0200Y    R270 S2      
017m3971            VIA   -    M      A18X+132958Y+056181X0260Y    R270 S2      
017m3971                  -    MD0100PA00X+132958Y+056181                       
327m3972            PR418 -2          A01X+129176Y+059287X0198Y0197R180 S1      
327m3972            VIA   -    M      A01X+129170Y+056754X0160Y0041R090 S1      
327m3972            PR435 -1   M      A01X+129616Y+055587X0198Y0197R090 S1      
327m3972            PU57  -6          A01X+131541Y+055303X0070Y0320R090 S1      
327m3972            PC113 -2   M      A01X+130737Y+054964X0198Y0197R270 S1      
327m3972            PR470 -2   M      A01X+130377Y+054839X0198Y0197R090 S1      
327m3972            PC6005-2   M      A01X+129633Y+055215X0198Y0197     S1      
317m3973            VIA   -    MD0100PA00X+130987Y+055279X0200Y         S2      
327m3973            PU57  -5          A01X+131541Y+055461X0070Y0320R090 S1      
327m3973            PC258 -1          A01X+130384Y+055281X0198Y0197R180 S1      
327m3973            PC113 -1   M      A01X+130737Y+055279X0198Y0197R270 S1      
327m3974            VIA   -    M      A01X+131045Y+055618X0160Y0041R180 S1      
327m3974            PR417 -2          A01X+130733Y+055654X0198Y0197     S1      
327m3974            PU57  -4          A01X+131541Y+055618X0070Y0320R090 S1      
327m3975            PR438 -1          A01X+129179Y+059701X0198Y0197     S1      
327m3975            VIA   -    M      A01X+128957Y+056283X0160Y0041R090 S1      
327m3975            PC6005-1   M      A01X+129318Y+055215X0198Y0197     S1      
327m3975            PR434 -1   M      A01X+129279Y+054840X0198Y0197R270 S1      
327m3975            PC259 -2   M      A01X+129639Y+054840X0198Y0197R090 S1      
327m3975            PR471 -2          A01X+129999Y+054840X0198Y0197R090 S1      
327m3976            VIA   -    M      A01X+130705Y+054669X0160Y0041R225 S1      
327m3976            PU57  -7          A01X+131541Y+055146X0070Y0320R090 S1      
327m3976            PR470 -1   M      A01X+130376Y+054524X0198Y0197R090 S1      
327m3976            PR471 -1   M      A01X+129999Y+054525X0198Y0197R090 S1      
327m3976            PC259 -1          A01X+129639Y+054525X0198Y0197R090 S1      
317m3977            VIA   -    M      A01X+114127Y+050030X0300Y         S1      
017m3977            VIA   -    M      A18X+114127Y+050030X0200Y         S1      
017m3977                  -    MD0100PA00X+114127Y+050030                       
327m3977            R176  -1          A01X+077823Y+043534X0198Y0197R180 S1      
317m3977            VIA   -    MD0100PA00X+078058Y+043556X0200Y    R180 S0      
327m3977            PU57  -8          A01X+131541Y+054988X0070Y0320R090 S1      
327m3977            C674  -1   M      A01X+130031Y+054163X0198Y0197R180 S1      
317m3978            VIA   -    MD0100PA00X+130978Y+055983X0200Y         S2      
327m3978            PR448 -1          A01X+130730Y+056021X0198Y0197R180 S1      
327m3978            PU57  -3          A01X+131541Y+055776X0070Y0320R090 S1      
327PVDD18_S5_P0     U25   -BH27       A01X+145810Y+103339X0177Y    R180 S1      
317PVDD18_S5_P0     VIA   -    MD0080PA00X+145994Y+103443X0160Y         S0      
317PVDD18_S5_P0     VIA   -    MD0100PA00X+140102Y+101474X0190Y    R180 S0      
327PVDD18_S5_P0     C2525 -1          A01X+140116Y+101474X0198Y0197     S1      
327PVDD18_S5_P0     C2517 -1          A18X+140116Y+101474X0198Y0197R180 S2      
317PVDD18_S5_P0     VIA   -    MD0080PA00X+136441Y+100080X0160Y    R180 S0      
317PVDD18_S5_P0     VIA   -    MD0080PA00X+135701Y+100080X0160Y    R180 S0      
317PVDD18_S5_P0     VIA   -    MD0080PA00X+136441Y+099443X0160Y    R180 S0      
317PVDD18_S5_P0     VIA   -    MD0080PA00X+136441Y+098805X0160Y    R180 S0      
317PVDD18_S5_P0     VIA   -    MD0080PA00X+135886Y+099124X0160Y    R180 S0      
317PVDD18_S5_P0     VIA   -    MD0080PA00X+135701Y+099443X0160Y    R180 S0      
317PVDD18_S5_P0     VIA   -    MD0080PA00X+135886Y+099762X0160Y    R180 S0      
317PVDD18_S5_P0     VIA   -    MD0080PA00X+135701Y+098805X0160Y    R180 S0      
317PVDD18_S5_P0     VIA   -    MD0080PA00X+135886Y+098486X0160Y    R180 S0      
317PVDD18_S5_P0     VIA   -    MD0080PA00X+136441Y+098167X0160Y    R180 S0      
317PVDD18_S5_P0     VIA   -    MD0080PA00X+135701Y+098167X0160Y    R180 S0      
317PVDD18_S5_P0     VIA   -    MD0080PA00X+136441Y+100718X0160Y    R180 S0      
317PVDD18_S5_P0     VIA   -    MD0080PA00X+135886Y+100399X0160Y    R180 S0      
317PVDD18_S5_P0     VIA   -    MD0080PA00X+135701Y+100718X0160Y    R180 S0      
317PVDD18_S5_P0     VIA   -    MD0080PA00X+136626Y+100399X0160Y    R180 S0      
317PVDD18_S5_P0     VIA   -    MD0080PA00X+136626Y+099124X0160Y    R180 S0      
317PVDD18_S5_P0     VIA   -    MD0080PA00X+136626Y+099762X0160Y    R180 S0      
317PVDD18_S5_P0     VIA   -    MD0080PA00X+137182Y+100080X0160Y    R180 S0      
317PVDD18_S5_P0     VIA   -    MD0080PA00X+137182Y+099443X0160Y    R180 S0      
317PVDD18_S5_P0     VIA   -    MD0080PA00X+137182Y+098805X0160Y    R180 S0      
317PVDD18_S5_P0     VIA   -    MD0080PA00X+137367Y+099124X0160Y    R180 S0      
317PVDD18_S5_P0     VIA   -    MD0080PA00X+136626Y+098486X0160Y    R180 S0      
327PVDD18_S5_P0     C2163 -1          A18X+139173Y+100986X0198Y0197R180 S2      
327PVDD18_S5_P0     C2164 -1          A01X+139173Y+100612X0198Y0197     S1      
327PVDD18_S5_P0     C2513 -1   M      A18X+136460Y+098176X0198Y0197R180 S2      
327PVDD18_S5_P0     C2514 -1   M      A18X+137210Y+098776X0198Y0197R180 S2      
327PVDD18_S5_P0     C2516 -1   M      A18X+136460Y+099426X0198Y0197R180 S2      
327PVDD18_S5_P0     C2518 -1   M      A18X+137160Y+099426X0198Y0197R180 S2      
327PVDD18_S5_P0     C2520 -1   M      A18X+136593Y+100376X0198Y0197     S2      
327PVDD18_S5_P0     C2521 -1   M      A18X+136460Y+098776X0198Y0197R180 S2      
327PVDD18_S5_P0     C2522 -1   M      A18X+137200Y+100026X0198Y0197R180 S2      
327PVDD18_S5_P0     C2523 -1   M      A18X+136460Y+100026X0198Y0197R180 S2      
327PVDD18_S5_P0     C2524 -1   M      A18X+136473Y+100726X0198Y0197R180 S2      
327PVDD18_S5_P0     C2526 -1          A18X+139173Y+100612X0198Y0197R180 S2      
327PVDD18_S5_P0     C3897 -1          A01X+139173Y+100986X0198Y0197     S1      
327PVDD18_S5_P0     PU12  -19         A01X+120968Y+141921X0070Y0260R270 S1      
327PVDD18_S5_P0     C1505 -1   M      A01X+057391Y+021777X0198Y0197R270 S1      
327PVDD18_S5_P0     U147  -6          A01X+057510Y+022274X0070Y0320R180 S1      
317PVDD18_S5_P0     VIA   -    MD0100PA00X+057143Y+021777X0200Y         S0      
327PVDD18_S5_P0     C1518 -1   M      A01X+050435Y+021328X0198Y0197R180 S1      
327PVDD18_S5_P0     U152  -6          A01X+050932Y+021407X0070Y0320R090 S1      
327PVDD18_S5_P0     U152  -7          A01X+050932Y+021250X0070Y0320R090 S1      
317PVDD18_S5_P0     VIA   -    MD0100PA00X+050435Y+021590X0200Y    R090 S0      
327PVDD18_S5_P0     U146  -7          A01X+048397Y+021841X0070Y0320     S1      
327PVDD18_S5_P0     U146  -6          A01X+048554Y+021841X0070Y0320     S1      
327PVDD18_S5_P0     C1504 -1   M      A01X+048475Y+022338X0198Y0197R090 S1      
317PVDD18_S5_P0     VIA   -    MD0100PA00X+048744Y+022338X0200Y    R270 S0      
327PVDD18_S5_P0     U146  -10         A01X+048116Y+021408X0070Y0310R090 S1      
317PVDD18_S5_P0     VIA   -    MD0100PA00X+048072Y+021110X0200Y         S0      
327PVDD18_S5_P0     R617  -1          A01X+048318Y+020683X0198Y0197     S1      
317PVDD18_S5_P0     VIA   -    MD0100PA00X+048070Y+020820X0200Y         S0      
317PVDD18_S5_P0     VIA   -    MD0100PA00X+131354Y+061310X0200Y         S0      
327PVDD18_S5_P0     U150  -8          A01X+098667Y+040105X0140Y0630R180 S1      
327PVDD18_S5_P0     U150  -7          A01X+098923Y+040105X0140Y0630R180 S1      
317PVDD18_S5_P0     VIA   -    MD0100PA00X+098758Y+040833X0200Y         S0      
317PVDD18_S5_P0     VIA   -    MD0100PA00X+098460Y+040848X0200Y         S0      
327PVDD18_S5_P0     U150  -2          A01X+100202Y+040105X0140Y0630R180 S1      
327PVDD18_S5_P0     U150  -1          A01X+100458Y+040105X0140Y0630R180 S1      
327PVDD18_S5_P0     C1514 -1          A01X+100962Y+040214X0198Y0197R270 S1      
317PVDD18_S5_P0     VIA   -    M      A01X+100982Y+040490X0200Y         S2      
017PVDD18_S5_P0     VIA   -    M      A18X+100982Y+040490X0260Y         S2      
017PVDD18_S5_P0           -    MD0100PA00X+100982Y+040490                       
317PVDD18_S5_P0     VIA   -    MD0100PA00X+107166Y+036673X0200Y         S0      
327PVDD18_S5_P0     R1624 -1          A01X+107166Y+036979X0198Y0197R180 S1      
327PVDD18_S5_P0     C1516 -1          A01X+100446Y+036661X0198Y0197R270 S1      
327PVDD18_S5_P0     U150  -16         A01X+100458Y+037900X0140Y0630R180 S1      
327PVDD18_S5_P0     U150  -15         A01X+100202Y+037900X0140Y0630R180 S1      
317PVDD18_S5_P0     VIA   -    MD0100PA00X+100708Y+036709X0200Y         S0      
317PVDD18_S5_P0     VIA   -    MD0100PA00X+094950Y+088650X0200Y         S0      
327PVDD18_S5_P0     U96   -1          A18X+095487Y+088706X0240Y0460     S2      
327PVDD18_S5_P0     C612  -1   M      A18X+094950Y+088358X0198Y0197R090 S2      
317PVDD18_S5_P0     VIA   -    MD0100PA00X+091300Y+090900X0200Y         S0      
327PVDD18_S5_P0     R139  -2          A18X+091300Y+091242X0198Y0197R090 S2      
327PVDD18_S5_P0     R370  -1          A18X+094650Y+091042X0198Y0197R270 S2      
317PVDD18_S5_P0     VIA   -    MD0100PA00X+095117Y+091042X0200Y         S0      
327PVDD18_S5_P0     R367  -1          A18X+095450Y+091042X0198Y0197R270 S2      
327PVDD18_S5_P0     R368  -1          A18X+095392Y+090350X0198Y0197R180 S2      
317PVDD18_S5_P0     VIA   -    MD0100PA00X+095392Y+090050X0200Y         S0      
327PVDD18_S5_P0     R406  -1          A18X+096408Y+090350X0198Y0197     S2      
317PVDD18_S5_P0     VIA   -    MD0100PA00X+096408Y+090050X0200Y         S0      
327PVDD18_S5_P0     C24   -1   M      A18X+091800Y+092192X0198Y0197R270 S2      
327PVDD18_S5_P0     U213  -5          A18X+091295Y+092401X0100Y0220R180 S2      
317PVDD18_S5_P0     VIA   -    MD0100PA00X+092100Y+092192X0200Y         S0      
327PVDD18_S5_P0     R740  -1          A18X+154377Y+123848X0198Y0197R090 S2      
327PVDD18_S5_P0     R1233 -1          A18X+093820Y+129015X0198Y0197     S2      
317PVDD18_S5_P0     VIA   -    MD0100PA00X+094092Y+129015X0200Y    R180 S0      
317PVDD18_S5_P0     VIA   -    MD0100PA00X+096031Y+136265X0200Y         S0      
327PVDD18_S5_P0     R8070 -1          A18X+119692Y+141900X0198Y0197R180 S2      
317PVDD18_S5_P0     VIA   -    MD0100PA00X+119880Y+142150X0200Y         S0      
327PVDD18_S5_P0     PC73  -1   M      A01X+120008Y+141900X0198Y0197R180 S1      
327PVDD18_S5_P0     R8045 -1   M      A18X+118792Y+141000X0198Y0197R180 S2      
317PVDD18_S5_P0     VIA   -    MD0100PA00X+118300Y+142290X0200Y         S0      
327PVDD18_S5_P0     PR41  -1          A18X+118792Y+139650X0198Y0197R180 S2      
327PVDD18_S5_P0     R8043 -1   M      A18X+118792Y+140100X0198Y0197R180 S2      
327PVDD18_S5_P0     R8048 -1   M      A18X+118792Y+140550X0198Y0197R180 S2      
327PVDD18_S5_P0     R8075 -1          A01X+124858Y+141450X0198Y0197R180 S1      
317PVDD18_S5_P0     VIA   -    MD0100PA00X+125310Y+141350X0200Y         S0      
327PVDD18_S5_P0     R8036 -1          A18X+071850Y+057458X0198Y0197R090 S2      
327PVDD18_S5_P0     R1288 -2          A18X+072191Y+052833X0198Y0197R270 S2      
327PVDD18_S5_P0     PR438 -2          A01X+129494Y+059701X0198Y0197     S1      
327PVDD18_S5_P0     PC215 -1          A01X+129889Y+059663X0198Y0197R270 S1      
327PVDD18_S5_P0     PC261 -1          A18X+132044Y+060731X0400Y0500     S2      
327PVDD18_S5_P0     PC288 -1          A18X+132938Y+059824X0400Y0500R270 S2      
327PVDD18_S5_P0     PR439 -1          A18X+130782Y+059659X0198Y0197R090 S2      
327PVDD18_S5_P0     PC285 -1          A18X+131323Y+059826X0400Y0500R270 S2      
327PVDD18_S5_P0     PC260 -1          A18X+132133Y+059826X0400Y0500R270 S2      
317PVDD18_S5_P0     VIA   -    MD0100PA00X+146426Y+055750X0200Y    R180 S0      
327PVDD18_S5_P0     R8317 -1          A01X+146668Y+055698X0198Y0197     S1      
317PVDD18_S5_P0     VIA   -    MD0100PA00X+147276Y+056126X0200Y    R180 S0      
327PVDD18_S5_P0     PR284 -1          A01X+146983Y+058098X0198Y0197R180 S1      
327PVDD18_S5_P0     PC466 -1          A18X+146983Y+056098X0198Y0197     S2      
327PVDD18_S5_P0     PU42  -19         A18X+147844Y+056126X0070Y0260R270 S2      
327PVDD18_S5_P0     R8293 -1          A01X+146983Y+057298X0198Y0197R180 S1      
327PVDD18_S5_P0     R8289 -1          A01X+146983Y+056898X0198Y0197R180 S1      
327PVDD18_S5_P0     R8287 -1          A01X+146983Y+057698X0198Y0197R180 S1      
327PVDD18_S5_P0     R8313 -1          A01X+151383Y+056398X0198Y0197R180 S1      
317PVDD18_S5_P0     VIA   -    MD0100PA00X+130878Y+059918X0200Y    R180 S0      
317PVDD18_S5_P0     VIA   -    MD0100PA00X+130917Y+060171X0200Y    R180 S0      
327PVDD18_S5_P0     PL78  -2          A01X+132216Y+060900X1380Y1380R090 S1      
317PVDD18_S5_P0     VIA   -    MD0100PA00X+131727Y+059721X0200Y    R180 S0      
317PVDD18_S5_P0     VIA   -    MD0100PA00X+131727Y+060021X0200Y    R180 S0      
317PVDD18_S5_P0     VIA   -    MD0100PA00X+132130Y+062520X0200Y    R180 S0      
317PVDD18_S5_P0     VIA   -    MD0100PA00X+132130Y+062220X0200Y    R180 S0      
317PVDD18_S5_P0     VIA   -    MD0100PA00X+132130Y+061920X0200Y    R180 S0      
317PVDD18_S5_P0     VIA   -    MD0100PA00X+131830Y+061920X0200Y    R180 S0      
317PVDD18_S5_P0     VIA   -    MD0100PA00X+131830Y+062220X0200Y    R180 S0      
317PVDD18_S5_P0     VIA   -    MD0100PA00X+131830Y+062520X0200Y    R180 S0      
317PVDD18_S5_P0     VIA   -    MD0100PA00X+130880Y+062520X0200Y    R180 S0      
317PVDD18_S5_P0     VIA   -    MD0100PA00X+130880Y+062220X0200Y    R180 S0      
317PVDD18_S5_P0     VIA   -    MD0100PA00X+130880Y+061920X0200Y    R180 S0      
327PVDD18_S5_P0     PC114 -1          A18X+132044Y+061441X0400Y0500     S2      
327PVDD18_S5_P0     U25   -AR52       A01X+136625Y+098272X0177Y    R180 S1      
327PVDD18_S5_P0     U25   -AR54       A01X+135885Y+098272X0177Y    R180 S1      
327PVDD18_S5_P0     U25   -AT51       A01X+136810Y+098591X0177Y    R180 S1      
327PVDD18_S5_P0     U25   -AT53       A01X+136070Y+098591X0177Y    R180 S1      
327PVDD18_S5_P0     U25   -AU50       A01X+137365Y+098910X0177Y    R180 S1      
327PVDD18_S5_P0     U25   -AU52       A01X+136625Y+098910X0177Y    R180 S1      
327PVDD18_S5_P0     U25   -AU54       A01X+135885Y+098910X0177Y    R180 S1      
327PVDD18_S5_P0     U25   -AV49       A01X+137550Y+099228X0177Y    R180 S1      
327PVDD18_S5_P0     U25   -AV51       A01X+136810Y+099228X0177Y    R180 S1      
327PVDD18_S5_P0     U25   -AV53       A01X+136070Y+099228X0177Y    R180 S1      
327PVDD18_S5_P0     U25   -AW50       A01X+137365Y+099547X0177Y    R180 S1      
327PVDD18_S5_P0     U25   -AW52       A01X+136625Y+099547X0177Y    R180 S1      
327PVDD18_S5_P0     U25   -AW54       A01X+135885Y+099547X0177Y    R180 S1      
327PVDD18_S5_P0     U25   -AY51       A01X+136810Y+099866X0177Y    R180 S1      
327PVDD18_S5_P0     U25   -AY53       A01X+136070Y+099866X0177Y    R180 S1      
327PVDD18_S5_P0     U25   -BA50       A01X+137365Y+100185X0177Y    R180 S1      
327PVDD18_S5_P0     U25   -BA52       A01X+136625Y+100185X0177Y    R180 S1      
327PVDD18_S5_P0     U25   -BA54       A01X+135885Y+100185X0177Y    R180 S1      
327PVDD18_S5_P0     U25   -BB51       A01X+136810Y+100504X0177Y    R180 S1      
327PVDD18_S5_P0     U25   -BB53       A01X+136070Y+100504X0177Y    R180 S1      
327PVDD18_S5_P0     U25   -BC52       A01X+136625Y+100823X0177Y    R180 S1      
327PVDD18_S5_P0     U25   -BC54       A01X+135885Y+100823X0177Y    R180 S1      
317PVDD18_S5_P0     VIA   -    MD0100PA00X+133780Y+086776X0200Y         S0      
317PVDD18_S5_P0     VIA   -    MD0100PA00X+134130Y+086776X0200Y         S0      
317PVDD18_S5_P0     VIA   -    MD0100PA00X+133430Y+086776X0200Y         S0      
317PVDD18_S5_P0     VIA   -    MD0100PA00X+139146Y+100602X0190Y    R270 S0      
317PVDD18_S5_P0     VIA   -    MD0100PA00X+139146Y+100976X0190Y    R270 S0      
317PVDD18_S5_P0     VIA   -    MD0100PA00X+126668Y+080299X0200Y    R180 S0      
327PVDD18_S5_P0     R442  -2          A18X+126918Y+080125X0198Y0197R090 S2      
317PVDD18_S5_P0     VIA   -    MD0100PA00X+125118Y+079488X0200Y    R180 S0      
327PVDD18_S5_P0     R414  -2          A18X+128668Y+079415X0198Y0197R090 S2      
327PVDD18_S5_P0     R413  -2   M      A18X+128268Y+079415X0198Y0197R090 S2      
317PVDD18_S5_P0     VIA   -    MD0100PA00X+125930Y+079878X0200Y    R180 S0      
327PVDD18_S5_P0     R443  -2          A18X+126068Y+080125X0198Y0197R090 S2      
317PVDD18_S5_P0     VIA   -    MD0100PA00X+125498Y+078758X0200Y    R180 S0      
327PVDD18_S5_P0     R452  -2   M      A18X+127160Y+078732X0198Y0197     S2      
327PVDD18_S5_P0     R438  -2          A18X+127160Y+078332X0198Y0197     S2      
317PVDD18_S5_P0     VIA   -    MD0100PA00X+123826Y+077973X0200Y    R180 S0      
327PVDD18_S5_P0     R410  -2          A18X+126960Y+077432X0198Y0197     S2      
327PVDD18_S5_P0     R411  -2   M      A18X+126960Y+077032X0198Y0197     S2      
317PVDD18_S5_P0     VIA   -    MD0100PA00X+124413Y+078460X0200Y    R180 S0      
327PVDD18_S5_P0     R408  -2   M      A18X+126160Y+078182X0198Y0197     S2      
327PVDD18_S5_P0     R409  -2          A18X+126160Y+077782X0198Y0197     S2      
317PVDD18_S5_P0     VIA   -    MD0100PA00X+132242Y+065687X0200Y         S0      
327PVDD18_S5_P0     R400  -1   M      A18X+147418Y+081941X0198Y0197R270 S2      
317PVDD18_S5_P0     VIA   -    MD0100PA00X+147418Y+081687X0200Y    R180 S0      
317PVDD18_S5_P0     VIA   -    MD0100PA00X+148118Y+080349X0200Y    R180 S0      
317PVDD18_S5_P0     VIA   -    MD0100PA00X+150218Y+081701X0200Y    R180 S0      
317PVDD18_S5_P0     VIA   -    MD0100PA00X+155112Y+080129X0200Y         S0      
317PVDD18_S5_P0     VIA   -    MD0100PA00X+157058Y+080010X0200Y         S0      
327PVDD18_S5_P0     R454  -1          A18X+156767Y+079655X0198Y0197     S2      
317PVDD18_S5_P0     VIA   -    MD0100PA00X+155612Y+079854X0200Y         S0      
327PVDD18_S5_P0     R6132 -1          A18X+155611Y+080111X0198Y0197R270 S2      
327PVDD18_S5_P0     R6131 -1          A18X+155992Y+080110X0198Y0197R270 S2      
327PVDD18_S5_P0     R6130 -1          A18X+155032Y+080413X0198Y0197     S2      
327PVDD18_S5_P0     R399  -1          A18X+150218Y+081941X0198Y0197R270 S2      
317PVDD18_S5_P0     VIA   -    MD0100PA00X+148792Y+081677X0200Y    R180 S0      
327PVDD18_S5_P0     R402  -1          A18X+149018Y+081941X0198Y0197R270 S2      
327PVDD18_S5_P0     R401  -1   M      A18X+148618Y+081941X0198Y0197R270 S2      
317PVDD18_S5_P0     VIA   -    MD0100PA00X+148518Y+080349X0200Y    R180 S0      
327PVDD18_S5_P0     R403  -1          A18X+148518Y+080591X0198Y0197R270 S2      
327PVDD18_S5_P0     R398  -1          A18X+148118Y+080591X0198Y0197R270 S2      
327PVDD18_S5_P0     R416  -2          A01X+130068Y+075891X0198Y0197R270 S1      
317PVDD18_S5_P0     VIA   -    MD0100PA00X+130960Y+066770X0200Y         S0      
327PVDD18_S5_P0     R412  -2          A01X+127368Y+076191X0198Y0197R270 S1      
317PVDD18_S5_P0     VIA   -    MD0100PA00X+129230Y+065721X0200Y         S0      
327PVDD18_S5_P0     R418  -2          A01X+127768Y+076191X0198Y0197R270 S1      
317PVDD18_S5_P0     VIA   -    MD0100PA00X+129500Y+065520X0200Y         S0      
327PVDD18_S5_P0     R415  -2          A01X+128868Y+075891X0198Y0197R270 S1      
317PVDD18_S5_P0     VIA   -    MD0100PA00X+130190Y+066070X0200Y         S0      
317PVDD18_S5_P0     VIA   -    MD0100PA00X+129740Y+059941X0200Y    R180 S0      
317PVDD18_S5_P0     VIA   -    MD0100PA00X+130040Y+059941X0200Y         S0      
317PVDD18_S5_P0     VIA   -    MD0100PA00X+130754Y+060710X0200Y    R270 S0      
317PVDD18_S5_P0     VIA   -    MD0100PA00X+130754Y+060410X0200Y    R270 S0      
317PVDD18_S5_P0     VIA   -    MD0100PA00X+130754Y+061610X0200Y    R090 S0      
317PVDD18_S5_P0     VIA   -    MD0100PA00X+130754Y+061310X0200Y    R270 S0      
317PVDD18_S5_P0     VIA   -    MD0100PA00X+130754Y+061010X0200Y    R270 S0      
317PVDD18_S5_P0     VIA   -    MD0100PA00X+131054Y+060410X0200Y    R270 S0      
317PVDD18_S5_P0     VIA   -    MD0100PA00X+131354Y+060410X0200Y    R270 S0      
317PVDD18_S5_P0     VIA   -    MD0100PA00X+131054Y+060710X0200Y    R270 S0      
317PVDD18_S5_P0     VIA   -    MD0100PA00X+131354Y+060710X0200Y    R270 S0      
317PVDD18_S5_P0     VIA   -    MD0100PA00X+131054Y+061010X0200Y    R270 S0      
317PVDD18_S5_P0     VIA   -    MD0100PA00X+131354Y+061010X0200Y    R270 S0      
317PVDD18_S5_P0     VIA   -    MD0100PA00X+131054Y+061310X0200Y    R270 S0      
317PVDD18_S5_P0     VIA   -    MD0100PA00X+131354Y+061610X0200Y    R090 S0      
317PVDD18_S5_P0     VIA   -    MD0100PA00X+131054Y+061610X0200Y    R090 S0      
327PVDD18_S5_P0     PC115 -1          A01X+131350Y+062484X0630Y1190R180 S1      
317PVDD18_S5_P0     VIA   -    MD0100PA00X+132537Y+059721X0200Y    R180 S0      
317PVDD18_S5_P0     VIA   -    MD0100PA00X+132537Y+060021X0200Y    R180 S0      
317PVDD18_S5_P0     VIA   -    MD0100PA00X+115012Y+021234X0200Y    R180 S0      
327PVDD18_S5_P0     R424  -1          A01X+115212Y+020984X0198Y0197     S1      
317PVDD18_S5_P0     VIA   -    MD0100PA00X+115012Y+020734X0200Y    R180 S0      
327PVDD18_S5_P0     R422  -1          A01X+115212Y+020484X0198Y0197     S1      
317PVDD18_S5_P0     VIA   -    MD0100PA00X+047102Y+052728X0200Y         S0      
327PVDD18_S5_P0     C1523 -1   M      A01X+090975Y+062591X0198Y0197R180 S1      
327PVDD18_S5_P0     U154  -8          A01X+091689Y+062607X0140Y0520R090 S1      
317PVDD18_S5_P0     VIA   -    MD0100PA00X+090975Y+062843X0200Y         S0      
327PVDD18_S5_P0     C1522 -1   M      A01X+090671Y+061136X0198Y0197R180 S1      
327PVDD18_S5_P0     U14   -8          A01X+091689Y+061157X0140Y0520R090 S1      
317PVDD18_S5_P0     VIA   -    MD0100PA00X+090671Y+061406X0200Y         S0      
327PVDD18_S5_P0     R495  -1   M      A01X+070264Y+062169X0198Y0197R270 S1      
327PVDD18_S5_P0     R498  -1          A01X+069864Y+062169X0198Y0197R270 S1      
317PVDD18_S5_P0     VIA   -    MD0100PA00X+070639Y+062169X0200Y         S0      
327PVDD18_S5_P0     C42   -1   M      A01X+071191Y+060643X0198Y0197R270 S1      
327PVDD18_S5_P0     U27   -1          A01X+070566Y+060606X0240Y0460     S1      
317PVDD18_S5_P0     VIA   -    MD0100PA00X+071504Y+060643X0200Y         S0      
327PVDD18_S5_P0     R1287 -2          A01X+072050Y+055344X0198Y0197R090 S1      
327PVDD18_S5_P0     R632  -1          A18X+074848Y+055458X0198Y0197R090 S2      
317PVDD18_S5_P0     VIA   -    MD0100PA00X+074848Y+055708X0200Y         S0      
317PVDD18_S5_P0     VIA   -    MD0100PA00X+075650Y+054586X0200Y         S0      
327PVDD18_S5_P0     R1567 -1          A01X+075650Y+054344X0198Y0197R270 S1      
327PVDD18_S5_P0     R633  -1          A18X+076052Y+055446X0198Y0197R090 S2      
317PVDD18_S5_P0     VIA   -    MD0100PA00X+075810Y+055687X0200Y         S0      
317PVDD18_S5_P0     VIA   -    MD0100PA00X+072443Y+053087X0200Y         S0      
317PVDD18_S5_P0     VIA   -    MD0100PA00X+084509Y+053511X0200Y         S0      
327PVDD18_S5_P0     R1649 -1          A01X+084187Y+053511X0198Y0197R090 S1      
317PVDD18_S5_P0     VIA   -    MD0100PA00X+086066Y+051596X0200Y         S0      
327PVDD18_S5_P0     R1650 -1          A01X+086406Y+051596X0198Y0197R090 S1      
317PVDD18_S5_P0     VIA   -    MD0100PA00X+082783Y+055427X0200Y         S0      
327PVDD18_S5_P0     C1521 -1   M      A01X+090553Y+059745X0198Y0197R180 S1      
327PVDD18_S5_P0     U13   -8          A01X+091689Y+059707X0140Y0520R090 S1      
317PVDD18_S5_P0     VIA   -    MD0100PA00X+090553Y+059466X0200Y         S0      
317PVDD18_S5_P0     VIA   -    MD0100PA00X+083552Y+058006X0200Y         S0      
327PVDD18_S5_P0     C1519 -1   M      A01X+090975Y+058241X0198Y0197R180 S1      
327PVDD18_S5_P0     U153  -8          A01X+091689Y+058257X0140Y0520R090 S1      
317PVDD18_S5_P0     VIA   -    MD0100PA00X+090975Y+057970X0200Y         S0      
327PVDD18_S5_P0     R1646 -1          A01X+091688Y+057071X0198Y0197     S1      
317PVDD18_S5_P0     VIA   -    MD0100PA00X+093041Y+057731X0200Y         S0      
327PVDD18_S5_P0     R1647 -1          A01X+092960Y+057070X0198Y0197R180 S1      
327PVDD18_S5_P0     U149  -16         A01X+104004Y+037601X0140Y0630R090 S1      
327PVDD18_S5_P0     U149  -15         A01X+104004Y+037857X0140Y0630R090 S1      
327PVDD18_S5_P0     U149  -2          A01X+106209Y+037857X0140Y0630R090 S1      
327PVDD18_S5_P0     U149  -1          A01X+106209Y+037601X0140Y0630R090 S1      
327PVDD18_S5_P0     U149  -8          A01X+106209Y+039392X0140Y0630R090 S1      
327PVDD18_S5_P0     U149  -7          A01X+106209Y+039136X0140Y0630R090 S1      
327PVDD18_S5_P0     C1507 -1          A01X+106924Y+039703X0198Y0197R270 S1      
317PVDD18_S5_P0     VIA   -    MD0100PA00X+107214Y+039691X0200Y         S0      
317PVDD18_S5_P0     VIA   -    MD0100PA00X+107474Y+039693X0200Y         S0      
327PVDD18_S5_P0     C1509 -1          A01X+106932Y+040097X0198Y0197R090 S1      
327PVDD18_S5_P0     U151  -16         A01X+109711Y+037547X0140Y0630R090 S1      
327PVDD18_S5_P0     U151  -2          A01X+111916Y+037803X0140Y0630R090 S1      
327PVDD18_S5_P0     U151  -1          A01X+111916Y+037547X0140Y0630R090 S1      
327PVDD18_S5_P0     C1515 -1          A01X+112433Y+039802X0198Y0197     S1      
327PVDD18_S5_P0     U151  -8          A01X+111916Y+039338X0140Y0630R090 S1      
327PVDD18_S5_P0     U151  -7          A01X+111916Y+039082X0140Y0630R090 S1      
317PVDD18_S5_P0     VIA   -    M      A01X+112163Y+040192X0200Y         S2      
017PVDD18_S5_P0     VIA   -    M      A18X+112163Y+040192X0260Y         S2      
017PVDD18_S5_P0           -    MD0100PA00X+112163Y+040192                       
317PVDD18_S5_P0     VIA   -    MD0100PA00X+112427Y+040464X0200Y         S0      
327PVDD18_S5_P0     C1508 -1   M      A01X+104682Y+040659X0198Y0197R180 S1      
327PVDD18_S5_P0     U148  -15         A01X+104042Y+041426X0140Y0630R090 S1      
317PVDD18_S5_P0     VIA   -    MD0100PA00X+104957Y+040659X0200Y         S0      
327PVDD18_S5_P0     U53   -2          A01X+103068Y+051715X0140Y0630R090 S1      
317PVDD18_S5_P0     VIA   -    MD0100PA00X+100621Y+051030X0200Y    R270 S0      
327PVDD18_S5_P0     U53   -16  M      A01X+100863Y+051459X0140Y0630R090 S1      
327PVDD18_S5_P0     C1102 -1   M      A01X+100863Y+051030X0198Y0197     S1      
327PVDD18_S5_P0     U53   -1          A01X+103068Y+051459X0140Y0630R090 S1      
327PVDD18_S5_P0     U53   -8          A01X+103068Y+053250X0140Y0630R090 S1      
327PVDD18_S5_P0     U53   -7          A01X+103068Y+052994X0140Y0630R090 S1      
327PVDD18_S5_P0     R811  -1          A01X+104283Y+051601X0198Y0197R180 S1      
317PVDD18_S5_P0     VIA   -    MD0100PA00X+104525Y+051601X0200Y    R090 S0      
327PVDD18_S5_P0     R601  -1          A01X+104283Y+052607X0198Y0197R180 S1      
317PVDD18_S5_P0     VIA   -    MD0100PA00X+104525Y+052607X0200Y    R090 S0      
327PVDD18_S5_P0     R659  -1          A01X+104283Y+053407X0198Y0197R180 S1      
317PVDD18_S5_P0     VIA   -    MD0100PA00X+104525Y+053407X0200Y    R090 S0      
327PVDD18_S5_P0     C1103 -1   M      A01X+103484Y+054135X0198Y0197R270 S1      
327PVDD18_S5_P0     U54   -1          A01X+103008Y+054350X0070Y0280R270 S1      
317PVDD18_S5_P0     VIA   -    MD0100PA00X+103730Y+053968X0200Y    R270 S0      
327PVDD18_S5_P0     R1529 -1          A01X+104483Y+054457X0198Y0197R180 S1      
317PVDD18_S5_P0     VIA   -    MD0100PA00X+104720Y+054309X0200Y    R270 S0      
327PVDD18_S5_P0     R1530 -1          A01X+104483Y+054957X0198Y0197R180 S1      
317PVDD18_S5_P0     VIA   -    MD0100PA00X+104734Y+054957X0200Y    R270 S0      
317PVDD18_S5_P0     VIA   -    MD0100PA00X+115414Y+058634X0200Y    R180 S0      
317PVDD18_S5_P0     VIA   -    MD0100PA00X+115414Y+058334X0200Y    R180 S0      
317PVDD18_S5_P0     VIA   -    MD0100PA00X+115704Y+058630X0200Y    R180 S0      
317PVDD18_S5_P0     VIA   -    MD0100PA00X+115704Y+058330X0200Y    R180 S0      
317PVDD18_S5_P0     VIA   -    MD0100PA00X+103100Y+056850X0200Y         S0      
327PVDD18_S5_P0     R1531 -1          A01X+103158Y+056600X0198Y0197R180 S1      
327PVDD18_S5_P0     U152  -10         A01X+051365Y+020969X0070Y0310R180 S1      
327PVDD18_S5_P0     C1513 -1   M      A01X+052209Y+020428X0198Y0197R090 S1      
317PVDD18_S5_P0     VIA   -    MD0100PA00X+053222Y+020785X0200Y    R270 S0      
317PVDD18_S5_P0     VIA   -    MD0100PA00X+053354Y+040413X0200Y         S0      
317PVDD18_S5_P0     VIA   -    MD0100PA00X+072220Y+057931X0200Y         S0      
317PVDD18_S5_P0     VIA   -    MD0100PA00X+103900Y+055500X0200Y         S0      
327PVDD18_S5_P0     R1532 -1          A01X+103900Y+055742X0198Y0197R090 S1      
317PVDD18_S5_P0     VIA   -    M      A01X+072050Y+055586X0200Y         S2      
017PVDD18_S5_P0     VIA   -    M      A18X+072050Y+055586X0260Y         S2      
017PVDD18_S5_P0           -    MD0100PA00X+072050Y+055586                       
317PVDD18_S5_P0     VIA   -    MD0100PA00X+168492Y+012376X0200Y    R090 S0      
327PVDD18_S5_P0     R6106 -1          A18X+168735Y+012276X0198Y0197R180 S2      
317PVDD18_S5_P0     VIA   -    MD0100PA00X+168492Y+014576X0200Y    R090 S0      
327PVDD18_S5_P0     R6107 -1          A18X+168735Y+014576X0198Y0197R180 S2      
317PVDD18_S5_P0     VIA   -    MD0100PA00X+157255Y+025749X0200Y         S0      
317PVDD18_S5_P0     VIA   -    MD0100PA00X+157250Y+025425X0200Y         S0      
327PVDD18_S5_P0     J54   -19         A01X+156420Y+025425X0340Y0960R090 S1      
317PVDD18_S5_P0     VIA   -    MD0100PA00X+153316Y+023125X0200Y         S0      
327PVDD18_S5_P0     R1628 -1          A01X+152209Y+023125X0198Y0197R180 S1      
317PVDD18_S5_P0     VIA   -    MD0100PA00X+152739Y+023802X0200Y         S0      
327PVDD18_S5_P0     R1630 -1          A01X+152209Y+023802X0198Y0197R180 S1      
317PVDD18_S5_P0     VIA   -    MD0100PA00X+153745Y+022629X0200Y         S0      
327PVDD18_S5_P0     R1627 -1          A01X+152209Y+022525X0198Y0197R180 S1      
317PVDD18_S5_P0     VIA   -    MD0100PA00X+151771Y+021650X0200Y         S0      
327PVDD18_S5_P0     R1626 -1          A01X+151364Y+021640X0198Y0197R270 S1      
317PVDD18_S5_P0     VIA   -    MD0100PA00X+155436Y+020725X0200Y         S0      
327PVDD18_S5_P0     J54   -1          A01X+156420Y+020925X0340Y0960R090 S1      
327PVDD18_S5_P0     R816  -1          A01X+144977Y+017979X0198Y0197R270 S1      
317PVDD18_S5_P0     VIA   -    MD0100PA00X+144977Y+018222X0200Y    R180 S0      
327PVDD18_S5_P0     R813  -1          A01X+143977Y+017979X0198Y0197R270 S1      
317PVDD18_S5_P0     VIA   -    MD0100PA00X+143977Y+018222X0200Y    R180 S0      
327PVDD18_S5_P0     R815  -1          A01X+145477Y+017179X0198Y0197R270 S1      
317PVDD18_S5_P0     VIA   -    MD0100PA00X+145397Y+017441X0200Y    R180 S0      
327PVDD18_S5_P0     R814  -1          A01X+144477Y+017179X0198Y0197R270 S1      
317PVDD18_S5_P0     VIA   -    MD0100PA00X+144477Y+017422X0200Y    R180 S0      
327PVDD18_S5_P0     U116  -1          A01X+145623Y+015687X0140Y0630R180 S1      
317PVDD18_S5_P0     VIA   -    MD0100PA00X+145623Y+015217X0200Y    R180 S0      
327PVDD18_S5_P0     U116  -7          A01X+144087Y+015687X0140Y0630R180 S1      
317PVDD18_S5_P0     VIA   -    MD0100PA00X+144087Y+015217X0200Y    R180 S0      
327PVDD18_S5_P0     R1419 -1          A01X+142917Y+010974X0198Y0197R090 S1      
317PVDD18_S5_P0     VIA   -    MD0100PA00X+142917Y+010731X0200Y    R180 S0      
317PVDD18_S5_P0     VIA   -    MD0100PA00X+146302Y+013952X0200Y    R090 S0      
327PVDD18_S5_P0     U116  -16         A01X+145623Y+013482X0140Y0630R180 S1      
327PVDD18_S5_P0     C1352 -1   M      A01X+146051Y+013952X0198Y0197R270 S1      
317PVDD18_S5_P0     VIA   -    MD0100PA00X+159646Y+022979X0200Y    R090 S0      
327PVDD18_S5_P0     R1621 -1          A01X+159088Y+022925X0198Y0197R180 S1      
327PVDD18_S5_P0     U101  -5          A18X+158760Y+135925X0220Y0530R090 S2      
327PVDD18_S5_P0     C226  -1   M      A18X+158092Y+135925X0198Y0197R090 S2      
317PVDD18_S5_P0     VIA   -    MD0100PA00X+157834Y+135925X0200Y         S0      
317PVDD18_S5_P0     VIA   -    MD0100PA00X+158656Y+130451X0200Y         S0      
327PVDD18_S5_P0     R451  -2          A18X+159285Y+130098X0198Y0197R090 S2      
317PVDD18_S5_P0     VIA   -    MD0100PA00X+160536Y+129460X0200Y    R180 S0      
327PVDD18_S5_P0     R444  -2          A18X+160275Y+129899X0198Y0197R180 S2      
327PVDD18_S5_P0     R445  -2   M      A18X+160275Y+129499X0198Y0197R180 S2      
327PVDD18_S5_P0     R288  -2          A18X+160275Y+129099X0198Y0197R180 S2      
317PVDD18_S5_P0     VIA   -    MD0100PA00X+160890Y+128589X0200Y    R180 S0      
327PVDD18_S5_P0     R455  -1   M      A18X+160275Y+127899X0198Y0197     S2      
327PVDD18_S5_P0     R458  -1          A18X+160275Y+127499X0198Y0197     S2      
317PVDD18_S5_P0     VIA   -    MD0100PA00X+159100Y+128889X0200Y    R180 S0      
327PVDD18_S5_P0     R737  -1          A18X+159205Y+129129X0198Y0197     S2      
317PVDD18_S5_P0     VIA   -    MD0100PA00X+158001Y+129610X0200Y    R180 S0      
327PVDD18_S5_P0     R457  -1   M      A18X+157958Y+129957X0198Y0197     S2      
327PVDD18_S5_P0     R938  -2          A01X+158170Y+129828X0198Y0197R180 S1      
317PVDD18_S5_P0     VIA   -    MD0100PA00X+156810Y+129042X0200Y    R180 S0      
327PVDD18_S5_P0     R1506 -1          A18X+156375Y+128411X0198Y0197     S2      
327PVDD18_S5_P0     R1351 -2   M      A18X+156278Y+129042X0198Y0197R180 S2      
317PVDD18_S5_P0     VIA   -    MD0100PA00X+159415Y+128258X0200Y    R180 S0      
327PVDD18_S5_P0     R743  -1          A01X+159175Y+127899X0198Y0197R180 S1      
317PVDD18_S5_P0     VIA   -    MD0100PA00X+157869Y+128331X0200Y    R180 S0      
327PVDD18_S5_P0     R742  -1          A18X+157721Y+128609X0198Y0197     S2      
327PVDD18_S5_P0     R448  -2   M      A01X+159118Y+126536X0198Y0197R090 S1      
327PVDD18_S5_P0     R276  -2          A01X+158318Y+126536X0198Y0197R090 S1      
327PVDD18_S5_P0     R449  -2   M      A01X+158718Y+126536X0198Y0197R090 S1      
317PVDD18_S5_P0     VIA   -    MD0100PA00X+158883Y+126908X0200Y    R180 S0      
327PVDD18_S5_P0     R446  -2   M      A18X+158552Y+126449X0198Y0197R180 S2      
327PVDD18_S5_P0     R447  -2          A18X+158552Y+126059X0198Y0197R180 S2      
317PVDD18_S5_P0     VIA   -    MD0100PA00X+155756Y+126910X0200Y    R180 S0      
327PVDD18_S5_P0     R437  -1   M      A01X+155025Y+127419X0198Y0197R180 S1      
327PVDD18_S5_P0     R450  -2          A01X+155025Y+127819X0198Y0197     S1      
327PVDD18_S5_P0     R1504 -1          A01X+156191Y+127344X0198Y0197     S1      
327PVDD18_S5_P0     R1503 -1   M      A01X+155808Y+127321X0198Y0197R090 S1      
327PVDD18_S5_P0     R1505 -1   M      A01X+155438Y+127321X0198Y0197R090 S1      
327PVDD18_S5_P0     R581  -2          A01X+155618Y+126594X0198Y0197R090 S1      
327PVDD18_S5_P0     R417  -2   M      A01X+156016Y+126594X0198Y0197R090 S1      
327PVDD18_S5_P0     R739  -1          A18X+155133Y+126849X0198Y0197     S2      
317PVDD18_S5_P0     VIA   -    MD0100PA00X+154377Y+124102X0200Y         S0      
317PVDD18_S5_P0     VIA   -    MD0100PA00X+163193Y+126092X0200Y    R180 S0      
317PVDD18_S5_P0     VIA   -    MD0100PA00X+162943Y+126092X0200Y    R180 S0      
317PVDD18_S5_P0     VIA   -    MD0100PA00X+162693Y+126092X0200Y    R180 S0      
317PVDD18_S5_P0     VIA   -    MD0100PA00X+163443Y+126092X0200Y    R180 S0      
317PVDD18_S5_P0     VIA   -    MD0100PA00X+169297Y+055312X0200Y    R180 S0      
317PVDD18_S5_P0     VIA   -    MD0100PA00X+169697Y+055312X0200Y    R180 S0      
317PVDD18_S5_P0     VIA   -    MD0100PA00X+170097Y+055312X0200Y    R180 S0      
317PVDD18_S5_P0     VIA   -    MD0100PA00X+170497Y+055312X0200Y    R180 S0      
317PVDD18_S5_P0     VIA   -    MD0100PA00X+157557Y+049785X0200Y    R180 S0      
317PVDD18_S5_P0     VIA   -    MD0100PA00X+157057Y+049785X0200Y    R180 S0      
317PVDD18_S5_P0     VIA   -    MD0100PA00X+157307Y+049785X0200Y    R180 S0      
317PVDD18_S5_P0     VIA   -    MD0100PA00X+156807Y+049785X0200Y    R180 S0      
327PVDD18_S5_P0     R6121 -1   M      A18X+159072Y+137329X0198Y0197R270 S2      
327PVDD18_S5_P0     R6122 -1   M      A18X+159544Y+137321X0198Y0197R270 S2      
327PVDD18_S5_P0     R6124 -1          A18X+158118Y+137330X0198Y0197R270 S2      
327PVDD18_S5_P0     R6123 -1   M      A18X+158600Y+137330X0198Y0197R270 S2      
317PVDD18_S5_P0     VIA   -    MD0100PA00X+159544Y+137060X0200Y         S0      
317PVDD18_S5_P0     VIA   -    MD0100PA00X+160565Y+143730X0200Y         S0      
317PVDD18_S5_P0     VIA   -    MD0100PA00X+162722Y+142837X0200Y    R270 S0      
327PVDD18_S5_P0     PR128 -2          A01X+162963Y+142837X0198Y0197R180 S1      
327PVDD18_S5_P0     R6120 -1          A18X+159966Y+137327X0198Y0197R270 S2      
327PVDD18_S5_P0     R441  -2          A18X+157920Y+130299X0198Y0197R090 S2      
317PVDD18_S5_P0     VIA   -    MD0100PA00X+156294Y+134161X0200Y         S0      
327PVDD18_S5_P0     R942  -1          A18X+156550Y+134161X0198Y0197R270 S2      
327PVDD18_S5_P0     R207  -2          A18X+135575Y+120799X0198Y0197R180 S2      
317PVDD18_S5_P0     VIA   -    MD0100PA00X+135564Y+121067X0200Y         S0      
327PVDD18_S5_P0     R124  -1          A01X+166938Y+141668X0198Y0197R180 S1      
317PVDD18_S5_P0     VIA   -    MD0100PA00X+167250Y+141668X0200Y         S0      
327PVDD18_S5_P0     R392  -1          A18X+133398Y+121895X0198Y0197R090 S2      
317PVDD18_S5_P0     VIA   -    MD0100PA00X+133398Y+122216X0200Y    R090 S0      
317PVDD18_S5_P0     VIA   -    MD0100PA00X+133120Y+120648X0200Y         S0      
327PVDD18_S5_P0     R729  -1          A18X+133360Y+120799X0198Y0197R180 S2      
327m3979            PU45  -1          A01X+074349Y+139211X0090Y0240R090 S1      
317m3979            VIA   -    MD0100PA00X+074221Y+139452X0200Y         S0      
327m3979            PR333 -1          A18X+073852Y+139207X0198Y0197R270 S2      
327m3980            PU44  -1          A01X+071071Y+139201X0090Y0240R090 S1      
317m3980            VIA   -    MD0100PA00X+070943Y+139442X0200Y         S0      
327m3980            PR332 -1          A18X+070574Y+139197X0198Y0197R270 S2      
327m3981            PR6   -1          A18X+064853Y+137491X0198Y0197     S2      
327m3981            PR376 -2          A18X+065959Y+137684X0198Y0197     S2      
317m3981            VIA   -    MD0100PA00X+065265Y+137531X0200Y         S2      
327m3981            PU54  -37         A01X+064814Y+137462X0070Y0240R270 S1      
327m3981            PC638 -1          A01X+065563Y+137506X0198Y0197     S1      
327m3982            VIA   -    M      A18X+065499Y+138084X0260Y    R180 S2      
327m3982            PR604 -1          A18X+064853Y+138095X0198Y0197     S2      
327m3982            PR388 -2          A18X+065959Y+138084X0198Y0197     S2      
317m3982            VIA   -    MD0100PA00X+065312Y+137804X0200Y         S0      
327m3982            PU54  -38         A01X+064814Y+137619X0070Y0240R270 S1      
327m3982            PC8   -1          A01X+065559Y+137893X0198Y0197     S1      
327m3983            VIA   -    M      A01X+062243Y+136237X0300Y    R180 S1      
327m3983            PU54  -15         A01X+062925Y+137304X0070Y0240R270 S1      
327m3983            R8146 -2          A01X+062243Y+136717X0198Y0197     S1      
327m3984            PC504_-1   M      A01X+074233Y+140070X0198Y0197R090 S1      
327m3984            PU45  -39         A01X+074510Y+139457X0090Y0240     S1      
317m3984            VIA   -    MD0100PA00X+074520Y+140070X0200Y         S2      
317m3984            VIA   -    MD0100PA00X+071242Y+140060X0200Y    R180 S0      
327m3984            PU44  -39         A01X+071232Y+139447X0090Y0240     S1      
327m3984            PC503_-1   M      A01X+070955Y+140060X0198Y0197R090 S1      
317m3984            VIA   -    MD0100PA00X+064740Y+138416X0200Y    R180 S0      
327m3984            PU54  -40         A01X+064814Y+137934X0070Y0240R270 S1      
327m3984            PC96  -1          A01X+064356Y+138682X0198Y0197R090 S1      
327m3984            PC644 -1          A01X+064744Y+138685X0198Y0197R090 S1      
327m3985            PC506 -1          A01X+073844Y+139207X0198Y0197R090 S1      
327m3985            PU45  -3          A01X+074349Y+138857X0090Y0240R090 S1      
317m3985            VIA   -    MD0100PA00X+073844Y+138967X0200Y         S0      
327m3985            VIA   -    M      A18X+074563Y+139447X0260Y    R180 S2      
317m3985            VIA   -    MD0100PA00X+075189Y+139767X0200Y         S0      
327m3985            PR327 -2   M      A18X+074384Y+138890X0198Y0197R270 S2      
327m3985            PU45  -35         A01X+075219Y+139457X0090Y0240     S1      
327m3986            PC505 -1          A01X+070566Y+139197X0198Y0197R090 S1      
327m3986            PU44  -3          A01X+071071Y+138847X0090Y0240R090 S1      
317m3986            VIA   -    MD0100PA00X+070566Y+138957X0200Y         S0      
327m3986            VIA   -    M      A18X+071302Y+139336X0260Y    R180 S2      
317m3986            VIA   -    MD0100PA00X+071911Y+139757X0200Y         S0      
327m3986            PR326 -2   M      A18X+071106Y+138880X0198Y0197R270 S2      
327m3986            PU44  -35         A01X+071941Y+139447X0090Y0240     S1      
327m3987            PC95  -1          A01X+065570Y+138535X0198Y0197R090 S1      
327m3987            VIA   -           A01X+066322Y+138787X0300Y    R180 S1      
327m3987            PC645 -1   M      A01X+065956Y+138529X0198Y0197R090 S1      
327m3987            PR393 -1          A01X+065188Y+138532X0198Y0197R090 S1      
327m3987            PU54  -39         A01X+064814Y+137777X0070Y0240R270 S1      
317m3988            VIA   -    MD0100PA00X+065310Y+136986X0200Y    R180 S2      
327m3988            PR415 -1          A18X+064853Y+137079X0198Y0197     S2      
327m3988            PU54  -35         A01X+064814Y+137147X0070Y0240R270 S1      
327m3989            PC643 -1          A01X+065566Y+137120X0198Y0197     S1      
327m3989            PU54  -36         A01X+064814Y+137304X0070Y0240R270 S1      
317m3989            VIA   -    MD0100PA00X+065315Y+137250X0200Y         S0      
327m3989            PU44  -36         A01X+071764Y+139447X0090Y0240     S1      
317m3989            VIA   -    MD0100PA00X+071637Y+139854X0200Y         S2      
327m3989            PU45  -36         A01X+075042Y+139457X0090Y0240     S1      
317m3989            VIA   -    MD0100PA00X+074916Y+139864X0200Y         S0      
327m3990            PR392 -1          A01X+062239Y+137118X0198Y0197R180 S1      
327m3990            PU54  -14         A01X+062925Y+137462X0070Y0240R270 S1      
327m3990            PR391 -1          A01X+062239Y+137508X0198Y0197R180 S1      
317m3990            VIA   -    M      A01X+062480Y+137326X0200Y    R180 S2      
017m3990            VIA   -    M      A18X+062480Y+137326X0260Y    R180 S2      
017m3990                  -    MD0100PA00X+062480Y+137326                       
327m3990            PR390 -1          A18X+062806Y+136875X0198Y0197R180 S2      
317m3991            VIA   -    MD0100PA00X+075331Y+065552X0200Y         S0      
327m3991            U18   -H16        A01X+071938Y+046714X0160Y    R090 S1      
317m3991            VIA   -    MD0100PA00X+071784Y+046867X0180Y    R090 S0      
317m3991            VIA   -    MD0100PA00X+073338Y+063357X0200Y         S0      
317m3991            VIA   -    MD0100PA00X+082279Y+079501X0200Y         S0      
327m3991            PR392 -2          A01X+061924Y+137118X0198Y0197R180 S1      
317m3991            VIA   -    M      A01X+060815Y+137389X0200Y         S2      
017m3991            VIA   -    M      A18X+060815Y+137389X0260Y         S2      
017m3991                  -    MD0100PA00X+060815Y+137389                       
317m3991            VIA   -    MD0100PA00X+068545Y+142314X0200Y         S0      
327m3992            PU45  -34         A01X+075396Y+139457X0090Y0240     S1      
317m3992            VIA   -    MD0100PA00X+075264Y+140024X0200Y         S0      
327m3992            PU54  -7          A01X+063633Y+138171X0070Y0240R180 S1      
317m3992            VIA   -    MD0100PA00X+063805Y+138449X0200Y         S2      
327m3993            PU54  -8          A01X+063476Y+138171X0070Y0240R180 S1      
317m3993            VIA   -    MD0100PA00X+063500Y+138446X0200Y    R180 S0      
327m3993            PU44  -34         A01X+072118Y+139447X0090Y0240     S1      
317m3993            VIA   -    MD0100PA00X+071986Y+140014X0200Y         S0      
327m3994            PR394 -1          A01X+070166Y+139199X0198Y0197R090 S1      
327m3994            PR387 -1          A01X+069773Y+139196X0198Y0197R090 S1      
327m3994            PC507_-1   M      A01X+070566Y+138462X0198Y0197R270 S1      
327m3994            PU44  -4          A01X+071071Y+138670X0090Y0240R090 S1      
327m3994            VIA   -           A01X+069839Y+138523X0300Y    R180 S1      
327m3994            PC508_-1   M      A01X+073844Y+138472X0198Y0197R270 S1      
327m3994            PU45  -4          A01X+074349Y+138680X0090Y0240R090 S1      
317m3994            VIA   -    MD0100PA00X+073844Y+138713X0200Y         S0      
327m3994            PR327 -1          A18X+074384Y+138575X0198Y0197R270 S2      
317m3994            VIA   -    MD0100PA00X+070566Y+138703X0200Y         S0      
327m3994            PR326 -1          A18X+071106Y+138565X0198Y0197R270 S2      
327m3995            VIA   -           A01X+063885Y+138989X0300Y    R180 S1      
327m3995            R8382 -2   M      A01X+063410Y+138688X0198Y0197R270 S1      
327m3995            PU54  -9          A01X+063318Y+138171X0070Y0240R180 S1      
317m3996            VIA   -    M      A01X+063020Y+138426X0200Y    R180 S2      
017m3996            VIA   -    M      A18X+063020Y+138426X0260Y    R180 S2      
017m3996                  -    MD0100PA00X+063020Y+138426                       
327m3996            PU54  -10         A01X+063161Y+138171X0070Y0240R180 S1      
327m3996            R8381 -2          A01X+063020Y+138688X0198Y0197R270 S1      
327m3997            VIA   -           A01X+062819Y+139560X0300Y    R180 S1      
327m3997            PU54  -11         A01X+062925Y+137934X0070Y0240R270 S1      
327m3997            R8383 -2   M      A01X+062630Y+138688X0198Y0197R270 S1      
317m3998            VIA   -    MD0100PA00X+087541Y+079735X0200Y         S0      
327m3998            U18   -N1         A01X+073513Y+041989X0160Y    R090 S1      
327m3998            R1190 -1          A01X+073150Y+039644X0198Y0197R270 S1      
317m3998            VIA   -    MD0100PA00X+073121Y+039874X0180Y    R090 S0      
317m3998            VIA   -    MD0100PA00X+087006Y+042770X0200Y         S0      
317m3998            VIA   -    M      A01X+062235Y+139328X0200Y         S2      
017m3998            VIA   -    M      A18X+062235Y+139328X0260Y         S2      
017m3998                  -    MD0100PA00X+062235Y+139328                       
327m3998            R8383 -1          A01X+062630Y+139003X0198Y0197R270 S1      
327m3998            C5010 -1   M      A01X+062235Y+139073X0198Y0197R180 S1      
317m3998            VIA   -    MD0100PA00X+071426Y+144748X0200Y         S0      
327m3999            VIA   -    M      A18X+065792Y+136216X0260Y    R180 S2      
327m3999            R8011 -2          A18X+065860Y+136693X0198Y0197R090 S2      
317m3999            VIA   -    MD0100PA00X+065197Y+136304X0200Y    R180 S0      
327m3999            PU54  -33         A01X+064814Y+136832X0070Y0240R270 S1      
327m3999            R8010 -2          A01X+065565Y+136339X0198Y0197R180 S1      
317m4000            VIA   -    MD0100PA00X+082279Y+080001X0200Y         S0      
317m4000            VIA   -    M      A01X+064008Y+049796X0200Y         S2      
017m4000            VIA   -    M      A18X+064008Y+049796X0260Y         S2      
017m4000                  -    MD0100PA00X+064008Y+049796                       
327m4000            R278  -2          A18X+071150Y+039329X0198Y0197R090 S2      
317m4000            VIA   -    MD0100PA00X+071150Y+038686X0200Y    R090 S0      
317m4000            VIA   -    MD0100PA00X+073084Y+067894X0200Y         S0      
327m4000            R8010 -1          A01X+065880Y+136339X0198Y0197R180 S1      
317m4000            VIA   -    MD0100PA00X+066172Y+136339X0200Y         S0      
327m4001            VIA   -    M      A01X+074718Y+139960X0160Y0041R270 S1      
327m4001            PU45  -37         A01X+074865Y+139457X0090Y0240     S1      
327m4001            PR329 -2          A01X+074623Y+140367X0198Y0197R180 S1      
327m4002            VIA   -    M      A01X+071440Y+139950X0160Y0041R270 S1      
327m4002            PR328 -2          A01X+071345Y+140357X0198Y0197R180 S1      
327m4002            PU44  -37         A01X+071587Y+139447X0090Y0240     S1      
327m4003            PU45  -38         A01X+074688Y+139457X0090Y0240     S1      
317m4003            VIA   -    MD0100PA00X+074520Y+139819X0200Y         S0      
327m4003            PU54  -24         A01X+063633Y+136281X0070Y0240R180 S1      
317m4003            VIA   -    M      A01X+063478Y+135374X0200Y    R180 S2      
017m4003            VIA   -    M      A18X+063478Y+135374X0260Y    R180 S2      
017m4003                  -    MD0100PA00X+063478Y+135374                       
327m4004            PU44  -38         A01X+071409Y+139447X0090Y0240     S1      
317m4004            VIA   -    MD0100PA00X+071242Y+139809X0200Y         S0      
327m4004            PU54  -23         A01X+063476Y+136281X0070Y0240R180 S1      
317m4004            VIA   -    M      A01X+063341Y+135858X0200Y    R180 S2      
017m4004            VIA   -    M      A18X+063341Y+135858X0260Y    R180 S2      
017m4004                  -    MD0100PA00X+063341Y+135858                       
327m4005            PU54  -13         A01X+062925Y+137619X0070Y0240R270 S1      
327m4005            C642  -1          A01X+062241Y+137896X0198Y0197R180 S1      
317m4005            VIA   -    M      A01X+062498Y+137831X0200Y    R180 S2      
017m4005            VIA   -    M      A18X+062498Y+137831X0260Y    R180 S2      
017m4005                  -    MD0100PA00X+062498Y+137831                       
327m4005            R8386 -2          A18X+061979Y+137909X0198Y0197R180 S2      
317m4006            VIA   -    MD0100PA00X+078181Y+034186X0200Y         S0      
327m4006            R279  -1          A01X+077823Y+042734X0198Y0197R180 S1      
317m4006            VIA   -    MD0100PA00X+078088Y+042734X0200Y    R180 S0      
317m4006            VIA   -    MD0100PA00X+068339Y+142053X0200Y         S0      
327m4006            R8386 -1          A18X+061664Y+137909X0198Y0197R180 S2      
327m4006            VIA   -    M      A18X+061204Y+137909X0260Y    R180 S2      
317m4007            VIA   -    M      A01X+065338Y+136579X0200Y    R180 S2      
017m4007            VIA   -    M      A18X+065338Y+136579X0260Y    R180 S2      
017m4007                  -    MD0100PA00X+065338Y+136579                       
327m4007            PU54  -34         A01X+064814Y+136990X0070Y0240R270 S1      
327m4007            PR464 -2          A01X+065568Y+136728X0198Y0197R180 S1      
317PVDD11_S3_P1     VIA   -    MD0080PA00X+040426Y+105038X0160Y         S0      
317PVDD11_S3_P1     VIA   -    MD0080PA00X+040611Y+104719X0160Y         S0      
317PVDD11_S3_P1     VIA   -    MD0080PA00X+039870Y+104719X0160Y         S0      
317PVDD11_S3_P1     VIA   -    MD0080PA00X+039870Y+104081X0160Y         S0      
317PVDD11_S3_P1     VIA   -    MD0080PA00X+040426Y+104400X0160Y         S0      
317PVDD11_S3_P1     VIA   -    MD0080PA00X+040610Y+104082X0160Y         S0      
317PVDD11_S3_P1     VIA   -    MD0080PA00X+041906Y+105038X0160Y         S0      
317PVDD11_S3_P1     VIA   -    MD0080PA00X+042091Y+104719X0160Y         S0      
317PVDD11_S3_P1     VIA   -    MD0080PA00X+041351Y+104719X0160Y         S0      
317PVDD11_S3_P1     VIA   -    MD0080PA00X+042090Y+104082X0160Y         S0      
317PVDD11_S3_P1     VIA   -    MD0080PA00X+041350Y+104082X0160Y         S0      
317PVDD11_S3_P1     VIA   -    MD0080PA00X+043386Y+105038X0160Y         S0      
317PVDD11_S3_P1     VIA   -    MD0080PA00X+043571Y+104719X0160Y         S0      
317PVDD11_S3_P1     VIA   -    MD0080PA00X+042831Y+104719X0160Y         S0      
317PVDD11_S3_P1     VIA   -    MD0080PA00X+042830Y+104082X0160Y         S0      
317PVDD11_S3_P1     VIA   -    MD0080PA00X+045049Y+104719X0160Y         S0      
317PVDD11_S3_P1     VIA   -    MD0080PA00X+045974Y+105038X0160Y         S0      
317PVDD11_S3_P1     VIA   -    MD0080PA00X+046529Y+104719X0160Y         S0      
317PVDD11_S3_P1     VIA   -    MD0080PA00X+045789Y+104719X0160Y         S0      
317PVDD11_S3_P1     VIA   -    MD0080PA00X+046531Y+104082X0160Y         S0      
317PVDD11_S3_P1     VIA   -    MD0080PA00X+045790Y+104082X0160Y         S0      
317PVDD11_S3_P1     VIA   -    MD0080PA00X+047455Y+105038X0160Y         S0      
317PVDD11_S3_P1     VIA   -    MD0080PA00X+048010Y+104719X0160Y         S0      
317PVDD11_S3_P1     VIA   -    MD0080PA00X+047270Y+104719X0160Y         S0      
317PVDD11_S3_P1     VIA   -    MD0080PA00X+048010Y+104081X0160Y         S0      
317PVDD11_S3_P1     VIA   -    MD0080PA00X+048195Y+103762X0160Y         S0      
317PVDD11_S3_P1     VIA   -    MD0080PA00X+048195Y+104400X0160Y         S0      
317PVDD11_S3_P1     VIA   -    MD0080PA00X+047271Y+104082X0160Y         S0      
317PVDD11_S3_P1     VIA   -    MD0080PA00X+048935Y+105038X0160Y         S0      
317PVDD11_S3_P1     VIA   -    MD0080PA00X+048750Y+104719X0160Y         S0      
317PVDD11_S3_P1     VIA   -    MD0080PA00X+049490Y+104719X0160Y         S0      
317PVDD11_S3_P1     VIA   -    MD0080PA00X+049675Y+103762X0160Y         S0      
317PVDD11_S3_P1     VIA   -    MD0080PA00X+049675Y+104400X0160Y         S0      
317PVDD11_S3_P1     VIA   -    MD0080PA00X+048935Y+103762X0160Y         S0      
317PVDD11_S3_P1     VIA   -    MD0080PA00X+048750Y+104081X0160Y         S0      
317PVDD11_S3_P1     VIA   -    MD0080PA00X+048935Y+104400X0160Y         S0      
317PVDD11_S3_P1     VIA   -    MD0080PA00X+049490Y+104081X0160Y         S0      
317PVDD11_S3_P1     VIA   -    MD0080PA00X+050230Y+104081X0160Y         S0      
317PVDD11_S3_P1     VIA   -    MD0080PA00X+050230Y+106632X0160Y         S0      
317PVDD11_S3_P1     VIA   -    MD0080PA00X+051340Y+106632X0160Y         S0      
317PVDD11_S3_P1     VIA   -    MD0080PA00X+051340Y+104719X0160Y         S0      
317PVDD11_S3_P1     VIA   -    MD0080PA00X+050230Y+105357X0160Y         S0      
317PVDD11_S3_P1     VIA   -    MD0080PA00X+050230Y+104719X0160Y         S0      
317PVDD11_S3_P1     VIA   -    MD0080PA00X+050230Y+107908X0160Y         S0      
317PVDD11_S3_P1     VIA   -    MD0080PA00X+051340Y+108546X0160Y         S0      
317PVDD11_S3_P1     VIA   -    MD0080PA00X+050045Y+110140X0160Y         S0      
317PVDD11_S3_P1     VIA   -    MD0080PA00X+050230Y+109184X0160Y         S0      
317PVDD11_S3_P1     VIA   -    MD0080PA00X+051340Y+110459X0160Y         S0      
317PVDD11_S3_P1     VIA   -    MD0080PA00X+050230Y+112373X0160Y         S0      
317PVDD11_S3_P1     VIA   -    MD0080PA00X+051340Y+112373X0160Y         S0      
317PVDD11_S3_P1     VIA   -    MD0080PA00X+050230Y+111097X0160Y         S0      
317PVDD11_S3_P1     VIA   -    MD0080PA00X+050230Y+113648X0160Y         S0      
317PVDD11_S3_P1     VIA   -    MD0080PA00X+051340Y+114286X0160Y         S0      
317PVDD11_S3_P1     VIA   -    MD0080PA00X+051526Y+103762X0160Y         S0      
317PVDD11_S3_P1     VIA   -    MD0080PA00X+051526Y+105676X0160Y         S0      
317PVDD11_S3_P1     VIA   -    MD0080PA00X+051526Y+107589X0160Y         S0      
317PVDD11_S3_P1     VIA   -    MD0080PA00X+051526Y+111416X0160Y         S0      
317PVDD11_S3_P1     VIA   -    MD0080PA00X+051526Y+109502X0160Y         S0      
317PVDD11_S3_P1     VIA   -    MD0080PA00X+051526Y+113329X0160Y         S0      
317PVDD11_S3_P1     VIA   -    MD0080PA00X+051526Y+115243X0160Y         S0      
317PVDD11_S3_P1     VIA   -    MD0080PA00X+053931Y+106632X0160Y         S0      
317PVDD11_S3_P1     VIA   -    MD0080PA00X+053931Y+104719X0160Y         S0      
317PVDD11_S3_P1     VIA   -    MD0080PA00X+054116Y+105676X0160Y         S0      
317PVDD11_S3_P1     VIA   -    MD0080PA00X+053931Y+110459X0160Y         S0      
317PVDD11_S3_P1     VIA   -    MD0080PA00X+054116Y+109502X0160Y         S0      
317PVDD11_S3_P1     VIA   -    MD0080PA00X+054116Y+107589X0160Y         S0      
317PVDD11_S3_P1     VIA   -    MD0080PA00X+053931Y+108546X0160Y         S0      
317PVDD11_S3_P1     VIA   -    MD0080PA00X+054116Y+113329X0160Y         S0      
317PVDD11_S3_P1     VIA   -    MD0080PA00X+053931Y+112373X0160Y         S0      
317PVDD11_S3_P1     VIA   -    MD0080PA00X+054116Y+111416X0160Y         S0      
317PVDD11_S3_P1     VIA   -    MD0080PA00X+054116Y+115243X0160Y         S0      
317PVDD11_S3_P1     VIA   -    MD0080PA00X+053931Y+114286X0160Y         S0      
317PVDD11_S3_P1     VIA   -    MD0080PA00X+056707Y+107589X0160Y         S0      
317PVDD11_S3_P1     VIA   -    MD0080PA00X+056522Y+108546X0160Y         S0      
317PVDD11_S3_P1     VIA   -    MD0080PA00X+056522Y+106632X0160Y         S0      
317PVDD11_S3_P1     VIA   -    MD0080PA00X+056707Y+105676X0160Y         S0      
317PVDD11_S3_P1     VIA   -    MD0080PA00X+056522Y+112373X0160Y         S0      
317PVDD11_S3_P1     VIA   -    MD0080PA00X+056707Y+113329X0160Y         S0      
317PVDD11_S3_P1     VIA   -    MD0080PA00X+056707Y+111416X0160Y         S0      
317PVDD11_S3_P1     VIA   -    MD0080PA00X+056707Y+109502X0160Y         S0      
317PVDD11_S3_P1     VIA   -    MD0080PA00X+056522Y+110459X0160Y         S0      
317PVDD11_S3_P1     VIA   -    MD0080PA00X+056707Y+115243X0160Y         S0      
317PVDD11_S3_P1     VIA   -    MD0080PA00X+056336Y+115880X0160Y         S0      
317PVDD11_S3_P1     VIA   -    MD0080PA00X+056522Y+114286X0160Y         S0      
327PVDD11_S3_P1     C2113 -1          A01X+043889Y+103208X0198Y0197R270 S1      
327PVDD11_S3_P1     C2114 -1   M      A18X+047973Y+104077X0198Y0197     S2      
327PVDD11_S3_P1     C2115 -1   M      A18X+040623Y+104727X0198Y0197     S2      
327PVDD11_S3_P1     C2118 -1   M      A18X+045773Y+104727X0198Y0197     S2      
327PVDD11_S3_P1     C2119 -1   M      A18X+047273Y+104077X0198Y0197     S2      
327PVDD11_S3_P1     C2120 -1   M      A18X+049423Y+104077X0198Y0197     S2      
327PVDD11_S3_P1     C2121 -1          A01X+043141Y+103208X0198Y0197R270 S1      
327PVDD11_S3_P1     C2124 -1   M      A18X+043515Y+103208X0198Y0197R090 S2      
327PVDD11_S3_P1     C2125 -1   M      A18X+043141Y+103208X0198Y0197R090 S2      
327PVDD11_S3_P1     C2126 -1   M      A18X+049473Y+104727X0198Y0197     S2      
327PVDD11_S3_P1     C2128 -1   M      A18X+046523Y+104077X0198Y0197     S2      
327PVDD11_S3_P1     C2261 -1   M      A18X+041323Y+104727X0198Y0197     S2      
327PVDD11_S3_P1     C2262 -1          A01X+042393Y+103208X0198Y0197R270 S1      
327PVDD11_S3_P1     C2266 -1          A01X+043487Y+102301X0198Y0197     S1      
327PVDD11_S3_P1     C2267 -1          A01X+045396Y+102301X0198Y0197     S1      
327PVDD11_S3_P1     C2271 -1   M      A18X+045759Y+103208X0198Y0197R090 S2      
327PVDD11_S3_P1     C2275 -1   M      A18X+045023Y+104727X0198Y0197     S2      
327PVDD11_S3_P1     C2279 -1          A01X+044372Y+102301X0198Y0197     S1      
327PVDD11_S3_P1     C2282 -1          A01X+044637Y+103208X0198Y0197R270 S1      
327PVDD11_S3_P1     C2285 -1   M      A18X+043523Y+104727X0198Y0197     S2      
327PVDD11_S3_P1     C2287 -1   M      A18X+042073Y+104727X0198Y0197     S2      
327PVDD11_S3_P1     C2289 -1   M      A18X+042823Y+104727X0198Y0197     S2      
327PVDD11_S3_P1     C2291 -1   M      A18X+043889Y+103208X0198Y0197R090 S2      
327PVDD11_S3_P1     C2480 -1   M      A18X+048023Y+104727X0198Y0197     S2      
327PVDD11_S3_P1     C2481 -1   M      A18X+047273Y+104727X0198Y0197     S2      
327PVDD11_S3_P1     C2482 -1   M      A18X+048167Y+103727X0198Y0197     S2      
327PVDD11_S3_P1     C2483 -1   M      A18X+048723Y+104077X0198Y0197     S2      
327PVDD11_S3_P1     C2485 -1          A01X+045385Y+103208X0198Y0197R270 S1      
327PVDD11_S3_P1     C2486 -1          A18X+043487Y+101888X0198Y0197R180 S2      
327PVDD11_S3_P1     C2487 -1          A01X+046573Y+103230X0198Y0197R180 S1      
327PVDD11_S3_P1     C2488 -1          A18X+045396Y+102301X0198Y0197R180 S2      
327PVDD11_S3_P1     C2489 -1   M      A18X+041874Y+103230X0198Y0197     S2      
327PVDD11_S3_P1     C2490 -1   M      A18X+041323Y+104077X0198Y0197     S2      
327PVDD11_S3_P1     C2491 -1   M      A18X+044637Y+103208X0198Y0197R090 S2      
327PVDD11_S3_P1     C2492 -1   M      A18X+046573Y+103230X0198Y0197     S2      
327PVDD11_S3_P1     C2494 -1   M      A18X+042767Y+103208X0198Y0197R090 S2      
327PVDD11_S3_P1     C2495 -1   M      A18X+040573Y+104077X0198Y0197     S2      
327PVDD11_S3_P1     C2496 -1   M      A18X+045773Y+104077X0198Y0197     S2      
327PVDD11_S3_P1     C2497 -1   M      A18X+045385Y+103208X0198Y0197R090 S2      
327PVDD11_S3_P1     C2499 -1          A01X+044263Y+103208X0198Y0197R270 S1      
327PVDD11_S3_P1     C2500 -1          A01X+042767Y+103208X0198Y0197R270 S1      
327PVDD11_S3_P1     C2501 -1          A01X+045011Y+103208X0198Y0197R270 S1      
327PVDD11_S3_P1     C2502 -1          A18X+043487Y+102301X0198Y0197R180 S2      
327PVDD11_S3_P1     C2503 -1          A01X+043487Y+101888X0198Y0197     S1      
327PVDD11_S3_P1     C2504 -1          A01X+043515Y+103208X0198Y0197R270 S1      
327PVDD11_S3_P1     C2505 -1          A18X+044372Y+102301X0198Y0197R180 S2      
327PVDD11_S3_P1     C2506 -1   M      A18X+045011Y+103208X0198Y0197R090 S2      
327PVDD11_S3_P1     C2508 -1          A01X+045759Y+103208X0198Y0197R270 S1      
327PVDD11_S3_P1     C2510 -1   M      A18X+044263Y+103208X0198Y0197R090 S2      
327PVDD11_S3_P1     C2511 -1   M      A18X+046523Y+104727X0198Y0197     S2      
327PVDD11_S3_P1     C3902 -1   M      A18X+042823Y+104077X0198Y0197     S2      
327PVDD11_S3_P1     C3903 -1   M      A18X+042073Y+104077X0198Y0197     S2      
327PVDD11_S3_P1     C3904 -1   M      A18X+044273Y+103877X0198Y0197     S2      
327PVDD11_S3_P1     C3905 -1   M      A18X+044273Y+104277X0198Y0197     S2      
327PVDD11_S3_P1     C3919 -1   M      A18X+048723Y+104727X0198Y0197     S2      
327PVDD11_S3_P1     C3920 -1          A01X+041874Y+103230X0198Y0197R180 S1      
327PVDD11_S3_P1     C3921 -1   M      A18X+042393Y+103208X0198Y0197R090 S2      
327PVDD11_S3_P1     C3922 -1   M      A18X+039873Y+104727X0198Y0197     S2      
327PVDD11_S3_P1     R542  -1          A18X+062880Y+075102X0198Y0197R270 S2      
317PVDD11_S3_P1     VIA   -    MD0100PA00X+082393Y+090768X0200Y         S0      
317PVDD11_S3_P1     VIA   -    MD0100PA00X+091950Y+094150X0200Y         S0      
327PVDD11_S3_P1     R359  -1          A18X+091950Y+094492X0198Y0197R270 S2      
317PVDD11_S3_P1     VIA   -    MD0100PA00X+090184Y+093686X0200Y         S0      
317PVDD11_S3_P1     VIA   -    MD0100PA00X+093250Y+094150X0200Y         S0      
327PVDD11_S3_P1     R362  -1          A18X+093250Y+094492X0198Y0197R270 S2      
327PVDD11_S3_P1     U26   -BJ18       A01X+051342Y+103658X0177Y    R180 S1      
327PVDD11_S3_P1     U26   -BJ23       A01X+049491Y+103658X0177Y    R180 S1      
327PVDD11_S3_P1     U26   -BJ25       A01X+048751Y+103658X0177Y    R180 S1      
327PVDD11_S3_P1     U26   -BJ27       A01X+048011Y+103658X0177Y    R180 S1      
327PVDD11_S3_P1     U26   -BK22       A01X+050046Y+103976X0177Y    R180 S1      
327PVDD11_S3_P1     U26   -BK24       A01X+049306Y+103976X0177Y    R180 S1      
327PVDD11_S3_P1     U26   -BK26       A01X+048566Y+103976X0177Y    R180 S1      
327PVDD11_S3_P1     U26   -BK28       A01X+047826Y+103976X0177Y    R180 S1      
327PVDD11_S3_P1     U26   -BK49       A01X+040054Y+103976X0177Y    R180 S1      
327PVDD11_S3_P1     U26   -BL23       A01X+049491Y+104295X0177Y    R180 S1      
327PVDD11_S3_P1     U26   -BL25       A01X+048751Y+104295X0177Y    R180 S1      
327PVDD11_S3_P1     U26   -BL27       A01X+048011Y+104295X0177Y    R180 S1      
327PVDD11_S3_P1     U26   -BL48       A01X+040609Y+104295X0177Y    R180 S1      
327PVDD11_S3_P1     U26   -BM12       A01X+053747Y+104614X0177Y    R180 S1      
327PVDD11_S3_P1     U26   -BM19       A01X+051157Y+104614X0177Y    R180 S1      
327PVDD11_S3_P1     U26   -BM22       A01X+050046Y+104614X0177Y    R180 S1      
327PVDD11_S3_P1     U26   -BM24       A01X+049306Y+104614X0177Y    R180 S1      
327PVDD11_S3_P1     U26   -BM26       A01X+048566Y+104614X0177Y    R180 S1      
327PVDD11_S3_P1     U26   -BM28       A01X+047826Y+104614X0177Y    R180 S1      
327PVDD11_S3_P1     U26   -BM30       A01X+047086Y+104614X0177Y    R180 S1      
327PVDD11_S3_P1     U26   -BM32       A01X+046346Y+104614X0177Y    R180 S1      
327PVDD11_S3_P1     U26   -BM34       A01X+045606Y+104614X0177Y    R180 S1      
327PVDD11_S3_P1     U26   -BM36       A01X+044865Y+104614X0177Y    R180 S1      
327PVDD11_S3_P1     U26   -BM39       A01X+043755Y+104614X0177Y    R180 S1      
327PVDD11_S3_P1     U26   -BM41       A01X+043015Y+104614X0177Y    R180 S1      
327PVDD11_S3_P1     U26   -BM43       A01X+042275Y+104614X0177Y    R180 S1      
327PVDD11_S3_P1     U26   -BM45       A01X+041535Y+104614X0177Y    R180 S1      
327PVDD11_S3_P1     U26   -BM47       A01X+040794Y+104614X0177Y    R180 S1      
327PVDD11_S3_P1     U26   -BM49       A01X+040054Y+104614X0177Y    R180 S1      
327PVDD11_S3_P1     U26   -BN25       A01X+048751Y+104933X0177Y    R180 S1      
327PVDD11_S3_P1     U26   -BN29       A01X+047271Y+104933X0177Y    R180 S1      
327PVDD11_S3_P1     U26   -BN33       A01X+045790Y+104933X0177Y    R180 S1      
327PVDD11_S3_P1     U26   -BN40       A01X+043570Y+104933X0177Y    R180 S1      
327PVDD11_S3_P1     U26   -BN44       A01X+042090Y+104933X0177Y    R180 S1      
327PVDD11_S3_P1     U26   -BN48       A01X+040609Y+104933X0177Y    R180 S1      
327PVDD11_S3_P1     U26   -BP22       A01X+050046Y+105252X0177Y    R180 S1      
327PVDD11_S3_P1     U26   -BR4        A01X+056523Y+105571X0177Y    R180 S1      
327PVDD11_S3_P1     U26   -BR11       A01X+053932Y+105571X0177Y    R180 S1      
327PVDD11_S3_P1     U26   -BR18       A01X+051342Y+105571X0177Y    R180 S1      
327PVDD11_S3_P1     U26   -BV5        A01X+056338Y+106528X0177Y    R180 S1      
327PVDD11_S3_P1     U26   -BV12       A01X+053747Y+106528X0177Y    R180 S1      
327PVDD11_S3_P1     U26   -BV19       A01X+051157Y+106528X0177Y    R180 S1      
327PVDD11_S3_P1     U26   -BV22       A01X+050046Y+106528X0177Y    R180 S1      
327PVDD11_S3_P1     U26   -CA4        A01X+056523Y+107484X0177Y    R180 S1      
327PVDD11_S3_P1     U26   -CA11       A01X+053932Y+107484X0177Y    R180 S1      
327PVDD11_S3_P1     U26   -CA18       A01X+051342Y+107484X0177Y    R180 S1      
327PVDD11_S3_P1     U26   -CB22       A01X+050046Y+107803X0177Y    R180 S1      
327PVDD11_S3_P1     U26   -CD5        A01X+056338Y+108441X0177Y    R180 S1      
327PVDD11_S3_P1     U26   -CD12       A01X+053747Y+108441X0177Y    R180 S1      
327PVDD11_S3_P1     U26   -CD19       A01X+051157Y+108441X0177Y    R180 S1      
327PVDD11_S3_P1     U26   -CF22       A01X+050046Y+109079X0177Y    R180 S1      
327PVDD11_S3_P1     U26   -CG4        A01X+056523Y+109398X0177Y    R180 S1      
327PVDD11_S3_P1     U26   -CG11       A01X+053932Y+109398X0177Y    R180 S1      
327PVDD11_S3_P1     U26   -CG18       A01X+051342Y+109398X0177Y    R180 S1      
327PVDD11_S3_P1     U26   -CJ22       A01X+049861Y+110036X0177Y    R180 S1      
327PVDD11_S3_P1     U26   -CK5        A01X+056338Y+110354X0177Y    R180 S1      
327PVDD11_S3_P1     U26   -CK12       A01X+053747Y+110354X0177Y    R180 S1      
327PVDD11_S3_P1     U26   -CK19       A01X+051157Y+110354X0177Y    R180 S1      
327PVDD11_S3_P1     U26   -CM22       A01X+050046Y+110992X0177Y    R180 S1      
327PVDD11_S3_P1     U26   -CN4        A01X+056523Y+111311X0177Y    R180 S1      
327PVDD11_S3_P1     U26   -CN11       A01X+053932Y+111311X0177Y    R180 S1      
327PVDD11_S3_P1     U26   -CN18       A01X+051342Y+111311X0177Y    R180 S1      
327PVDD11_S3_P1     U26   -CT5        A01X+056338Y+112268X0177Y    R180 S1      
327PVDD11_S3_P1     U26   -CT12       A01X+053747Y+112268X0177Y    R180 S1      
327PVDD11_S3_P1     U26   -CT19       A01X+051157Y+112268X0177Y    R180 S1      
327PVDD11_S3_P1     U26   -CT22       A01X+050046Y+112268X0177Y    R180 S1      
327PVDD11_S3_P1     U26   -CW4        A01X+056523Y+113225X0177Y    R180 S1      
327PVDD11_S3_P1     U26   -CW11       A01X+053932Y+113225X0177Y    R180 S1      
327PVDD11_S3_P1     U26   -CW18       A01X+051342Y+113225X0177Y    R180 S1      
327PVDD11_S3_P1     U26   -CY22       A01X+050046Y+113543X0177Y    R180 S1      
327PVDD11_S3_P1     U26   -DB5        A01X+056338Y+114181X0177Y    R180 S1      
327PVDD11_S3_P1     U26   -DB12       A01X+053747Y+114181X0177Y    R180 S1      
327PVDD11_S3_P1     U26   -DB19       A01X+051157Y+114181X0177Y    R180 S1      
327PVDD11_S3_P1     U26   -DE4        A01X+056523Y+115138X0177Y    R180 S1      
327PVDD11_S3_P1     U26   -DE11       A01X+053932Y+115138X0177Y    R180 S1      
327PVDD11_S3_P1     U26   -DE18       A01X+051342Y+115138X0177Y    R180 S1      
327PVDD11_S3_P1     U26   -DG5        A01X+056153Y+115776X0177Y    R180 S1      
317PVDD11_S3_P1     VIA   -    MD0100PA00X+077088Y+134334X0200Y         S0      
317PVDD11_S3_P1     VIA   -    MD0100PA00X+077088Y+134584X0200Y         S0      
317PVDD11_S3_P1     VIA   -    MD0100PA00X+076226Y+134342X0200Y         S0      
317PVDD11_S3_P1     VIA   -    MD0100PA00X+076226Y+134592X0200Y         S0      
317PVDD11_S3_P1     VIA   -    MD0100PA00X+073080Y+134244X0200Y         S0      
317PVDD11_S3_P1     VIA   -    MD0100PA00X+073950Y+134224X0200Y         S0      
317PVDD11_S3_P1     VIA   -    M      A01X+073574Y+132305X0200Y         S2      
017PVDD11_S3_P1     VIA   -    M      A18X+073574Y+132305X0260Y         S2      
017PVDD11_S3_P1           -    MD0100PA00X+073574Y+132305                       
327PVDD11_S3_P1     PC523_-1          A18X+076646Y+134336X0400Y0500R090 S2      
327PVDD11_S3_P1     PC528 -1          A18X+075274Y+134243X0950Y1110R270 S2      
327PVDD11_S3_P1     PC527_-1          A18X+073527Y+134399X0400Y0500R090 S2      
327PVDD11_S3_P1     PC525 -1          A18X+072027Y+134252X0950Y1110R270 S2      
327PVDD11_S3_P1     PC526_-1          A18X+070612Y+134399X0400Y0500R090 S2      
327PVDD11_S3_P1     PC802 -1          A18X+069227Y+134089X0950Y1110R270 S2      
327PVDD11_S3_P1     PC529_-1          A18X+067855Y+134399X0400Y0500R090 S2      
327PVDD11_S3_P1     VIA   -           A18X+076756Y+132801X0260Y         S2      
327PVDD11_S3_P1     VIA   -           A18X+072714Y+131309X0260Y         S2      
327PVDD11_S3_P1     PR395 -1          A01X+069870Y+134580X0198Y0197R090 S1      
327PVDD11_S3_P1     PC530 -1          A01X+076464Y+131868X0630Y1190     S1      
327PVDD11_S3_P1     PC532 -1          A01X+074064Y+131868X0630Y1190     S1      
327PVDD11_S3_P1     PC531 -1          A01X+071664Y+131868X0630Y1190     S1      
327PVDD11_S3_P1     PC803 -1          A01X+069276Y+131864X0630Y1190     S1      
327PVDD11_S3_P1     PC524 -1          A01X+067807Y+131176X0198Y0197R270 S1      
327PVDD11_S3_P1     PR229 -1          A01X+067418Y+131250X0198Y0197R180 S1      
317PVDD11_S3_P1     VIA   -    MD0100PA00X+073950Y+134474X0200Y         S0      
317PVDD11_S3_P1     VIA   -    MD0100PA00X+073080Y+134494X0200Y         S0      
317PVDD11_S3_P1     VIA   -    MD0100PA00X+070635Y+139759X0200Y    R180 S0      
317PVDD11_S3_P1     VIA   -    MD0100PA00X+071022Y+134499X0200Y    R180 S0      
327PVDD11_S3_P1     PR332 -2          A18X+070574Y+139512X0198Y0197R270 S2      
317PVDD11_S3_P1     VIA   -    MD0100PA00X+070177Y+134499X0200Y    R180 S0      
317PVDD11_S3_P1     VIA   -    MD0100PA00X+068305Y+134505X0200Y    R180 S0      
317PVDD11_S3_P1     VIA   -    MD0100PA00X+067455Y+134499X0200Y    R180 S0      
317PVDD11_S3_P1     VIA   -    MD0100PA00X+076275Y+133231X0200Y         S0      
317PVDD11_S3_P1     VIA   -    MD0100PA00X+076275Y+132981X0200Y         S0      
317PVDD11_S3_P1     VIA   -    MD0100PA00X+076275Y+133481X0200Y         S0      
317PVDD11_S3_P1     VIA   -    MD0100PA00X+076284Y+133982X0200Y         S0      
317PVDD11_S3_P1     VIA   -    MD0100PA00X+076284Y+133732X0200Y         S0      
317PVDD11_S3_P1     VIA   -    MD0100PA00X+074297Y+133212X0200Y         S0      
317PVDD11_S3_P1     VIA   -    MD0100PA00X+074297Y+132962X0200Y         S0      
317PVDD11_S3_P1     VIA   -    MD0100PA00X+074297Y+133462X0200Y         S0      
317PVDD11_S3_P1     VIA   -    MD0100PA00X+074297Y+133962X0200Y         S0      
317PVDD11_S3_P1     VIA   -    MD0100PA00X+074297Y+133712X0200Y         S0      
317PVDD11_S3_P1     VIA   -    MD0100PA00X+074819Y+133552X0200Y         S0      
317PVDD11_S3_P1     VIA   -    MD0100PA00X+074569Y+133742X0200Y         S0      
317PVDD11_S3_P1     VIA   -    MD0100PA00X+074569Y+133992X0200Y         S0      
317PVDD11_S3_P1     VIA   -    MD0100PA00X+073993Y+139804X0200Y    R180 S0      
327PVDD11_S3_P1     PR333 -2          A18X+073852Y+139522X0198Y0197R270 S2      
317PVDD11_S3_P1     VIA   -    MD0100PA00X+074819Y+133052X0200Y         S0      
317PVDD11_S3_P1     VIA   -    MD0100PA00X+074819Y+133302X0200Y         S0      
317PVDD11_S3_P1     VIA   -    MD0100PA00X+074569Y+133492X0200Y         S0      
317PVDD11_S3_P1     VIA   -    MD0100PA00X+074569Y+132992X0200Y         S0      
317PVDD11_S3_P1     VIA   -    MD0100PA00X+074569Y+133242X0200Y         S0      
317PVDD11_S3_P1     VIA   -    MD0100PA00X+075764Y+133552X0200Y         S0      
317PVDD11_S3_P1     VIA   -    MD0100PA00X+076019Y+133752X0200Y         S0      
317PVDD11_S3_P1     VIA   -    MD0100PA00X+076019Y+134002X0200Y         S0      
317PVDD11_S3_P1     VIA   -    MD0100PA00X+075764Y+133052X0200Y         S0      
317PVDD11_S3_P1     VIA   -    MD0100PA00X+075764Y+133302X0200Y         S0      
317PVDD11_S3_P1     VIA   -    MD0100PA00X+076020Y+133501X0200Y         S0      
317PVDD11_S3_P1     VIA   -    MD0100PA00X+076020Y+133001X0200Y         S0      
317PVDD11_S3_P1     VIA   -    MD0100PA00X+076020Y+133251X0200Y         S0      
327PVDD11_S3_P1     PL55  -2   M      A01X+075294Y+133538X1300Y1660R270 S1      
317PVDD11_S3_P1     VIA   -    MD0100PA00X+073002Y+133223X0200Y         S0      
317PVDD11_S3_P1     VIA   -    MD0100PA00X+073002Y+132973X0200Y         S0      
317PVDD11_S3_P1     VIA   -    MD0100PA00X+073002Y+133473X0200Y         S0      
317PVDD11_S3_P1     VIA   -    MD0100PA00X+073002Y+133973X0200Y         S0      
317PVDD11_S3_P1     VIA   -    MD0100PA00X+073002Y+133723X0200Y         S0      
317PVDD11_S3_P1     VIA   -    MD0100PA00X+071029Y+132968X0200Y         S0      
317PVDD11_S3_P1     VIA   -    MD0100PA00X+071029Y+133218X0200Y         S0      
317PVDD11_S3_P1     VIA   -    MD0100PA00X+071029Y+133468X0200Y         S0      
317PVDD11_S3_P1     VIA   -    MD0100PA00X+071022Y+134249X0200Y    R180 S0      
317PVDD11_S3_P1     VIA   -    MD0100PA00X+071029Y+133718X0200Y         S0      
317PVDD11_S3_P1     VIA   -    MD0100PA00X+071029Y+133968X0200Y         S0      
317PVDD11_S3_P1     VIA   -    MD0100PA00X+071583Y+133538X0200Y         S0      
317PVDD11_S3_P1     VIA   -    MD0100PA00X+071301Y+133988X0200Y         S0      
317PVDD11_S3_P1     VIA   -    MD0100PA00X+071301Y+133738X0200Y         S0      
317PVDD11_S3_P1     VIA   -    MD0100PA00X+071583Y+133038X0200Y         S0      
317PVDD11_S3_P1     VIA   -    MD0100PA00X+071583Y+133288X0200Y         S0      
317PVDD11_S3_P1     VIA   -    MD0100PA00X+071301Y+133488X0200Y         S0      
317PVDD11_S3_P1     VIA   -    MD0100PA00X+071301Y+133238X0200Y         S0      
317PVDD11_S3_P1     VIA   -    MD0100PA00X+071301Y+132988X0200Y         S0      
317PVDD11_S3_P1     VIA   -    MD0100PA00X+072479Y+133538X0200Y         S0      
317PVDD11_S3_P1     VIA   -    MD0100PA00X+072740Y+133743X0200Y         S0      
317PVDD11_S3_P1     VIA   -    MD0100PA00X+072740Y+133993X0200Y         S0      
317PVDD11_S3_P1     VIA   -    MD0100PA00X+072479Y+133288X0200Y         S0      
317PVDD11_S3_P1     VIA   -    MD0100PA00X+072479Y+133038X0200Y         S0      
317PVDD11_S3_P1     VIA   -    MD0100PA00X+072740Y+133493X0200Y         S0      
317PVDD11_S3_P1     VIA   -    MD0100PA00X+072740Y+132993X0200Y         S0      
317PVDD11_S3_P1     VIA   -    MD0100PA00X+072740Y+133243X0200Y         S0      
327PVDD11_S3_P1     PL54  -2   M      A01X+072016Y+133528X1300Y1660R270 S1      
317PVDD11_S3_P1     VIA   -    MD0100PA00X+069987Y+133463X0200Y         S0      
317PVDD11_S3_P1     VIA   -    MD0100PA00X+070239Y+133463X0200Y         S0      
317PVDD11_S3_P1     VIA   -    MD0100PA00X+069987Y+133213X0200Y         S0      
317PVDD11_S3_P1     VIA   -    MD0100PA00X+070239Y+133213X0200Y         S0      
317PVDD11_S3_P1     VIA   -    MD0100PA00X+069987Y+132963X0200Y         S0      
317PVDD11_S3_P1     VIA   -    MD0100PA00X+070239Y+132963X0200Y         S0      
317PVDD11_S3_P1     VIA   -    MD0100PA00X+069987Y+133963X0200Y         S0      
317PVDD11_S3_P1     VIA   -    MD0100PA00X+069987Y+133713X0200Y         S0      
317PVDD11_S3_P1     VIA   -    MD0100PA00X+070239Y+133963X0200Y         S0      
317PVDD11_S3_P1     VIA   -    MD0100PA00X+070239Y+133713X0200Y         S0      
317PVDD11_S3_P1     VIA   -    MD0100PA00X+070177Y+134249X0200Y    R180 S0      
317PVDD11_S3_P1     VIA   -    MD0100PA00X+068235Y+133712X0200Y         S0      
317PVDD11_S3_P1     VIA   -    MD0100PA00X+068487Y+133962X0200Y         S0      
317PVDD11_S3_P1     VIA   -    MD0100PA00X+068487Y+133712X0200Y         S0      
317PVDD11_S3_P1     VIA   -    MD0100PA00X+068235Y+133462X0200Y         S0      
317PVDD11_S3_P1     VIA   -    MD0100PA00X+068487Y+133462X0200Y         S0      
317PVDD11_S3_P1     VIA   -    MD0100PA00X+068235Y+133212X0200Y         S0      
317PVDD11_S3_P1     VIA   -    MD0100PA00X+068487Y+133212X0200Y         S0      
317PVDD11_S3_P1     VIA   -    MD0100PA00X+068235Y+132962X0200Y         S0      
317PVDD11_S3_P1     VIA   -    MD0100PA00X+068487Y+132962X0200Y         S0      
317PVDD11_S3_P1     VIA   -    MD0100PA00X+068305Y+134255X0200Y    R180 S0      
317PVDD11_S3_P1     VIA   -    MD0100PA00X+068235Y+133962X0200Y         S0      
317PVDD11_S3_P1     VIA   -    MD0100PA00X+067455Y+134249X0200Y    R180 S0      
317PVDD11_S3_P1     VIA   -    MD0100PA00X+076944Y+131695X0200Y         S0      
317PVDD11_S3_P1     VIA   -    MD0100PA00X+076944Y+132295X0200Y         S0      
317PVDD11_S3_P1     VIA   -    MD0100PA00X+076944Y+131995X0200Y         S0      
317PVDD11_S3_P1     VIA   -    MD0100PA00X+075984Y+132295X0200Y         S0      
317PVDD11_S3_P1     VIA   -    MD0100PA00X+075764Y+132732X0200Y         S0      
317PVDD11_S3_P1     VIA   -    MD0100PA00X+075984Y+131695X0200Y         S0      
317PVDD11_S3_P1     VIA   -    MD0100PA00X+076275Y+132731X0200Y         S0      
317PVDD11_S3_P1     VIA   -    MD0100PA00X+076020Y+132731X0200Y         S0      
317PVDD11_S3_P1     VIA   -    MD0100PA00X+075984Y+131995X0200Y         S0      
317PVDD11_S3_P1     VIA   -    MD0100PA00X+074544Y+131705X0200Y         S0      
317PVDD11_S3_P1     VIA   -    MD0100PA00X+074544Y+132005X0200Y         S0      
317PVDD11_S3_P1     VIA   -    MD0100PA00X+074544Y+132305X0200Y         S0      
317PVDD11_S3_P1     VIA   -    MD0100PA00X+074297Y+132712X0200Y         S0      
317PVDD11_S3_P1     VIA   -    MD0100PA00X+074549Y+132712X0200Y         S0      
317PVDD11_S3_P1     VIA   -    MD0100PA00X+074819Y+132732X0200Y         S0      
317PVDD11_S3_P1     VIA   -    MD0100PA00X+073002Y+132723X0200Y         S0      
317PVDD11_S3_P1     VIA   -    MD0100PA00X+072750Y+132723X0200Y         S0      
317PVDD11_S3_P1     VIA   -    MD0100PA00X+072479Y+132728X0200Y         S0      
317PVDD11_S3_P1     VIA   -    MD0100PA00X+073574Y+131705X0200Y         S0      
317PVDD11_S3_P1     VIA   -    MD0100PA00X+073574Y+132005X0200Y         S0      
317PVDD11_S3_P1     VIA   -    MD0100PA00X+071184Y+131735X0200Y         S0      
317PVDD11_S3_P1     VIA   -    MD0100PA00X+071184Y+132035X0200Y         S0      
317PVDD11_S3_P1     VIA   -    MD0100PA00X+071184Y+132335X0200Y         S0      
317PVDD11_S3_P1     VIA   -    MD0100PA00X+071301Y+132718X0200Y         S0      
317PVDD11_S3_P1     VIA   -    MD0100PA00X+071049Y+132718X0200Y         S0      
317PVDD11_S3_P1     VIA   -    MD0100PA00X+071583Y+132728X0200Y         S0      
317PVDD11_S3_P1     VIA   -    MD0100PA00X+072134Y+131705X0200Y         S0      
317PVDD11_S3_P1     VIA   -    MD0100PA00X+072134Y+132005X0200Y         S0      
317PVDD11_S3_P1     VIA   -    MD0100PA00X+072134Y+132305X0200Y         S0      
317PVDD11_S3_P1     VIA   -    MD0100PA00X+069746Y+131701X0200Y         S0      
317PVDD11_S3_P1     VIA   -    MD0100PA00X+069987Y+132713X0200Y         S0      
317PVDD11_S3_P1     VIA   -    MD0100PA00X+070239Y+132713X0200Y         S0      
317PVDD11_S3_P1     VIA   -    MD0100PA00X+069746Y+132301X0200Y         S0      
317PVDD11_S3_P1     VIA   -    MD0100PA00X+069746Y+132001X0200Y         S0      
317PVDD11_S3_P1     VIA   -    MD0100PA00X+068235Y+132712X0200Y         S0      
317PVDD11_S3_P1     VIA   -    MD0100PA00X+068487Y+132712X0200Y         S0      
317PVDD11_S3_P1     VIA   -    MD0100PA00X+068796Y+131731X0200Y         S0      
317PVDD11_S3_P1     VIA   -    MD0100PA00X+068796Y+132331X0200Y         S0      
317PVDD11_S3_P1     VIA   -    MD0100PA00X+068796Y+132031X0200Y         S0      
317PVDD11_S3_P1     VIA   -    MD0100PA00X+076944Y+131395X0200Y         S0      
317PVDD11_S3_P1     VIA   -    MD0100PA00X+082811Y+123450X0200Y         S0      
317PVDD11_S3_P1     VIA   -    MD0100PA00X+075984Y+131395X0200Y         S0      
317PVDD11_S3_P1     VIA   -    MD0100PA00X+074544Y+131405X0200Y         S0      
317PVDD11_S3_P1     VIA   -    MD0100PA00X+073574Y+131405X0200Y         S0      
317PVDD11_S3_P1     VIA   -    MD0100PA00X+071184Y+131435X0200Y         S0      
317PVDD11_S3_P1     VIA   -    MD0100PA00X+072134Y+131405X0200Y         S0      
317PVDD11_S3_P1     VIA   -    MD0100PA00X+069746Y+131401X0200Y         S0      
317PVDD11_S3_P1     VIA   -    MD0100PA00X+068796Y+131431X0200Y         S0      
317PVDD11_S3_P1     VIA   -    MD0100PA00X+045747Y+103243X0190Y    R180 S0      
317PVDD11_S3_P1     VIA   -    MD0100PA00X+046596Y+103221X0190Y    R270 S0      
317PVDD11_S3_P1     VIA   -    MD0100PA00X+044999Y+103243X0190Y    R180 S0      
317PVDD11_S3_P1     VIA   -    MD0100PA00X+044625Y+103243X0190Y    R180 S0      
317PVDD11_S3_P1     VIA   -    MD0100PA00X+044288Y+104277X0190Y         S0      
317PVDD11_S3_P1     VIA   -    MD0100PA00X+044251Y+103243X0190Y    R180 S0      
317PVDD11_S3_P1     VIA   -    MD0100PA00X+044288Y+103877X0190Y         S0      
317PVDD11_S3_P1     VIA   -    MD0100PA00X+045373Y+103243X0190Y    R180 S0      
317PVDD11_S3_P1     VIA   -    MD0100PA00X+042755Y+103243X0190Y    R180 S0      
317PVDD11_S3_P1     VIA   -    MD0100PA00X+043877Y+103243X0190Y    R180 S0      
317PVDD11_S3_P1     VIA   -    MD0100PA00X+043503Y+103243X0190Y    R180 S0      
317PVDD11_S3_P1     VIA   -    MD0100PA00X+043129Y+103243X0190Y    R180 S0      
317PVDD11_S3_P1     VIA   -    MD0100PA00X+042381Y+103243X0190Y    R180 S0      
317PVDD11_S3_P1     VIA   -    MD0100PA00X+041892Y+103221X0190Y    R180 S0      
317PVDD11_S3_P1     VIA   -    MD0100PA00X+044357Y+102301X0190Y    R180 S0      
317PVDD11_S3_P1     VIA   -    MD0100PA00X+045381Y+102301X0190Y    R180 S0      
317PVDD11_S3_P1     VIA   -    MD0100PA00X+043472Y+102301X0190Y    R180 S0      
317PVDD11_S3_P1     VIA   -    MD0100PA00X+043472Y+101888X0190Y    R180 S0      
317PVDD11_S3_P1     VIA   -    M      A01X+031478Y+054572X0200Y         S2      
017PVDD11_S3_P1     VIA   -    M      A18X+031478Y+054572X0260Y         S2      
017PVDD11_S3_P1           -    MD0100PA00X+031478Y+054572                       
327PVDD11_S3_P1     R5020 -1          A01X+071672Y+063069X0198Y0197R090 S1      
317PVDD11_S3_P1     VIA   -    MD0100PA00X+071672Y+062791X0200Y         S0      
327PVDD11_S3_P1     R5021 -1          A01X+072079Y+063076X0198Y0197R090 S1      
317PVDD11_S3_P1     VIA   -    MD0100PA00X+072079Y+062791X0200Y         S0      
327PVDD11_S3_P1     R5013 -1          A01X+072213Y+066424X0198Y0197R270 S1      
317PVDD11_S3_P1     VIA   -    MD0100PA00X+072213Y+066672X0200Y         S0      
317PVDD11_S3_P1     VIA   -    MD0100PA00X+068579Y+068094X0200Y         S0      
317PVDD11_S3_P1     VIA   -    MD0100PA00X+070123Y+065536X0200Y         S0      
317PVDD11_S3_P1     VIA   -    MD0100PA00X+064992Y+054561X0200Y         S0      
327PVDD11_S3_P1     R5012 -1          A01X+071813Y+066424X0198Y0197R270 S1      
317PVDD11_S3_P1     VIA   -    MD0100PA00X+071813Y+066672X0200Y         S0      
317PVDD11_S3_P1     VIA   -    MD0100PA00X+066710Y+073607X0200Y         S0      
317PVDD11_S3_P1     VIA   -    MD0100PA00X+018250Y+067250X0200Y         S0      
327PVDD11_S3_P1     R563  -1   M      A01X+017958Y+067250X0198Y0197R180 S1      
327PVDD11_S3_P1     R543  -1          A01X+017958Y+067650X0198Y0197R180 S1      
327PVDD11_S3_P1     R5019 -1   M      A01X+016944Y+068480X0198Y0197R180 S1      
327PVDD11_S3_P1     R5018 -1          A01X+016944Y+068080X0198Y0197R180 S1      
317PVDD11_S3_P1     VIA   -    MD0100PA00X+017250Y+068480X0200Y         S0      
327PVDD11_S3_P1     R5010 -1          A01X+013490Y+067529X0198Y0197     S1      
327PVDD11_S3_P1     R5011 -1   M      A01X+013490Y+067929X0198Y0197     S1      
317PVDD11_S3_P1     VIA   -    MD0100PA00X+013196Y+067929X0200Y         S0      
327PVDD11_S3_P1     R541  -1   M      A18X+063280Y+075102X0198Y0197R270 S2      
317m4008            VIA   -    MD0100PA00X+168994Y+139381X0200Y         S0      
327m4008            PU23  -1          A01X+169122Y+139140X0090Y0240R090 S1      
327m4008            PR138 -1          A18X+168626Y+139136X0198Y0197R270 S2      
317m4009            VIA   -    MD0100PA00X+165716Y+139371X0200Y         S0      
327m4009            PU22  -1          A01X+165844Y+139130X0090Y0240R090 S1      
327m4009            PR137 -1          A18X+165348Y+139126X0198Y0197R270 S2      
327m4010            VIA   -    M      A18X+166698Y+142965X0260Y         S2      
327m4010            PR3   -1          A18X+166097Y+142694X0198Y0197     S2      
317m4010            VIA   -    MD0100PA00X+166324Y+142859X0200Y    R180 S0      
327m4010            PU21  -37         A01X+165873Y+142790X0070Y0240R270 S1      
327m4010            PC193 -1          A01X+166622Y+142834X0198Y0197     S1      
327m4010            PR113 -2          A18X+167026Y+142669X0198Y0197     S2      
317m4011            VIA   -    M      A01X+167108Y+143507X0200Y         S2      
017m4011            VIA   -    M      A18X+167108Y+143507X0260Y         S2      
017m4011                  -    MD0100PA00X+167108Y+143507                       
327m4011            PU21  -38         A01X+165873Y+142948X0070Y0240R270 S1      
327m4011            PC5   -1   M      A01X+166618Y+143222X0198Y0197     S1      
327m4011            PR125 -2          A01X+168100Y+143992X0198Y0197R270 S1      
327m4011            PR601 -1   M      A01X+168100Y+143658X0198Y0197R270 S1      
327m4012            VIA   -    M      A01X+163406Y+141573X0300Y    R180 S1      
327m4012            R8458 -2          A01X+163282Y+142045X0198Y0197     S1      
327m4012            PU21  -15         A01X+163983Y+142633X0070Y0240R270 S1      
317m4013            VIA   -    MD0100PA00X+169293Y+139999X0200Y         S2      
327m4013            PC202_-1          A01X+165367Y+144017X0198Y0197R090 S1      
327m4013            PC199 -1          A01X+165817Y+144017X0198Y0197R090 S1      
317m4013            VIA   -    MD0100PA00X+165809Y+143744X0200Y    R180 S0      
327m4013            PU21  -40         A01X+165873Y+143263X0070Y0240R270 S1      
317m4013            VIA   -    MD0100PA00X+166015Y+139989X0200Y         S0      
327m4013            PU22  -39         A01X+166006Y+139376X0090Y0240     S1      
327m4013            PC201_-1   M      A01X+165728Y+139989X0198Y0197R090 S1      
327m4013            PU23  -39         A01X+169284Y+139386X0090Y0240     S1      
327m4013            PC9   -1   M      A01X+169007Y+139999X0198Y0197R090 S1      
327m4014            PU23  -3          A01X+169122Y+138786X0090Y0240R090 S1      
327m4014            PC204 -1          A01X+168617Y+139136X0198Y0197R090 S1      
317m4014            VIA   -    MD0100PA00X+168617Y+138896X0200Y         S0      
327m4014            VIA   -    M      A18X+169337Y+139376X0260Y    R180 S2      
317m4014            VIA   -    MD0100PA00X+169963Y+139696X0200Y         S0      
327m4014            PR132 -2   M      A18X+169157Y+138819X0198Y0197R270 S2      
327m4014            PU23  -35         A01X+169992Y+139386X0090Y0240     S1      
327m4015            VIA   -    M      A18X+166058Y+139366X0260Y    R180 S2      
317m4015            VIA   -    MD0100PA00X+166684Y+139686X0200Y         S0      
327m4015            PR131 -2   M      A18X+165879Y+138809X0198Y0197R270 S2      
327m4015            PU22  -35         A01X+166714Y+139376X0090Y0240     S1      
317m4015            VIA   -    MD0100PA00X+165339Y+138886X0200Y         S0      
327m4015            PC203 -1          A01X+165339Y+139126X0198Y0197R090 S1      
327m4015            PU22  -3          A01X+165844Y+138776X0090Y0240R090 S1      
327m4016            PC4   -1          A01X+166629Y+143863X0198Y0197R090 S1      
327m4016            VIA   -           A01X+167464Y+144564X0300Y    R180 S1      
327m4016            PR130 -1   M      A01X+167015Y+143857X0198Y0197R090 S1      
327m4016            PC200 -1          A01X+166246Y+143860X0198Y0197R090 S1      
327m4016            PU21  -39         A01X+165873Y+143105X0070Y0240R270 S1      
327m4017            PR412 -1          A18X+165714Y+141628X0198Y0197     S2      
317m4017            VIA   -    MD0100PA00X+166249Y+142418X0200Y    R180 S0      
327m4017            VIA   -    M      A18X+165834Y+142312X0260Y    R180 S2      
327m4017            PU21  -35         A01X+165873Y+142475X0070Y0240R270 S1      
327m4018            PU22  -36         A01X+166537Y+139376X0090Y0240     S1      
317m4018            VIA   -    MD0100PA00X+166411Y+139783X0200Y         S2      
327m4018            PU23  -36         A01X+169815Y+139386X0090Y0240     S1      
317m4018            VIA   -    MD0100PA00X+169689Y+139793X0200Y         S0      
317m4018            VIA   -    MD0100PA00X+166424Y+142628X0200Y         S0      
327m4018            PU21  -36         A01X+165873Y+142633X0070Y0240R270 S1      
327m4018            PC198 -1          A01X+166625Y+142448X0198Y0197     S1      
327m4019            PR128 -1          A01X+163278Y+142837X0198Y0197R180 S1      
327m4019            PR129 -1   M      A01X+163278Y+142447X0198Y0197R180 S1      
327m4019            PU21  -14         A01X+163983Y+142790X0070Y0240R270 S1      
317m4019            VIA   -    M      A01X+163528Y+142245X0200Y    R180 S2      
017m4019            VIA   -    M      A18X+163528Y+142245X0260Y    R180 S2      
017m4019                  -    MD0100PA00X+163528Y+142245                       
327m4019            PR127 -1          A18X+162983Y+142137X0198Y0197R270 S2      
317m4020            VIA   -    M      A01X+082298Y+079124X0200Y         S2      
017m4020            VIA   -    M      A18X+082298Y+079124X0260Y         S2      
017m4020                  -    MD0100PA00X+082298Y+079124                       
317m4020            VIA   -    MD0100PA00X+075006Y+065542X0200Y         S0      
327m4020            U18   -H17        A01X+071938Y+047029X0160Y    R090 S1      
317m4020            VIA   -    MD0100PA00X+071784Y+047182X0180Y    R090 S0      
317m4020            VIA   -    MD0100PA00X+113418Y+148393X0200Y         S0      
327m4020            PR129 -2          A01X+162963Y+142447X0198Y0197R180 S1      
317m4021            VIA   -    M      A01X+165040Y+143782X0200Y    R180 S2      
017m4021            VIA   -    M      A18X+165040Y+143782X0260Y    R180 S2      
017m4021                  -    MD0100PA00X+165040Y+143782                       
327m4021            PU21  -7          A01X+164692Y+143499X0070Y0240R180 S1      
317m4021            VIA   -    MD0100PA00X+170038Y+139953X0200Y         S0      
327m4021            PU23  -34         A01X+170170Y+139386X0090Y0240     S1      
317m4022            VIA   -    MD0100PA00X+164598Y+143795X0200Y    R180 S0      
327m4022            PU21  -8          A01X+164535Y+143499X0070Y0240R180 S1      
327m4022            PU22  -34         A01X+166891Y+139376X0090Y0240     S1      
317m4022            VIA   -    MD0100PA00X+166759Y+139943X0200Y         S0      
327m4023            PR411 -1          A01X+164920Y+139119X0198Y0197R090 S1      
327m4023            PR413 -1          A01X+164516Y+139124X0198Y0197R090 S1      
327m4023            PC205_-1   M      A01X+165339Y+138391X0198Y0197R270 S1      
327m4023            PU22  -4          A01X+165844Y+138598X0090Y0240R090 S1      
327m4023            VIA   -           A01X+164738Y+138541X0300Y    R270 S1      
317m4023            VIA   -    MD0100PA00X+165339Y+138632X0200Y         S0      
327m4023            PR131 -1          A18X+165879Y+138494X0198Y0197R270 S2      
327m4023            PC206_-1   M      A01X+168617Y+138401X0198Y0197R270 S1      
327m4023            PU23  -4          A01X+169122Y+138608X0090Y0240R090 S1      
317m4023            VIA   -    MD0100PA00X+168617Y+138642X0200Y         S0      
327m4023            PR132 -1          A18X+169157Y+138504X0198Y0197R270 S2      
327m4024            VIA   -           A01X+164653Y+144577X0300Y    R180 S1      
327m4024            PU21  -9          A01X+164377Y+143499X0070Y0240R180 S1      
327m4024            R119  -2   M      A01X+164660Y+144049X0198Y0197R180 S1      
317m4025            VIA   -    M      A01X+164240Y+143967X0200Y    R180 S2      
017m4025            VIA   -    M      A18X+164240Y+143967X0260Y    R180 S2      
017m4025                  -    MD0100PA00X+164240Y+143967                       
327m4025            PU21  -10         A01X+164220Y+143499X0070Y0240R180 S1      
327m4025            R118  -2          A01X+164274Y+144223X0198Y0197     S1      
317m4026            VIA   -    M      A01X+163983Y+143448X0200Y    R180 S2      
017m4026            VIA   -    M      A18X+163983Y+143448X0260Y    R180 S2      
017m4026                  -    MD0100PA00X+163983Y+143448                       
327m4026            R120  -2          A01X+163617Y+143890X0198Y0197R270 S1      
327m4026            PU21  -11         A01X+163983Y+143263X0070Y0240R270 S1      
317m4027            VIA   -    MD0100PA00X+072729Y+043726X0180Y    R090 S0      
327m4027            U18   -L7         A01X+072883Y+043879X0160Y    R090 S1      
327m4027            R1189 -1          A18X+073015Y+043727X0198Y0197R270 S2      
317m4027            VIA   -    MD0100PA00X+150378Y+046482X0200Y         S0      
317m4027            VIA   -    M      A01X+163617Y+144675X0200Y         S2      
017m4027            VIA   -    M      A18X+163617Y+144675X0260Y         S2      
017m4027                  -    MD0100PA00X+163617Y+144675                       
327m4027            C5009 -1          A01X+163274Y+144802X0198Y0197R180 S1      
327m4027            R120  -1          A01X+163617Y+144205X0198Y0197R270 S1      
327m4028            R124  -2          A01X+166624Y+141668X0198Y0197R180 S1      
327m4028            PU21  -33         A01X+165873Y+142160X0070Y0240R270 S1      
317m4028            VIA   -    M      A01X+166181Y+141695X0200Y    R180 S2      
017m4028            VIA   -    M      A18X+166181Y+141695X0260Y    R180 S2      
017m4028                  -    MD0100PA00X+166181Y+141695                       
327m4028            R8116 -2          A18X+166626Y+141671X0198Y0197     S2      
317m4029            VIA   -    MD0100PA00X+071550Y+039086X0200Y    R090 S0      
327m4029            R226  -2          A18X+071550Y+039329X0198Y0197R090 S2      
317m4029            VIA   -    MD0100PA00X+071487Y+034494X0200Y         S0      
327m4029            VIA   -    M      A18X+166941Y+142197X0260Y    R180 S2      
327m4029            R8116 -1          A18X+166941Y+141671X0198Y0197     S2      
317m4029            VIA   -    MD0100PA00X+167240Y+142336X0200Y         S0      
317m4029            VIA   -    MD0100PA00X+106336Y+031830X0200Y         S0      
317m4029            VIA   -    MD0100PA00X+161470Y+042259X0200Y         S0      
317m4029            VIA   -    MD0100PA00X+101142Y+028289X0200Y         S0      
317m4029            VIA   -    MD0100PA00X+077968Y+031305X0200Y         S0      
317m4029            VIA   -    MD0100PA00X+075824Y+034376X0200Y         S0      
327m4030            VIA   -    M      A01X+169492Y+139870X0160Y0041R090 S1      
327m4030            PR134 -2          A01X+169396Y+140296X0198Y0197R180 S1      
327m4030            PU23  -37         A01X+169638Y+139386X0090Y0240     S1      
327m4031            VIA   -    M      A01X+166214Y+139860X0160Y0041R090 S1      
327m4031            PR133 -2          A01X+166118Y+140286X0198Y0197R180 S1      
327m4031            PU22  -37         A01X+166360Y+139376X0090Y0240     S1      
317m4032            VIA   -    M      A01X+164648Y+141274X0200Y    R090 S2      
017m4032            VIA   -    M      A18X+164648Y+141274X0260Y    R090 S2      
017m4032                  -    MD0100PA00X+164648Y+141274                       
327m4032            PU23  -38         A01X+169461Y+139386X0090Y0240     S1      
317m4032            VIA   -    MD0100PA00X+169293Y+139748X0200Y         S0      
327m4032            PU21  -24         A01X+164692Y+141609X0070Y0240R180 S1      
317m4033            VIA   -    M      A01X+164400Y+140807X0200Y    R090 S2      
017m4033            VIA   -    M      A18X+164400Y+140807X0260Y    R090 S2      
017m4033                  -    MD0100PA00X+164400Y+140807                       
327m4033            PU21  -23         A01X+164535Y+141609X0070Y0240R180 S1      
317m4033            VIA   -    MD0100PA00X+166015Y+139738X0200Y         S0      
327m4033            PU22  -38         A01X+166183Y+139376X0090Y0240     S1      
327m4034            R123  -2          A01X+162100Y+143242X0198Y0197R270 S1      
327m4034            PU21  -13         A01X+163983Y+142948X0070Y0240R270 S1      
327m4034            C197  -1   M      A01X+163280Y+143225X0198Y0197R180 S1      
317m4034            VIA   -    M      A01X+163562Y+143054X0200Y    R180 S2      
017m4034            VIA   -    M      A18X+163562Y+143054X0260Y    R180 S2      
017m4034                  -    MD0100PA00X+163562Y+143054                       
317m4035            VIA   -    MD0100PA00X+150597Y+047064X0200Y         S0      
327m4035            R227  -2          A01X+079268Y+041534X0198Y0197     S1      
317m4035            VIA   -    M      A01X+079628Y+041534X0200Y    R180 S2      
017m4035            VIA   -    M      A18X+079628Y+041534X0260Y    R180 S2      
017m4035                  -    MD0100PA00X+079628Y+041534                       
327m4035            R123  -1          A01X+162100Y+143558X0198Y0197R270 S1      
317m4035            VIA   -    MD0100PA00X+162270Y+144080X0200Y         S0      
317m4036            VIA   -    M      A01X+166378Y+142157X0200Y    R180 S2      
017m4036            VIA   -    M      A18X+166378Y+142157X0260Y    R180 S2      
017m4036                  -    MD0100PA00X+166378Y+142157                       
327m4036            PU21  -34         A01X+165873Y+142318X0070Y0240R270 S1      
327m4036            PR126 -1          A01X+166627Y+142057X0198Y0197     S1      
317PVDD11_S3_P0     VIA   -    MD0080PA00X+137485Y+104081X0160Y         S0      
317PVDD11_S3_P0     VIA   -    MD0080PA00X+137485Y+104719X0160Y         S0      
317PVDD11_S3_P0     VIA   -    MD0080PA00X+138040Y+105038X0160Y         S0      
317PVDD11_S3_P0     VIA   -    MD0080PA00X+138965Y+104719X0160Y         S0      
317PVDD11_S3_P0     VIA   -    MD0080PA00X+138225Y+104719X0160Y         S0      
317PVDD11_S3_P0     VIA   -    MD0080PA00X+138964Y+104082X0160Y         S0      
317PVDD11_S3_P0     VIA   -    MD0080PA00X+138225Y+104082X0160Y         S0      
317PVDD11_S3_P0     VIA   -    MD0080PA00X+138040Y+104400X0160Y         S0      
317PVDD11_S3_P0     VIA   -    MD0080PA00X+140444Y+104082X0160Y         S0      
317PVDD11_S3_P0     VIA   -    MD0080PA00X+139704Y+104082X0160Y         S0      
317PVDD11_S3_P0     VIA   -    MD0080PA00X+139520Y+105038X0160Y         S0      
317PVDD11_S3_P0     VIA   -    MD0080PA00X+140445Y+104719X0160Y         S0      
317PVDD11_S3_P0     VIA   -    MD0080PA00X+139705Y+104719X0160Y         S0      
317PVDD11_S3_P0     VIA   -    MD0080PA00X+141000Y+105038X0160Y         S0      
317PVDD11_S3_P0     VIA   -    MD0080PA00X+141186Y+104719X0160Y         S0      
317PVDD11_S3_P0     VIA   -    MD0080PA00X+143588Y+105038X0160Y         S0      
317PVDD11_S3_P0     VIA   -    MD0080PA00X+142663Y+104719X0160Y         S0      
317PVDD11_S3_P0     VIA   -    MD0080PA00X+143404Y+104719X0160Y         S0      
317PVDD11_S3_P0     VIA   -    MD0080PA00X+143405Y+104082X0160Y         S0      
317PVDD11_S3_P0     VIA   -    MD0080PA00X+145069Y+105038X0160Y         S0      
317PVDD11_S3_P0     VIA   -    MD0080PA00X+144884Y+104719X0160Y         S0      
317PVDD11_S3_P0     VIA   -    MD0080PA00X+144144Y+104719X0160Y         S0      
317PVDD11_S3_P0     VIA   -    MD0080PA00X+144885Y+104082X0160Y         S0      
317PVDD11_S3_P0     VIA   -    MD0080PA00X+144145Y+104082X0160Y         S0      
317PVDD11_S3_P0     VIA   -    MD0080PA00X+146549Y+105038X0160Y         S0      
317PVDD11_S3_P0     VIA   -    MD0080PA00X+145624Y+104719X0160Y         S0      
317PVDD11_S3_P0     VIA   -    MD0080PA00X+146364Y+104719X0160Y         S0      
317PVDD11_S3_P0     VIA   -    MD0080PA00X+145624Y+104081X0160Y         S0      
317PVDD11_S3_P0     VIA   -    MD0080PA00X+146364Y+104081X0160Y         S0      
317PVDD11_S3_P0     VIA   -    MD0080PA00X+146549Y+104400X0160Y         S0      
317PVDD11_S3_P0     VIA   -    MD0080PA00X+146549Y+103762X0160Y         S0      
317PVDD11_S3_P0     VIA   -    MD0080PA00X+145809Y+104400X0160Y         S0      
317PVDD11_S3_P0     VIA   -    MD0080PA00X+145809Y+103762X0160Y         S0      
317PVDD11_S3_P0     VIA   -    MD0080PA00X+147289Y+104400X0160Y         S0      
317PVDD11_S3_P0     VIA   -    MD0080PA00X+147289Y+103762X0160Y         S0      
317PVDD11_S3_P0     VIA   -    MD0080PA00X+147104Y+104081X0160Y         S0      
317PVDD11_S3_P0     VIA   -    MD0080PA00X+147844Y+104081X0160Y         S0      
317PVDD11_S3_P0     VIA   -    MD0080PA00X+147844Y+106632X0160Y         S0      
317PVDD11_S3_P0     VIA   -    MD0080PA00X+147844Y+105357X0160Y         S0      
317PVDD11_S3_P0     VIA   -    MD0080PA00X+147104Y+104719X0160Y         S0      
317PVDD11_S3_P0     VIA   -    MD0080PA00X+147844Y+104719X0160Y         S0      
317PVDD11_S3_P0     VIA   -    MD0080PA00X+147659Y+110140X0160Y         S0      
317PVDD11_S3_P0     VIA   -    MD0080PA00X+147844Y+109184X0160Y         S0      
317PVDD11_S3_P0     VIA   -    MD0080PA00X+147844Y+107908X0160Y         S0      
317PVDD11_S3_P0     VIA   -    MD0080PA00X+147844Y+111097X0160Y         S0      
317PVDD11_S3_P0     VIA   -    MD0080PA00X+147844Y+112372X0160Y         S0      
317PVDD11_S3_P0     VIA   -    MD0080PA00X+147844Y+113648X0160Y         S0      
317PVDD11_S3_P0     VIA   -    MD0080PA00X+149140Y+105676X0160Y         S0      
317PVDD11_S3_P0     VIA   -    MD0080PA00X+148955Y+104719X0160Y         S0      
317PVDD11_S3_P0     VIA   -    MD0080PA00X+149140Y+103762X0160Y         S0      
317PVDD11_S3_P0     VIA   -    MD0080PA00X+148955Y+106632X0160Y         S0      
317PVDD11_S3_P0     VIA   -    MD0080PA00X+148955Y+108546X0160Y         S0      
317PVDD11_S3_P0     VIA   -    MD0080PA00X+149140Y+107589X0160Y         S0      
317PVDD11_S3_P0     VIA   -    MD0080PA00X+148955Y+110459X0160Y         S0      
317PVDD11_S3_P0     VIA   -    MD0080PA00X+149140Y+109502X0160Y         S0      
317PVDD11_S3_P0     VIA   -    MD0080PA00X+149140Y+111416X0160Y         S0      
317PVDD11_S3_P0     VIA   -    MD0080PA00X+148955Y+112372X0160Y         S0      
317PVDD11_S3_P0     VIA   -    MD0080PA00X+149140Y+113329X0160Y         S0      
317PVDD11_S3_P0     VIA   -    MD0080PA00X+149140Y+115242X0160Y         S0      
317PVDD11_S3_P0     VIA   -    MD0080PA00X+148955Y+114286X0160Y         S0      
317PVDD11_S3_P0     VIA   -    MD0080PA00X+151545Y+106632X0160Y         S0      
317PVDD11_S3_P0     VIA   -    MD0080PA00X+151545Y+104719X0160Y         S0      
317PVDD11_S3_P0     VIA   -    MD0080PA00X+151730Y+105676X0160Y         S0      
317PVDD11_S3_P0     VIA   -    MD0080PA00X+151730Y+109502X0160Y         S0      
317PVDD11_S3_P0     VIA   -    MD0080PA00X+151545Y+110459X0160Y         S0      
317PVDD11_S3_P0     VIA   -    MD0080PA00X+151730Y+107589X0160Y         S0      
317PVDD11_S3_P0     VIA   -    MD0080PA00X+151545Y+108546X0160Y         S0      
317PVDD11_S3_P0     VIA   -    MD0080PA00X+151545Y+112372X0160Y         S0      
317PVDD11_S3_P0     VIA   -    MD0080PA00X+151730Y+113329X0160Y         S0      
317PVDD11_S3_P0     VIA   -    MD0080PA00X+151730Y+111416X0160Y         S0      
317PVDD11_S3_P0     VIA   -    MD0080PA00X+151730Y+115242X0160Y         S0      
317PVDD11_S3_P0     VIA   -    MD0080PA00X+151545Y+114286X0160Y         S0      
317PVDD11_S3_P0     VIA   -    MD0080PA00X+154136Y+106632X0160Y         S0      
317PVDD11_S3_P0     VIA   -    MD0080PA00X+154321Y+105676X0160Y         S0      
317PVDD11_S3_P0     VIA   -    MD0080PA00X+154321Y+107589X0160Y         S0      
317PVDD11_S3_P0     VIA   -    MD0080PA00X+154136Y+108546X0160Y         S0      
317PVDD11_S3_P0     VIA   -    MD0080PA00X+154321Y+109502X0160Y         S0      
317PVDD11_S3_P0     VIA   -    MD0080PA00X+154136Y+110459X0160Y         S0      
317PVDD11_S3_P0     VIA   -    MD0080PA00X+154136Y+112372X0160Y         S0      
317PVDD11_S3_P0     VIA   -    MD0080PA00X+154321Y+113329X0160Y         S0      
317PVDD11_S3_P0     VIA   -    MD0080PA00X+154321Y+111416X0160Y         S0      
317PVDD11_S3_P0     VIA   -    MD0080PA00X+154321Y+115242X0160Y         S0      
317PVDD11_S3_P0     VIA   -    MD0080PA00X+153951Y+115880X0160Y         S0      
317PVDD11_S3_P0     VIA   -    MD0080PA00X+154136Y+114286X0160Y         S0      
327PVDD11_S3_P0     C2132 -1          A01X+141101Y+102301X0198Y0197     S1      
327PVDD11_S3_P0     C2133 -1          A01X+144187Y+103230X0198Y0197R180 S1      
327PVDD11_S3_P0     C2137 -1   M      A18X+142999Y+103208X0198Y0197R090 S2      
327PVDD11_S3_P0     C2138 -1   M      A18X+143388Y+104076X0198Y0197     S2      
327PVDD11_S3_P0     C2142 -1   M      A18X+144888Y+104726X0198Y0197     S2      
327PVDD11_S3_P0     C2146 -1          A01X+141877Y+103208X0198Y0197R270 S1      
327PVDD11_S3_P0     C2150 -1          A01X+140007Y+103208X0198Y0197R270 S1      
327PVDD11_S3_P0     C2153 -1   M      A18X+140755Y+103208X0198Y0197R090 S2      
327PVDD11_S3_P0     C2156 -1          A01X+141129Y+103208X0198Y0197R270 S1      
327PVDD11_S3_P0     C2158 -1          A01X+141503Y+103208X0198Y0197R270 S1      
327PVDD11_S3_P0     C2160 -1          A18X+141987Y+102301X0198Y0197R180 S2      
327PVDD11_S3_P0     C2162 -1   M      A18X+138188Y+104076X0198Y0197     S2      
327PVDD11_S3_P0     C2600 -1   M      A18X+145638Y+104726X0198Y0197     S2      
327PVDD11_S3_P0     C2601 -1          A01X+140755Y+103208X0198Y0197R270 S1      
327PVDD11_S3_P0     C2602 -1   M      A18X+139688Y+104076X0198Y0197     S2      
327PVDD11_S3_P0     C2603 -1   M      A18X+137488Y+104726X0198Y0197     S2      
327PVDD11_S3_P0     C2607 -1   M      A18X+140438Y+104076X0198Y0197     S2      
327PVDD11_S3_P0     C2608 -1   M      A18X+138938Y+104076X0198Y0197     S2      
327PVDD11_S3_P0     C2609 -1   M      A18X+140381Y+103208X0198Y0197R090 S2      
327PVDD11_S3_P0     C2610 -1   M      A18X+141503Y+103208X0198Y0197R090 S2      
327PVDD11_S3_P0     C2614 -1          A01X+141101Y+101888X0198Y0197     S1      
327PVDD11_S3_P0     C2615 -1   M      A18X+140007Y+103208X0198Y0197R090 S2      
327PVDD11_S3_P0     C2616 -1          A18X+141101Y+101888X0198Y0197R180 S2      
327PVDD11_S3_P0     C2617 -1   M      A18X+141129Y+103208X0198Y0197R090 S2      
327PVDD11_S3_P0     C2621 -1          A18X+141101Y+102301X0198Y0197R180 S2      
327PVDD11_S3_P0     C2622 -1          A01X+142625Y+103208X0198Y0197R270 S1      
327PVDD11_S3_P0     C2623 -1   M      A18X+141888Y+104276X0198Y0197     S2      
327PVDD11_S3_P0     C2624 -1          A18X+143010Y+102301X0198Y0197R180 S2      
327PVDD11_S3_P0     C2627 -1          A01X+139488Y+103230X0198Y0197R180 S1      
327PVDD11_S3_P0     C2628 -1   M      A18X+147038Y+104076X0198Y0197     S2      
327PVDD11_S3_P0     C2629 -1   M      A18X+138238Y+104726X0198Y0197     S2      
327PVDD11_S3_P0     C2630 -1   M      A18X+145588Y+104076X0198Y0197     S2      
327PVDD11_S3_P0     C2633 -1          A01X+143373Y+103208X0198Y0197R270 S1      
327PVDD11_S3_P0     C2634 -1   M      A18X+142625Y+103208X0198Y0197R090 S2      
327PVDD11_S3_P0     C2635 -1          A01X+142251Y+103208X0198Y0197R270 S1      
327PVDD11_S3_P0     C2636 -1   M      A18X+141877Y+103208X0198Y0197R090 S2      
327PVDD11_S3_P0     C2639 -1   M      A18X+147088Y+104726X0198Y0197     S2      
327PVDD11_S3_P0     C2640 -1   M      A18X+144138Y+104726X0198Y0197     S2      
327PVDD11_S3_P0     C2641 -1          A01X+142999Y+103208X0198Y0197R270 S1      
327PVDD11_S3_P0     C2642 -1          A01X+140381Y+103208X0198Y0197R270 S1      
327PVDD11_S3_P0     C2645 -1   M      A18X+144888Y+104076X0198Y0197     S2      
327PVDD11_S3_P0     C2646 -1   M      A18X+142638Y+104726X0198Y0197     S2      
327PVDD11_S3_P0     C2647 -1   M      A18X+145781Y+103726X0198Y0197     S2      
327PVDD11_S3_P0     C2648 -1   M      A18X+141888Y+103876X0198Y0197     S2      
327PVDD11_S3_P0     C2651 -1   M      A18X+146338Y+104076X0198Y0197     S2      
327PVDD11_S3_P0     C2652 -1   M      A18X+146338Y+104726X0198Y0197     S2      
327PVDD11_S3_P0     C2653 -1   M      A18X+144138Y+104076X0198Y0197     S2      
327PVDD11_S3_P0     C2656 -1   M      A18X+143388Y+104726X0198Y0197     S2      
327PVDD11_S3_P0     C2657 -1          A01X+141987Y+102301X0198Y0197     S1      
327PVDD11_S3_P0     C2658 -1   M      A18X+142251Y+103208X0198Y0197R090 S2      
327PVDD11_S3_P0     C3890 -1   M      A18X+140438Y+104726X0198Y0197     S2      
327PVDD11_S3_P0     C3891 -1   M      A18X+143373Y+103208X0198Y0197R090 S2      
327PVDD11_S3_P0     C3892 -1   M      A18X+144187Y+103230X0198Y0197     S2      
327PVDD11_S3_P0     C3893 -1          A01X+143010Y+102301X0198Y0197     S1      
327PVDD11_S3_P0     C3932 -1   M      A18X+139688Y+104726X0198Y0197     S2      
327PVDD11_S3_P0     C3933 -1   M      A18X+138938Y+104726X0198Y0197     S2      
327PVDD11_S3_P0     C3934 -1   M      A18X+141138Y+104726X0198Y0197     S2      
327PVDD11_S3_P0     C3935 -1   M      A18X+139488Y+103230X0198Y0197     S2      
327PVDD11_S3_P0     U25   -BJ18       A01X+148956Y+103658X0177Y    R180 S1      
327PVDD11_S3_P0     U25   -BJ23       A01X+147106Y+103658X0177Y    R180 S1      
327PVDD11_S3_P0     U25   -BJ25       A01X+146365Y+103658X0177Y    R180 S1      
327PVDD11_S3_P0     U25   -BJ27       A01X+145625Y+103658X0177Y    R180 S1      
327PVDD11_S3_P0     U25   -BK22       A01X+147661Y+103976X0177Y    R180 S1      
327PVDD11_S3_P0     U25   -BK24       A01X+146920Y+103976X0177Y    R180 S1      
327PVDD11_S3_P0     U25   -BK26       A01X+146180Y+103976X0177Y    R180 S1      
327PVDD11_S3_P0     U25   -BK28       A01X+145440Y+103976X0177Y    R180 S1      
327PVDD11_S3_P0     U25   -BK49       A01X+137668Y+103976X0177Y    R180 S1      
327PVDD11_S3_P0     U25   -BL23       A01X+147106Y+104295X0177Y    R180 S1      
327PVDD11_S3_P0     U25   -BL25       A01X+146365Y+104295X0177Y    R180 S1      
327PVDD11_S3_P0     U25   -BL27       A01X+145625Y+104295X0177Y    R180 S1      
327PVDD11_S3_P0     U25   -BL48       A01X+138224Y+104295X0177Y    R180 S1      
327PVDD11_S3_P0     U25   -BM12       A01X+151361Y+104614X0177Y    R180 S1      
327PVDD11_S3_P0     U25   -BM19       A01X+148771Y+104614X0177Y    R180 S1      
327PVDD11_S3_P0     U25   -BM22       A01X+147661Y+104614X0177Y    R180 S1      
327PVDD11_S3_P0     U25   -BM24       A01X+146920Y+104614X0177Y    R180 S1      
327PVDD11_S3_P0     U25   -BM26       A01X+146180Y+104614X0177Y    R180 S1      
327PVDD11_S3_P0     U25   -BM28       A01X+145440Y+104614X0177Y    R180 S1      
327PVDD11_S3_P0     U25   -BM30       A01X+144700Y+104614X0177Y    R180 S1      
327PVDD11_S3_P0     U25   -BM32       A01X+143960Y+104614X0177Y    R180 S1      
327PVDD11_S3_P0     U25   -BM34       A01X+143220Y+104614X0177Y    R180 S1      
327PVDD11_S3_P0     U25   -BM36       A01X+142480Y+104614X0177Y    R180 S1      
327PVDD11_S3_P0     U25   -BM39       A01X+141369Y+104614X0177Y    R180 S1      
327PVDD11_S3_P0     U25   -BM41       A01X+140629Y+104614X0177Y    R180 S1      
327PVDD11_S3_P0     U25   -BM43       A01X+139889Y+104614X0177Y    R180 S1      
327PVDD11_S3_P0     U25   -BM45       A01X+139149Y+104614X0177Y    R180 S1      
327PVDD11_S3_P0     U25   -BM47       A01X+138409Y+104614X0177Y    R180 S1      
327PVDD11_S3_P0     U25   -BM49       A01X+137668Y+104614X0177Y    R180 S1      
327PVDD11_S3_P0     U25   -BN25       A01X+146365Y+104933X0177Y    R180 S1      
327PVDD11_S3_P0     U25   -BN29       A01X+144885Y+104933X0177Y    R180 S1      
327PVDD11_S3_P0     U25   -BN33       A01X+143405Y+104933X0177Y    R180 S1      
327PVDD11_S3_P0     U25   -BN40       A01X+141184Y+104933X0177Y    R180 S1      
327PVDD11_S3_P0     U25   -BN44       A01X+139704Y+104933X0177Y    R180 S1      
327PVDD11_S3_P0     U25   -BN48       A01X+138224Y+104933X0177Y    R180 S1      
327PVDD11_S3_P0     U25   -BP22       A01X+147661Y+105252X0177Y    R180 S1      
327PVDD11_S3_P0     U25   -BR4        A01X+154137Y+105571X0177Y    R180 S1      
327PVDD11_S3_P0     U25   -BR11       A01X+151546Y+105571X0177Y    R180 S1      
327PVDD11_S3_P0     U25   -BR18       A01X+148956Y+105571X0177Y    R180 S1      
327PVDD11_S3_P0     U25   -BV5        A01X+153952Y+106528X0177Y    R180 S1      
327PVDD11_S3_P0     U25   -BV12       A01X+151361Y+106528X0177Y    R180 S1      
327PVDD11_S3_P0     U25   -BV19       A01X+148771Y+106528X0177Y    R180 S1      
327PVDD11_S3_P0     U25   -BV22       A01X+147661Y+106528X0177Y    R180 S1      
327PVDD11_S3_P0     U25   -CA4        A01X+154137Y+107484X0177Y    R180 S1      
327PVDD11_S3_P0     U25   -CA11       A01X+151546Y+107484X0177Y    R180 S1      
327PVDD11_S3_P0     U25   -CA18       A01X+148956Y+107484X0177Y    R180 S1      
327PVDD11_S3_P0     U25   -CB22       A01X+147661Y+107803X0177Y    R180 S1      
327PVDD11_S3_P0     U25   -CD5        A01X+153952Y+108441X0177Y    R180 S1      
327PVDD11_S3_P0     U25   -CD12       A01X+151361Y+108441X0177Y    R180 S1      
327PVDD11_S3_P0     U25   -CD19       A01X+148771Y+108441X0177Y    R180 S1      
327PVDD11_S3_P0     U25   -CF22       A01X+147661Y+109079X0177Y    R180 S1      
327PVDD11_S3_P0     U25   -CG4        A01X+154137Y+109398X0177Y    R180 S1      
327PVDD11_S3_P0     U25   -CG11       A01X+151546Y+109398X0177Y    R180 S1      
327PVDD11_S3_P0     U25   -CG18       A01X+148956Y+109398X0177Y    R180 S1      
327PVDD11_S3_P0     U25   -CJ22       A01X+147476Y+110036X0177Y    R180 S1      
327PVDD11_S3_P0     U25   -CK5        A01X+153952Y+110354X0177Y    R180 S1      
327PVDD11_S3_P0     U25   -CK12       A01X+151361Y+110354X0177Y    R180 S1      
327PVDD11_S3_P0     U25   -CK19       A01X+148771Y+110354X0177Y    R180 S1      
327PVDD11_S3_P0     U25   -CM22       A01X+147661Y+110992X0177Y    R180 S1      
327PVDD11_S3_P0     U25   -CN4        A01X+154137Y+111311X0177Y    R180 S1      
327PVDD11_S3_P0     U25   -CN11       A01X+151546Y+111311X0177Y    R180 S1      
327PVDD11_S3_P0     U25   -CN18       A01X+148956Y+111311X0177Y    R180 S1      
327PVDD11_S3_P0     U25   -CT5        A01X+153952Y+112268X0177Y    R180 S1      
327PVDD11_S3_P0     U25   -CT12       A01X+151361Y+112268X0177Y    R180 S1      
327PVDD11_S3_P0     U25   -CT19       A01X+148771Y+112268X0177Y    R180 S1      
327PVDD11_S3_P0     U25   -CT22       A01X+147661Y+112268X0177Y    R180 S1      
327PVDD11_S3_P0     U25   -CW4        A01X+154137Y+113224X0177Y    R180 S1      
327PVDD11_S3_P0     U25   -CW11       A01X+151546Y+113224X0177Y    R180 S1      
327PVDD11_S3_P0     U25   -CW18       A01X+148956Y+113224X0177Y    R180 S1      
327PVDD11_S3_P0     U25   -CY22       A01X+147661Y+113543X0177Y    R180 S1      
327PVDD11_S3_P0     U25   -DB5        A01X+153952Y+114181X0177Y    R180 S1      
327PVDD11_S3_P0     U25   -DB12       A01X+151361Y+114181X0177Y    R180 S1      
327PVDD11_S3_P0     U25   -DB19       A01X+148771Y+114181X0177Y    R180 S1      
327PVDD11_S3_P0     U25   -DE4        A01X+154137Y+115138X0177Y    R180 S1      
327PVDD11_S3_P0     U25   -DE11       A01X+151546Y+115138X0177Y    R180 S1      
327PVDD11_S3_P0     U25   -DE18       A01X+148956Y+115138X0177Y    R180 S1      
327PVDD11_S3_P0     U25   -DG5        A01X+153767Y+115776X0177Y    R180 S1      
317PVDD11_S3_P0     VIA   -    MD0100PA00X+173270Y+131301X0200Y         S0      
317PVDD11_S3_P0     VIA   -    MD0100PA00X+173270Y+131901X0200Y         S0      
317PVDD11_S3_P0     VIA   -    MD0100PA00X+173270Y+132201X0200Y         S0      
317PVDD11_S3_P0     VIA   -    MD0100PA00X+173270Y+131601X0200Y         S0      
317PVDD11_S3_P0     VIA   -    MD0100PA00X+171871Y+134413X0200Y         S0      
317PVDD11_S3_P0     VIA   -    MD0100PA00X+171871Y+134163X0200Y         S0      
317PVDD11_S3_P0     VIA   -    MD0100PA00X+171018Y+134459X0200Y         S0      
317PVDD11_S3_P0     VIA   -    MD0100PA00X+171018Y+134209X0200Y         S0      
317PVDD11_S3_P0     VIA   -    MD0100PA00X+169907Y+131374X0200Y         S0      
327PVDD11_S3_P0     VIA   -           A18X+167097Y+132284X0260Y    R090 S2      
327PVDD11_S3_P0     VIA   -           A18X+169507Y+132274X0260Y    R090 S2      
327PVDD11_S3_P0     VIA   -           A18X+164707Y+132314X0260Y    R090 S2      
317PVDD11_S3_P0     VIA   -    MD0100PA00X+181153Y+128167X0200Y    R180 S0      
317PVDD11_S3_P0     VIA   -    MD0100PA00X+179290Y+068354X0200Y         S0      
327PVDD11_S3_P0     R5017 -1          A01X+174265Y+066822X0198Y0197R180 S1      
317PVDD11_S3_P0     VIA   -    MD0100PA00X+174548Y+066822X0200Y         S0      
327PVDD11_S3_P0     R5016 -1          A01X+174265Y+066422X0198Y0197R180 S1      
317PVDD11_S3_P0     VIA   -    MD0100PA00X+170976Y+067022X0200Y         S0      
327PVDD11_S3_P0     PC801 -1          A01X+172767Y+131825X0630Y1190     S1      
327PVDD11_S3_P0     PC229 -1          A01X+170387Y+131825X0630Y1190     S1      
327PVDD11_S3_P0     PC230 -1          A01X+167987Y+131825X0630Y1190     S1      
327PVDD11_S3_P0     PC228 -1          A01X+165587Y+131825X0630Y1190     S1      
327PVDD11_S3_P0     PC222 -1          A01X+164180Y+131114X0198Y0197R270 S1      
327PVDD11_S3_P0     PR114 -1          A01X+163791Y+131187X0198Y0197R180 S1      
327PVDD11_S3_P0     PC800 -1          A18X+172797Y+134038X0950Y1110R270 S2      
327PVDD11_S3_P0     PC227_-1          A18X+171420Y+134265X0400Y0500R090 S2      
327PVDD11_S3_P0     PC226 -1          A18X+170047Y+134176X0950Y1110R270 S2      
327PVDD11_S3_P0     PC224_-1          A18X+168318Y+134299X0400Y0500R090 S2      
327PVDD11_S3_P0     PC223 -1          A18X+166799Y+134158X0950Y1110R270 S2      
327PVDD11_S3_P0     PC221_-1          A18X+165418Y+134299X0400Y0500R090 S2      
327PVDD11_S3_P0     PC225_-1          A18X+164618Y+134299X0400Y0500R090 S2      
327PVDD11_S3_P0     PR414 -1          A18X+168015Y+131113X0198Y0197R090 S2      
317PVDD11_S3_P0     VIA   -    MD0100PA00X+144211Y+103220X0190Y    R270 S0      
317PVDD11_S3_P0     VIA   -    MD0100PA00X+141117Y+103243X0190Y    R180 S0      
317PVDD11_S3_P0     VIA   -    MD0100PA00X+139995Y+103243X0190Y    R180 S0      
317PVDD11_S3_P0     VIA   -    MD0100PA00X+139506Y+103220X0190Y    R180 S0      
317PVDD11_S3_P0     VIA   -    MD0100PA00X+140369Y+103243X0190Y    R180 S0      
317PVDD11_S3_P0     VIA   -    MD0100PA00X+140743Y+103243X0190Y    R180 S0      
317PVDD11_S3_P0     VIA   -    MD0100PA00X+142995Y+102301X0190Y    R180 S0      
317PVDD11_S3_P0     VIA   -    MD0100PA00X+141086Y+101888X0190Y    R180 S0      
317PVDD11_S3_P0     VIA   -    MD0100PA00X+141972Y+102301X0190Y    R180 S0      
317PVDD11_S3_P0     VIA   -    MD0100PA00X+141086Y+102301X0190Y    R180 S0      
317PVDD11_S3_P0     VIA   -    MD0100PA00X+165488Y+139723X0200Y    R180 S0      
317PVDD11_S3_P0     VIA   -    MD0100PA00X+165868Y+134449X0200Y         S0      
327PVDD11_S3_P0     PR137 -2          A18X+165348Y+139441X0198Y0197R270 S2      
317PVDD11_S3_P0     VIA   -    MD0100PA00X+165018Y+134449X0200Y         S0      
317PVDD11_S3_P0     VIA   -    MD0100PA00X+164168Y+134449X0200Y         S0      
317PVDD11_S3_P0     VIA   -    MD0100PA00X+171740Y+133156X0200Y         S0      
317PVDD11_S3_P0     VIA   -    MD0100PA00X+171740Y+133406X0200Y         S0      
317PVDD11_S3_P0     VIA   -    MD0100PA00X+171992Y+133406X0200Y         S0      
317PVDD11_S3_P0     VIA   -    MD0100PA00X+171992Y+133156X0200Y         S0      
317PVDD11_S3_P0     VIA   -    MD0100PA00X+171054Y+133162X0200Y         S0      
317PVDD11_S3_P0     VIA   -    MD0100PA00X+171054Y+133412X0200Y         S0      
317PVDD11_S3_P0     VIA   -    MD0100PA00X+171740Y+133656X0200Y         S0      
317PVDD11_S3_P0     VIA   -    MD0100PA00X+171992Y+133656X0200Y         S0      
317PVDD11_S3_P0     VIA   -    MD0100PA00X+171740Y+133906X0200Y         S0      
317PVDD11_S3_P0     VIA   -    MD0100PA00X+171992Y+133906X0200Y         S0      
317PVDD11_S3_P0     VIA   -    MD0100PA00X+171054Y+133912X0200Y         S0      
317PVDD11_S3_P0     VIA   -    MD0100PA00X+171054Y+133662X0200Y         S0      
317PVDD11_S3_P0     VIA   -    MD0100PA00X+169070Y+133907X0200Y         S0      
317PVDD11_S3_P0     VIA   -    MD0100PA00X+167903Y+134423X0200Y         S0      
317PVDD11_S3_P0     VIA   -    MD0100PA00X+168723Y+134403X0200Y         S0      
317PVDD11_S3_P0     VIA   -    MD0100PA00X+168723Y+134153X0200Y         S0      
317PVDD11_S3_P0     VIA   -    MD0100PA00X+167903Y+134173X0200Y         S0      
317PVDD11_S3_P0     VIA   -    MD0100PA00X+169070Y+133157X0200Y         S0      
317PVDD11_S3_P0     VIA   -    MD0100PA00X+169070Y+133407X0200Y         S0      
317PVDD11_S3_P0     VIA   -    MD0100PA00X+169070Y+133657X0200Y         S0      
317PVDD11_S3_P0     VIA   -    MD0100PA00X+167775Y+133402X0200Y         S0      
317PVDD11_S3_P0     VIA   -    MD0100PA00X+167775Y+133152X0200Y         S0      
317PVDD11_S3_P0     VIA   -    MD0100PA00X+167775Y+133652X0200Y         S0      
317PVDD11_S3_P0     VIA   -    MD0100PA00X+167775Y+133902X0200Y         S0      
317PVDD11_S3_P0     VIA   -    MD0100PA00X+165802Y+133397X0200Y         S0      
317PVDD11_S3_P0     VIA   -    MD0100PA00X+165802Y+133147X0200Y         S0      
317PVDD11_S3_P0     VIA   -    MD0100PA00X+165802Y+133897X0200Y         S0      
317PVDD11_S3_P0     VIA   -    MD0100PA00X+165802Y+133647X0200Y         S0      
317PVDD11_S3_P0     VIA   -    MD0100PA00X+165828Y+134189X0200Y         S0      
317PVDD11_S3_P0     VIA   -    MD0100PA00X+165018Y+134149X0200Y         S0      
317PVDD11_S3_P0     VIA   -    MD0100PA00X+164168Y+134149X0200Y         S0      
317PVDD11_S3_P0     VIA   -    MD0100PA00X+170867Y+131674X0200Y         S0      
317PVDD11_S3_P0     VIA   -    MD0100PA00X+171740Y+132906X0200Y         S0      
317PVDD11_S3_P0     VIA   -    MD0100PA00X+171992Y+132906X0200Y         S0      
317PVDD11_S3_P0     VIA   -    MD0100PA00X+171740Y+132656X0200Y         S0      
317PVDD11_S3_P0     VIA   -    MD0100PA00X+171992Y+132656X0200Y         S0      
317PVDD11_S3_P0     VIA   -    MD0100PA00X+172267Y+132224X0200Y         S0      
317PVDD11_S3_P0     VIA   -    MD0100PA00X+172267Y+131924X0200Y         S0      
317PVDD11_S3_P0     VIA   -    MD0100PA00X+171054Y+132662X0200Y         S0      
317PVDD11_S3_P0     VIA   -    MD0100PA00X+170802Y+132662X0200Y         S0      
317PVDD11_S3_P0     VIA   -    MD0100PA00X+171054Y+132912X0200Y         S0      
317PVDD11_S3_P0     VIA   -    MD0100PA00X+170867Y+131974X0200Y         S0      
317PVDD11_S3_P0     VIA   -    MD0100PA00X+170867Y+132274X0200Y         S0      
317PVDD11_S3_P0     VIA   -    MD0100PA00X+172267Y+131624X0200Y         S0      
317PVDD11_S3_P0     VIA   -    MD0100PA00X+169907Y+131674X0200Y         S0      
317PVDD11_S3_P0     VIA   -    MD0100PA00X+169907Y+131974X0200Y         S0      
317PVDD11_S3_P0     VIA   -    MD0100PA00X+169907Y+132274X0200Y         S0      
317PVDD11_S3_P0     VIA   -    MD0100PA00X+169322Y+132657X0200Y         S0      
317PVDD11_S3_P0     VIA   -    MD0100PA00X+168766Y+139733X0200Y    R180 S0      
317PVDD11_S3_P0     VIA   -    MD0100PA00X+169342Y+133927X0200Y         S0      
317PVDD11_S3_P0     VIA   -    MD0100PA00X+169342Y+133677X0200Y         S0      
317PVDD11_S3_P0     VIA   -    MD0100PA00X+170538Y+133218X0200Y         S0      
317PVDD11_S3_P0     VIA   -    MD0100PA00X+169605Y+132968X0200Y         S0      
317PVDD11_S3_P0     VIA   -    MD0100PA00X+169605Y+133218X0200Y         S0      
317PVDD11_S3_P0     VIA   -    MD0100PA00X+170538Y+132968X0200Y         S0      
317PVDD11_S3_P0     VIA   -    MD0100PA00X+169605Y+133468X0200Y         S0      
317PVDD11_S3_P0     VIA   -    MD0100PA00X+170538Y+133468X0200Y         S0      
317PVDD11_S3_P0     VIA   -    MD0100PA00X+169342Y+133177X0200Y         S0      
317PVDD11_S3_P0     VIA   -    MD0100PA00X+169342Y+133427X0200Y         S0      
317PVDD11_S3_P0     VIA   -    MD0100PA00X+169342Y+132927X0200Y         S0      
317PVDD11_S3_P0     VIA   -    MD0100PA00X+170792Y+133682X0200Y         S0      
317PVDD11_S3_P0     VIA   -    MD0100PA00X+170792Y+133932X0200Y         S0      
317PVDD11_S3_P0     VIA   -    MD0100PA00X+170792Y+133182X0200Y         S0      
317PVDD11_S3_P0     VIA   -    MD0100PA00X+170792Y+133432X0200Y         S0      
317PVDD11_S3_P0     VIA   -    MD0100PA00X+170792Y+132932X0200Y         S0      
327PVDD11_S3_P0     PL22  -2   M      A01X+170067Y+133467X1300Y1660R270 S1      
327PVDD11_S3_P0     PR138 -2          A18X+168626Y+139451X0198Y0197R270 S2      
317PVDD11_S3_P0     VIA   -    MD0100PA00X+170538Y+132658X0200Y         S0      
317PVDD11_S3_P0     VIA   -    MD0100PA00X+169605Y+132658X0200Y         S0      
317PVDD11_S3_P0     VIA   -    MD0100PA00X+168467Y+131684X0200Y         S0      
317PVDD11_S3_P0     VIA   -    MD0100PA00X+168467Y+131984X0200Y         S0      
317PVDD11_S3_P0     VIA   -    MD0100PA00X+168467Y+132284X0200Y         S0      
317PVDD11_S3_P0     VIA   -    MD0100PA00X+169070Y+132657X0200Y         S0      
317PVDD11_S3_P0     VIA   -    MD0100PA00X+169070Y+132907X0200Y         S0      
317PVDD11_S3_P0     VIA   -    MD0100PA00X+167775Y+132902X0200Y         S0      
317PVDD11_S3_P0     VIA   -    MD0100PA00X+167775Y+132652X0200Y         S0      
317PVDD11_S3_P0     VIA   -    MD0100PA00X+167497Y+132284X0200Y         S0      
317PVDD11_S3_P0     VIA   -    MD0100PA00X+167497Y+131984X0200Y         S0      
317PVDD11_S3_P0     VIA   -    MD0100PA00X+166344Y+132653X0200Y         S0      
317PVDD11_S3_P0     VIA   -    MD0100PA00X+167262Y+132648X0200Y         S0      
317PVDD11_S3_P0     VIA   -    MD0100PA00X+167497Y+131684X0200Y         S0      
317PVDD11_S3_P0     VIA   -    MD0100PA00X+167523Y+132652X0200Y         S0      
317PVDD11_S3_P0     VIA   -    MD0100PA00X+165812Y+132647X0200Y         S0      
317PVDD11_S3_P0     VIA   -    MD0100PA00X+165802Y+132897X0200Y         S0      
317PVDD11_S3_P0     VIA   -    MD0100PA00X+166057Y+131684X0200Y         S0      
317PVDD11_S3_P0     VIA   -    MD0100PA00X+166064Y+132647X0200Y         S0      
317PVDD11_S3_P0     VIA   -    MD0100PA00X+166057Y+131984X0200Y         S0      
317PVDD11_S3_P0     VIA   -    MD0100PA00X+166057Y+132284X0200Y         S0      
317PVDD11_S3_P0     VIA   -    MD0100PA00X+165107Y+131714X0200Y         S0      
317PVDD11_S3_P0     VIA   -    MD0100PA00X+165107Y+132014X0200Y         S0      
317PVDD11_S3_P0     VIA   -    MD0100PA00X+165107Y+132314X0200Y         S0      
317PVDD11_S3_P0     VIA   -    MD0100PA00X+170867Y+131374X0200Y         S0      
317PVDD11_S3_P0     VIA   -    MD0100PA00X+172267Y+131324X0200Y         S0      
317PVDD11_S3_P0     VIA   -    MD0100PA00X+168467Y+131384X0200Y         S0      
317PVDD11_S3_P0     VIA   -    MD0100PA00X+167497Y+131384X0200Y         S0      
317PVDD11_S3_P0     VIA   -    MD0100PA00X+166057Y+131384X0200Y         S0      
317PVDD11_S3_P0     VIA   -    MD0100PA00X+165107Y+131414X0200Y         S0      
317PVDD11_S3_P0     VIA   -    MD0100PA00X+153930Y+117576X0200Y         S0      
317PVDD11_S3_P0     VIA   -    MD0100PA00X+153730Y+117826X0200Y         S0      
317PVDD11_S3_P0     VIA   -    MD0100PA00X+154080Y+117826X0200Y         S0      
317PVDD11_S3_P0     VIA   -    MD0100PA00X+166064Y+133667X0200Y         S0      
317PVDD11_S3_P0     VIA   -    MD0100PA00X+166064Y+133917X0200Y         S0      
317PVDD11_S3_P0     VIA   -    MD0100PA00X+166064Y+133417X0200Y         S0      
317PVDD11_S3_P0     VIA   -    MD0100PA00X+166064Y+133167X0200Y         S0      
317PVDD11_S3_P0     VIA   -    MD0100PA00X+166064Y+132917X0200Y         S0      
317PVDD11_S3_P0     VIA   -    MD0100PA00X+167513Y+132922X0200Y         S0      
317PVDD11_S3_P0     VIA   -    MD0100PA00X+167513Y+133922X0200Y         S0      
317PVDD11_S3_P0     VIA   -    MD0100PA00X+167513Y+133672X0200Y         S0      
317PVDD11_S3_P0     VIA   -    MD0100PA00X+167513Y+133422X0200Y         S0      
317PVDD11_S3_P0     VIA   -    MD0100PA00X+167513Y+133172X0200Y         S0      
317PVDD11_S3_P0     VIA   -    MD0100PA00X+167262Y+132968X0200Y         S0      
317PVDD11_S3_P0     VIA   -    MD0100PA00X+166344Y+133223X0200Y         S0      
317PVDD11_S3_P0     VIA   -    MD0100PA00X+167262Y+133218X0200Y         S0      
317PVDD11_S3_P0     VIA   -    MD0100PA00X+166344Y+132973X0200Y         S0      
317PVDD11_S3_P0     VIA   -    MD0100PA00X+167262Y+133468X0200Y         S0      
317PVDD11_S3_P0     VIA   -    MD0100PA00X+166344Y+133473X0200Y         S0      
327PVDD11_S3_P0     PL23  -2   M      A01X+166789Y+133457X1300Y1660R270 S1      
317PVDD11_S3_P0     VIA   -    MD0100PA00X+142987Y+103243X0190Y    R180 S0      
317PVDD11_S3_P0     VIA   -    MD0100PA00X+143361Y+103243X0190Y    R180 S0      
317PVDD11_S3_P0     VIA   -    MD0100PA00X+142613Y+103243X0190Y    R180 S0      
317PVDD11_S3_P0     VIA   -    MD0100PA00X+141865Y+103243X0190Y    R180 S0      
317PVDD11_S3_P0     VIA   -    MD0100PA00X+141491Y+103243X0190Y    R180 S0      
317PVDD11_S3_P0     VIA   -    MD0100PA00X+141903Y+104276X0190Y         S0      
317PVDD11_S3_P0     VIA   -    MD0100PA00X+141903Y+103876X0190Y         S0      
317PVDD11_S3_P0     VIA   -    MD0100PA00X+142239Y+103243X0190Y    R180 S0      
327PVDD11_S3_P0     R425  -1          A01X+126608Y+076500X0198Y0197R180 S1      
327PVDD11_S3_P0     R423  -1          A01X+125592Y+076500X0198Y0197     S1      
327PVDD11_S3_P0     R421  -1          A18X+149318Y+080591X0198Y0197R270 S2      
317PVDD11_S3_P0     VIA   -    MD0100PA00X+132664Y+065680X0200Y         S0      
327PVDD11_S3_P0     R5006 -1   M      A01X+116896Y+058060X0198Y0197     S1      
327PVDD11_S3_P0     R5007 -1          A01X+116902Y+058462X0198Y0197     S1      
317PVDD11_S3_P0     VIA   -    MD0100PA00X+116613Y+058060X0200Y         S0      
327PVDD11_S3_P0     R5014 -1   M      A01X+120269Y+058244X0198Y0197R180 S1      
327PVDD11_S3_P0     R5015 -1          A01X+120269Y+058744X0198Y0197R180 S1      
317PVDD11_S3_P0     VIA   -    MD0100PA00X+120590Y+058244X0200Y         S0      
317PVDD11_S3_P0     VIA   -    MD0100PA00X+141934Y+053396X0200Y         S0      
327PVDD11_S3_P0     R5008 -1   M      A01X+170976Y+066224X0198Y0197     S1      
327PVDD11_S3_P0     R5009 -1   M      A01X+170976Y+066624X0198Y0197     S1      
317PVDD11_S3_P0     VIA   -    MD0100PA00X+160092Y+052169X0200Y         S0      
317PVDD11_S3_P0     VIA   -    MD0100PA00X+116603Y+066901X0200Y         S0      
317PVDD11_S3_P0     VIA   -    MD0100PA00X+122837Y+068850X0200Y         S0      
317PVDD11_S3_P0     VIA   -    MD0100PA00X+150150Y+079995X0200Y    R180 S0      
317PVDD11_S3_P0     VIA   -    MD0100PA00X+153997Y+080732X0200Y         S0      
327PVDD11_S3_P0     R6083 -1          A18X+154345Y+079718X0198Y0197     S2      
327PVDD11_S3_P0     R6084 -1   M      A18X+154345Y+080118X0198Y0197     S2      
317PVDD11_S3_P0     VIA   -    MD0100PA00X+123140Y+076967X0200Y    R180 S0      
327PVDD11_S3_P0     R6081 -1          A18X+122993Y+077731X0198Y0197R270 S2      
327PVDD11_S3_P0     R6082 -1   M      A18X+122593Y+077731X0198Y0197R270 S2      
327PVDD11_S3_P0     R420  -1          A18X+150400Y+080591X0198Y0197R270 S2      
317PVDD11_S3_P0     VIA   -    MD0100PA00X+097653Y+080854X0200Y         S0      
317PVDD11_S3_P0     VIA   -    MD0100PA00X+094000Y+098650X0200Y         S0      
327PVDD11_S3_P0     R363  -1          A18X+093708Y+098650X0198Y0197     S2      
317PVDD11_S3_P0     VIA   -    MD0100PA00X+094000Y+097350X0200Y         S0      
327PVDD11_S3_P0     R360  -1          A18X+093708Y+097350X0198Y0197     S2      
327PVDD11_S3_P0     R290  -1          A18X+090242Y+085300X0198Y0197R180 S2      
317PVDD11_S3_P0     VIA   -    MD0100PA00X+089950Y+085300X0200Y         S0      
317PVDD11_S3_P0     VIA   -    MD0100PA00X+091850Y+086008X0200Y         S0      
327PVDD11_S3_P0     C3    -1   M      A18X+091550Y+086008X0198Y0197R090 S2      
327PVDD11_S3_P0     U2    -1          A18X+091221Y+086956X0240Y0460R180 S2      
327PVDD11_S3_P0     R322  -1          A18X+091408Y+085300X0198Y0197     S2      
317PVDD11_S3_P0     VIA   -    MD0100PA00X+091700Y+085300X0200Y         S0      
317PVDD11_S3_P0     VIA   -    MD0100PA00X+097653Y+080604X0200Y         S0      
317PVDD11_S3_P0     VIA   -    MD0100PA00X+097653Y+080354X0200Y         S0      
317PVDD11_S3_P0     VIA   -    MD0100PA00X+097653Y+080104X0200Y         S0      
327PU_U96_EN        R200  -2          A18X+096350Y+086058X0198Y0197R270 S2      
327PU_U96_EN        U96   -5          A18X+096313Y+086994X0240Y0460     S2      
327PU_U96_EN        VIA   -    M      A18X+096313Y+086400X0260Y         S2      
327PU_U5_EN         R78   -2          A18X+094800Y+085858X0198Y0197R270 S2      
327PU_U5_EN         VIA   -    M      A18X+094800Y+086200X0260Y         S2      
327PU_U5_EN         U5    -5          A18X+094406Y+086979X0240Y0460     S2      
327PU_SMERR_LED     D6    -A          A01X+134935Y+006074X0320Y0320R090 S1      
327PU_SMERR_LED     R950  -1          A01X+134384Y+006134X0198Y0197R090 S1      
327PU_SMERR_LED     VIA   -    M      A01X+134384Y+005654X0300Y         S1      
327m4037            D46   -A          A01X+137375Y+006082X0240Y0280R090 S1      
327m4037            VIA   -    M      A01X+136795Y+005654X0300Y         S1      
327m4037            R1208 -1          A01X+136795Y+006134X0198Y0197R090 S1      
327m4038            R3183 -2          A01X+040222Y+015228X0198Y0197R180 S1      
327m4038            VIA   -    M      A01X+039709Y+015174X0300Y    R180 S1      
327m4038            U217  -1          A01X+039164Y+015282X0170Y0240R090 S1      
327m4039            U8082 -1          A01X+180280Y+015183X0170Y0240R270 S1      
327m4039            VIA   -    M      A01X+179776Y+015183X0300Y    R270 S1      
327m4039            R45   -2          A01X+179296Y+015183X0198Y0197     S1      
327m4040            J90   -B9         A01X+093150Y+018648X0150Y0500R090 S1      
327m4040            R2317 -2          A01X+094137Y+018505X0198Y0197R180 S1      
317m4040            VIA   -    M      A01X+093645Y+018402X0200Y         S2      
017m4040            VIA   -    M      A18X+093645Y+018402X0260Y         S2      
017m4040                  -    MD0100PA00X+093645Y+018402                       
327m4041            VIA   -    M      A01X+059100Y+041185X0300Y         S1      
327m4041            R5377 -2          A01X+058620Y+041185X0198Y0197     S1      
327m4041            U239  -1          A01X+060324Y+040685X0170Y0240R270 S1      
327m4042            R948  -1          A01X+133193Y+006137X0198Y0197R090 S1      
327m4042            VIA   -    M      A01X+133193Y+005657X0300Y         S1      
327m4042            D5    -A          A01X+133744Y+006082X0240Y0280R090 S1      
327m4043            SW1   -4          A01X+166910Y+015176X0300Y0500R270 S1      
327m4043            VIA   -    M      A01X+166290Y+015176X0300Y    R180 S1      
327m4043            R22   -2          A01X+165810Y+015176X0198Y0197     S1      
327PRSNT_SWB_N      R8001 -1   M      A18X+038579Y+167005X0198Y0197     S2      
327PRSNT_SWB_N      R4058 -2          A01X+038299Y+167487X0198Y0197R270 S1      
317PRSNT_SWB_N      VIA   -    M      A01X+037333Y+166854X0200Y         S2      
017PRSNT_SWB_N      VIA   -    M      A18X+037333Y+166854X0260Y         S2      
017PRSNT_SWB_N            -    MD0100PA00X+037333Y+166854                       
317PRSNT_SWB_N      J112  -A7   D0142PA00X+027815Y+173421X0302Y    R180 S3      
327PRSNT_SWB_N      Q8000 -2          A18X+039419Y+167278X0170Y0200R090 S2      
327PRSNT_HDT_R_N    J54   -3          A01X+156420Y+021425X0340Y0960R090 S1      
327PRSNT_HDT_R_N    R1528 -2          A01X+158773Y+021425X0198Y0197R180 S1      
327PRSNT_HDT_R_N    VIA   -    M      A01X+158293Y+021425X0300Y    R270 S1      
327PRSNT_HDT_N      U18   -AB20       A01X+076347Y+047974X0160Y    R090 S1      
317PRSNT_HDT_N      VIA   -    MD0100PA00X+076501Y+048127X0180Y    R090 S0      
317PRSNT_HDT_N      VIA   -    MD0100PA00X+077239Y+049105X0200Y    R090 S0      
327PRSNT_HDT_N      R1527 -1          A01X+077508Y+049134X0198Y0197     S1      
317PRSNT_HDT_N      VIA   -    MD0100PA00X+098427Y+034929X0200Y         S0      
317PRSNT_HDT_N      VIA   -    MD0100PA00X+099029Y+049442X0200Y         S0      
327PRSNT_HDT_N      R1528 -1          A01X+159088Y+021425X0198Y0197R180 S1      
317PRSNT_HDT_N      VIA   -    M      A01X+160397Y+022296X0200Y    R090 S2      
017PRSNT_HDT_N      VIA   -    M      A18X+160397Y+022296X0260Y    R090 S2      
017PRSNT_HDT_N            -    MD0100PA00X+160397Y+022296                       
327PRSNT_CPU1_N     SW1   -8          A01X+166910Y+013176X0300Y0500R270 S1      
327PRSNT_CPU1_N     U26   -B66        A01X+033645Y+087748X0177Y    R180 S1      
327PRSNT_CPU1_N     R744  -1          A18X+167770Y+013176X0198Y0197R180 S2      
317PRSNT_CPU1_N     VIA   -    MD0100PA00X+167310Y+013176X0200Y    R270 S0      
317PRSNT_CPU1_N     VIA   -    MD0100PA00X+027124Y+078547X0200Y    R180 S0      
317PRSNT_CPU1_N     VIA   -    MD0100PA00X+065910Y+038102X0200Y         S0      
317PRSNT_CPU1_N     VIA   -    M      A01X+044708Y+051187X0200Y    R180 S2      
017PRSNT_CPU1_N     VIA   -    M      A18X+044708Y+051187X0260Y    R180 S2      
017PRSNT_CPU1_N           -    MD0100PA00X+044708Y+051187                       
327PRSNT_CPU0_N     SW1   -7          A01X+166910Y+013676X0300Y0500R270 S1      
317PRSNT_CPU0_N     VIA   -    M      A01X+167310Y+013676X0200Y    R270 S2      
017PRSNT_CPU0_N     VIA   -    M      A18X+167310Y+013676X0260Y    R270 S2      
017PRSNT_CPU0_N           -    MD0100PA00X+167310Y+013676                       
327PRSNT_CPU0_N     R734  -1          A18X+167770Y+013676X0198Y0197R180 S2      
317PRSNT_CPU0_N     VIA   -    MD0100PA00X+143540Y+053080X0200Y         S0      
317PRSNT_CPU0_N     VIA   -    MD0100PA00X+130325Y+065515X0200Y         S0      
327PRSNT_CPU0_N     U25   -B66        A01X+131259Y+087748X0177Y    R180 S1      
327PRSNT0_N         J41   -OB3        A01X+074749Y+006516X0150Y0570R180 S1      
327PRSNT0_N         R1801 -1          A18X+074909Y+007603X0198Y0197R180 S2      
317PRSNT0_N         VIA   -    M      A01X+074749Y+007143X0200Y         S2      
017PRSNT0_N         VIA   -    M      A18X+074749Y+007143X0260Y         S2      
017PRSNT0_N               -    MD0100PA00X+074749Y+007143                       
327TP_PECI_BMC      J41   -B27        A01X+064278Y+006516X0150Y0570R180 S1      
327TP_PECI_BMC      VIA   -           A01X+064639Y+008988X0300Y         S1      
327PD_M2_0_DEVSLP   J59   -38         A01X+066755Y+018524X0110Y0630R270 S1      
327PD_M2_0_DEVSLP   R1605 -1          A01X+064930Y+018486X0198Y0197R180 S1      
327PD_M2_0_DEVSLP   VIA   -    M      A01X+065431Y+018619X0300Y         S1      
317m4044            VIA   -    MD0080PA00X+048380Y+115562X0160Y         S0      
327m4044            U26   -DF27       A01X+048196Y+115457X0177Y    R180 S1      
327m4044            R736  -2          A01X+060020Y+127860X0198Y0197R180 S1      
327m4044            R760  -2   M      A01X+060020Y+127460X0198Y0197R180 S1      
317m4044            VIA   -    M      A01X+059694Y+127012X0200Y    R180 S2      
017m4044            VIA   -    M      A18X+059694Y+127012X0260Y    R180 S2      
017m4044                  -    MD0100PA00X+059694Y+127012                       
317m4045            VIA   -    MD0080PA00X+145994Y+115561X0160Y         S0      
327m4045            U25   -DF27       A01X+145810Y+115457X0177Y    R180 S1      
327m4045            VIA   -    M      A18X+156986Y+129366X0260Y    R180 S2      
327m4045            R742  -2          A18X+157406Y+128609X0198Y0197     S2      
327m4045            R753  -2   M      A18X+157025Y+128611X0198Y0197R180 S2      
327m4046            R778  -1          A18X+079726Y+076727X0198Y0197R180 S2      
317m4046            VIA   -    MD0100PA00X+079131Y+076687X0200Y         S2      
327m4046            J37   -148        A01X+079586Y+076687X0205Y0590R090 S1      
317m4047            VIA   -    MD0100PA00X+176745Y+076687X0200Y         S2      
327m4047            R769  -1          A18X+177340Y+076726X0198Y0197R180 S2      
327m4047            J67   -148        A01X+177200Y+076687X0205Y0590R090 S1      
327m4048            R777  -1          A18X+076756Y+076727X0198Y0197R180 S2      
317m4048            VIA   -    MD0100PA00X+076161Y+076687X0200Y         S2      
327m4048            J99   -148        A01X+076616Y+076687X0205Y0590R090 S1      
327m4049            R768  -1          A18X+174370Y+076726X0198Y0197R180 S2      
317m4049            VIA   -    MD0100PA00X+173785Y+076679X0200Y         S2      
327m4049            J20   -148        A01X+174230Y+076687X0205Y0590R090 S1      
327m4050            VIA   -    M      A18X+073437Y+076715X0260Y         S2      
317m4050            VIA   -    MD0100PA00X+073146Y+076687X0190Y         S0      
327m4050            R776  -1          A18X+073786Y+076727X0198Y0197R180 S2      
327m4050            J29   -148        A01X+073646Y+076687X0205Y0590R090 S1      
327m4051            R767  -1          A18X+171400Y+076726X0198Y0197R180 S2      
317m4051            VIA   -    MD0100PA00X+170805Y+076687X0200Y         S2      
327m4051            J68   -148        A01X+171260Y+076687X0205Y0590R090 S1      
327m4052            R775  -1          A18X+070816Y+076727X0198Y0197R180 S2      
317m4052            VIA   -    MD0100PA00X+070221Y+076687X0200Y         S2      
327m4052            J100  -148        A01X+070676Y+076687X0205Y0590R090 S1      
327m4053            VIA   -    M      A18X+168097Y+076587X0260Y         S2      
317m4053            VIA   -    MD0100PA00X+167835Y+076687X0190Y         S0      
327m4053            R766  -1          A18X+168430Y+076726X0198Y0197R180 S2      
327m4053            J18   -148        A01X+168290Y+076687X0205Y0590R090 S1      
327m4054            R774  -1          A18X+067846Y+076727X0198Y0197R180 S2      
317m4054            VIA   -    MD0100PA00X+067250Y+076687X0200Y         S2      
327m4054            J27   -148        A01X+067706Y+076687X0205Y0590R090 S1      
327m4055            VIA   -    M      A18X+165121Y+076572X0260Y         S2      
317m4055            VIA   -    MD0100PA00X+164865Y+076687X0190Y         S0      
327m4055            R765  -1          A18X+165460Y+076726X0198Y0197R180 S2      
327m4055            J69   -148        A01X+165320Y+076687X0205Y0590R090 S1      
327m4056            R37   -1          A18X+064875Y+076727X0198Y0197R180 S2      
317m4056            VIA   -    MD0100PA00X+064280Y+076687X0200Y         S2      
327m4056            J102  -148        A01X+064735Y+076687X0205Y0590R090 S1      
327m4057            R35   -1          A18X+162490Y+076726X0198Y0197R180 S2      
317m4057            VIA   -    MD0100PA00X+161720Y+076687X0200Y         S2      
327m4057            J16   -148        A01X+162350Y+076687X0205Y0590R090 S1      
317m4058            VIA   -    M      A01X+006162Y+076851X0200Y         S2      
017m4058            VIA   -    M      A18X+006162Y+076851X0260Y         S2      
017m4058                  -    MD0100PA00X+006162Y+076851                       
327m4058            R773  -1          A18X+006516Y+077383X0198Y0197R270 S2      
327m4058            J33   -148        A01X+006932Y+076687X0205Y0590R090 S1      
327m4059            R764  -1          A18X+104686Y+076726X0198Y0197R180 S2      
317m4059            VIA   -    MD0100PA00X+104092Y+076687X0200Y         S2      
327m4059            J23   -148        A01X+104546Y+076687X0205Y0590R090 S1      
317m4060            VIA   -    MD0100PA00X+009447Y+076687X0200Y         S2      
327m4060            R6    -1          A18X+010048Y+076727X0198Y0197R180 S2      
327m4060            J32   -148        A01X+009902Y+076687X0205Y0590R090 S1      
317m4061            VIA   -    MD0100PA00X+107062Y+076687X0200Y         S2      
327m4061            R5    -1          A18X+107657Y+076726X0198Y0197R180 S2      
327m4061            J21   -148        A01X+107517Y+076687X0205Y0590R090 S1      
317m4062            VIA   -    MD0100PA00X+012417Y+076687X0200Y         S2      
327m4062            R772  -1          A18X+013019Y+076727X0198Y0197R180 S2      
327m4062            J30   -148        A01X+012872Y+076687X0205Y0590R090 S1      
327m4063            R763  -1          A18X+110627Y+076726X0198Y0197R180 S2      
317m4063            VIA   -    MD0100PA00X+110032Y+076687X0200Y         S2      
327m4063            J19   -148        A01X+110487Y+076687X0205Y0590R090 S1      
317m4064            VIA   -    MD0100PA00X+015388Y+076687X0200Y         S2      
327m4064            R771  -1          A18X+015982Y+076727X0198Y0197R180 S2      
327m4064            J28   -148        A01X+015842Y+076687X0205Y0590R090 S1      
327m4065            R762  -1          A18X+113597Y+076726X0198Y0197R180 S2      
317m4065            VIA   -    MD0100PA00X+113002Y+076687X0200Y         S2      
327m4065            J17   -148        A01X+113457Y+076687X0205Y0590R090 S1      
317m4066            VIA   -    MD0100PA00X+018358Y+076687X0200Y         S2      
327m4066            R770  -1          A18X+018959Y+076727X0198Y0197R180 S2      
327m4066            J26   -148        A01X+018813Y+076687X0205Y0590R090 S1      
327m4067            R761  -1          A18X+116567Y+076726X0198Y0197R180 S2      
317m4067            VIA   -    MD0100PA00X+115972Y+076687X0200Y         S2      
327m4067            J15   -148        A01X+116427Y+076687X0205Y0590R090 S1      
327m4068            VIA   -    M      A18X+021575Y+076727X0260Y         S2      
317m4068            VIA   -    MD0100PA00X+021277Y+076687X0190Y    R180 S0      
327m4068            R36   -1          A18X+021919Y+076727X0198Y0197R180 S2      
327m4068            J24   -148        A01X+021783Y+076687X0205Y0590R090 S1      
327m4069            VIA   -    M      A18X+119171Y+076726X0260Y         S2      
317m4069            VIA   -    MD0100PA00X+118880Y+076687X0190Y         S0      
327m4069            R7    -1          A18X+119537Y+076726X0198Y0197R180 S2      
327m4069            J1    -148        A01X+119397Y+076687X0205Y0590R090 S1      
327m4070            SW1   -6          A01X+166910Y+014176X0300Y0500R270 S1      
327m4070            R1508 -2          A01X+165810Y+014176X0198Y0197     S1      
327m4070            VIA   -    M      A01X+166290Y+014176X0300Y    R180 S1      
327PDB_PRSNT_N      R1526 -1          A01X+105010Y+166546X0198Y0197R270 S1      
317PDB_PRSNT_N      VIA   -    M      A01X+104554Y+166309X0200Y         S2      
017PDB_PRSNT_N      VIA   -    M      A18X+104554Y+166309X0260Y         S2      
017PDB_PRSNT_N            -    MD0100PA00X+104554Y+166309                       
327PDB_PRSNT_N      C64   -1   M      A18X+091878Y+166634X0198Y0197R090 S2      
317PDB_PRSNT_N      VIA   -    MD0100PA00X+092129Y+166634X0200Y    R090 S0      
317PDB_PRSNT_N      J45   -D3   D0402PA00X+091878Y+168489X0657Y    R270 S3      
317m4071            VIA   -    M      A01X+066392Y+023448X0200Y         S2      
017m4071            VIA   -    M      A18X+066392Y+023448X0260Y         S2      
017m4071                  -    MD0100PA00X+066392Y+023448                       
327m4071            U18   -C8         A01X+070363Y+044194X0160Y    R090 S1      
317m4071            VIA   -    MD0100PA00X+070210Y+044040X0180Y    R090 S0      
327m4071            R178  -2   M      A01X+071015Y+022186X0198Y0197R180 S1      
327m4071            J59   -1          A01X+069728Y+022165X0110Y0630R270 S1      
327m4072            D49   -A          A01X+136155Y+006082X0240Y0280R090 S1      
327m4072            VIA   -    M      A01X+135575Y+005654X0300Y         S1      
327m4072            R1207 -1          A01X+135575Y+006134X0198Y0197R090 S1      
327P5V_AUX_VCC      U326  -19         A01X+163256Y+056096X0120Y0320R270 S1      
327P5V_AUX_VCC      PC1848-1          A01X+163833Y+056136X0198Y0197R270 S1      
317P5V_AUX_VCC      VIA   -    MD0100PA00X+163570Y+056125X0200Y    R270 S0      
327P5V_AUX_VCC      R2356 -1          A18X+162038Y+055051X0198Y0197R090 S2      
317P5V_AUX_VCC      VIA   -    M      A01X+160489Y+053123X0200Y    R180 S2      
017P5V_AUX_VCC      VIA   -    M      A18X+160489Y+053123X0260Y    R180 S2      
017P5V_AUX_VCC            -    MD0100PA00X+160489Y+053123                       
327P5V_AUX_VCC      R2343 -1          A01X+160187Y+053123X0198Y0197R180 S1      
327P5V_AUX_REF      U326  -5          A01X+162154Y+055426X0070Y0320R090 S1      
327P5V_AUX_REF      PC1853-1          A01X+161352Y+055466X0198Y0197R180 S1      
327P5V_AUX_MODE     U326  -4          A01X+162154Y+055584X0070Y0320R090 S1      
317P5V_AUX_MODE     VIA   -    M      A01X+161620Y+055636X0200Y    R270 S2      
017P5V_AUX_MODE     VIA   -    M      A18X+161620Y+055636X0260Y    R270 S2      
017P5V_AUX_MODE           -    MD0100PA00X+161620Y+055636                       
327P5V_AUX_MODE     PR3337-1          A18X+161052Y+055673X0198Y0197     S2      
327P5V_AUX_FB       U326  -7          A01X+162154Y+055111X0070Y0320R090 S1      
317P5V_AUX_FB       VIA   -    MD0100PA00X+161608Y+054910X0200Y    R270 S2      
327P5V_AUX_FB       PR8091-1   M      A01X+161336Y+054710X0198Y0197R090 S1      
327P5V_AUX_FB       PC1877-1          A01X+160529Y+055025X0198Y0197R270 S1      
327P5V_AUX_FB       PR8092-1   M      A01X+160929Y+055025X0198Y0197R270 S1      
327P5V_AUX_CS       U326  -3          A01X+162154Y+055741X0070Y0320R090 S1      
327P5V_AUX_CS       PR8089-1          A01X+161359Y+055909X0198Y0197R180 S1      
327P5V_AUX          PR335 -2          A01X+054337Y+059535X0198Y0197R270 S1      
317P5V_AUX          VIA   -    MD0100PA00X+054207Y+059309X0200Y    R180 S0      
317P5V_AUX          VIA   -    MD0100PA00X+081529Y+058040X0200Y         S0      
317P5V_AUX          VIA   -    MD0100PA00X+065337Y+058147X0200Y         S0      
317P5V_AUX          VIA   -    MD0100PA00X+041440Y+054469X0200Y    R180 S0      
327P5V_AUX          PR157 -1   M      A01X+040295Y+056142X0198Y0197R180 S1      
317P5V_AUX          VIA   -    MD0100PA00X+160904Y+060099X0200Y    R270 S0      
327P5V_AUX          PC1856-1          A18X+162306Y+059935X0400Y0500R270 S2      
327P5V_AUX          PC1855-1          A18X+163026Y+059932X0400Y0500R270 S2      
327P5V_AUX          PC1852-1          A18X+160914Y+059848X0198Y0197R090 S2      
317P5V_AUX          VIA   -    MD0100PA00X+161843Y+060575X0200Y    R270 S0      
317P5V_AUX          VIA   -    MD0100PA00X+163602Y+060613X0200Y    R270 S0      
317P5V_AUX          VIA   -    MD0100PA00X+136795Y+006689X0200Y         S0      
327P5V_AUX          R1208 -2          A01X+136795Y+006449X0198Y0197R090 S1      
317P5V_AUX          VIA   -    MD0100PA00X+135575Y+006689X0200Y         S0      
327P5V_AUX          R1207 -2          A01X+135575Y+006449X0198Y0197R090 S1      
327P5V_AUX          R130  -2          A01X+126347Y+009044X0198Y0197R090 S1      
317P5V_AUX          VIA   -    MD0100PA00X+126347Y+009286X0200Y    R180 S0      
327P5V_AUX          C6028 -1   M      A01X+055600Y+019354X0198Y0197     S1      
317P5V_AUX          VIA   -    MD0100PA00X+055358Y+019354X0200Y    R180 S0      
327P5V_AUX          R4450 -2   M      A01X+055420Y+018783X0198Y0197R090 S1      
317P5V_AUX          VIA   -    MD0100PA00X+055420Y+019026X0200Y    R090 S0      
327P5V_AUX          C6027 -1          A01X+055408Y+019904X0400Y0500R180 S1      
317P5V_AUX          VIA   -    MD0100PA00X+055055Y+019778X0200Y         S0      
317P5V_AUX          VIA   -    MD0100PA00X+055055Y+020030X0200Y         S0      
317P5V_AUX          VIA   -    MD0100PA00X+055948Y+015667X0200Y    R270 S0      
327P5V_AUX          R6208 -1          A01X+055441Y+015667X0198Y0197R180 S1      
327P5V_AUX          R820  -2          A01X+143826Y+005532X0198Y0197R270 S1      
317P5V_AUX          VIA   -    MD0100PA00X+143826Y+005289X0200Y         S0      
317P5V_AUX          VIA   -    MD0100PA00X+167340Y+020000X0200Y    R270 S0      
317P5V_AUX          VIA   -    MD0100PA00X+163120Y+016411X0200Y         S0      
317P5V_AUX          VIA   -    MD0100PA00X+041237Y+018821X0200Y    R270 S0      
327P5V_AUX          R6318 -1          A01X+041130Y+020654X0198Y0197R090 S1      
327P5V_AUX          PR445 -2          A01X+165415Y+061892X0198Y0197R270 S1      
317P5V_AUX          VIA   -    M      A01X+165415Y+061652X0200Y    R180 S2      
017P5V_AUX          VIA   -    M      A18X+165415Y+061652X0260Y    R180 S2      
017P5V_AUX                -    MD0100PA00X+165415Y+061652                       
317P5V_AUX          VIA   -    MD0100PA00X+162851Y+060302X0200Y         S0      
317P5V_AUX          VIA   -    MD0100PA00X+162501Y+060302X0200Y         S0      
317P5V_AUX          VIA   -    MD0100PA00X+162151Y+060302X0200Y         S0      
317P5V_AUX          VIA   -    MD0100PA00X+163201Y+060302X0200Y         S0      
317P5V_AUX          VIA   -    M      A01X+165119Y+060945X0200Y    R180 S2      
017P5V_AUX          VIA   -    M      A18X+165119Y+060945X0260Y    R180 S2      
017P5V_AUX                -    MD0100PA00X+165119Y+060945                       
317P5V_AUX          VIA   -    MD0100PA00X+163594Y+061251X0200Y    R270 S0      
317P5V_AUX          VIA   -    M      A01X+163594Y+060951X0200Y    R270 S2      
017P5V_AUX          VIA   -    M      A18X+163594Y+060951X0260Y    R270 S2      
017P5V_AUX                -    MD0100PA00X+163594Y+060951                       
317P5V_AUX          VIA   -    M      A01X+161836Y+060914X0200Y    R270 S2      
017P5V_AUX          VIA   -    M      A18X+161836Y+060914X0260Y    R270 S2      
017P5V_AUX                -    MD0100PA00X+161836Y+060914                       
317P5V_AUX          VIA   -    MD0100PA00X+161836Y+061214X0200Y    R270 S0      
317P5V_AUX          VIA   -    M      A01X+165119Y+059996X0200Y    R180 S2      
017P5V_AUX          VIA   -    M      A18X+165119Y+059996X0260Y    R180 S2      
017P5V_AUX                -    MD0100PA00X+165119Y+059996                       
317P5V_AUX          VIA   -    M      A01X+165719Y+059996X0200Y    R180 S2      
017P5V_AUX          VIA   -    M      A18X+165719Y+059996X0260Y    R180 S2      
017P5V_AUX                -    MD0100PA00X+165719Y+059996                       
317P5V_AUX          VIA   -    MD0100PA00X+165419Y+059996X0200Y    R180 S0      
317P5V_AUX          VIA   -    M      A01X+165719Y+060945X0200Y    R180 S2      
017P5V_AUX          VIA   -    M      A18X+165719Y+060945X0260Y    R180 S2      
017P5V_AUX                -    MD0100PA00X+165719Y+060945                       
317P5V_AUX          VIA   -    MD0100PA00X+166019Y+059996X0200Y    R180 S0      
317P5V_AUX          VIA   -    MD0100PA00X+165419Y+060945X0200Y    R180 S0      
317P5V_AUX          VIA   -    MD0100PA00X+166019Y+060945X0200Y    R180 S0      
327P5V_AUX          C1042 -1          A01X+158408Y+056468X0198Y0197R270 S1      
327P5V_AUX          C1170 -1          A01X+159750Y+056599X0400Y0500R090 S1      
327P5V_AUX          C57   -1          A01X+159040Y+056599X0400Y0500R090 S1      
327P5V_AUX          Q57   -5          A01X+159213Y+058152X1850Y1811R270 S1      
327P5V_AUX          PL8065-2          A01X+162718Y+061102X1300Y1300R090 S1      
327P5V_AUX          PC1845-1          A01X+165569Y+060470X0630Y1190R090 S1      
327P5V_AUX          PR8092-2          A01X+160929Y+054710X0198Y0197R270 S1      
327P5V_AUX          PC1877-2   M      A01X+160529Y+054710X0198Y0197R270 S1      
327P5V_AUX          PR290 -1          A01X+151383Y+055198X0198Y0197R180 S1      
317P5V_AUX          VIA   -    MD0100PA00X+151634Y+055198X0200Y    R180 S0      
317P5V_AUX          VIA   -    MD0100PA00X+092437Y+050341X0200Y         S0      
317P5V_AUX          VIA   -    MD0100PA00X+092443Y+050716X0200Y         S0      
317P5V_AUX          VIA   -    MD0100PA00X+092137Y+050341X0200Y         S0      
317P5V_AUX          VIA   -    MD0100PA00X+092143Y+050716X0200Y         S0      
317P5V_AUX          VIA   -    MD0100PA00X+108562Y+052065X0200Y         S0      
317P5V_AUX          VIA   -    MD0100PA00X+108544Y+052403X0200Y         S0      
317P5V_AUX          VIA   -    MD0100PA00X+108244Y+052403X0200Y         S0      
317P5V_AUX          VIA   -    MD0100PA00X+108262Y+052065X0200Y         S0      
327P5V_AUX          R1238 -1          A18X+093821Y+126564X0198Y0197     S2      
317P5V_AUX          VIA   -    MD0100PA00X+094099Y+126564X0200Y    R180 S0      
317P5V_AUX          VIA   -    MD0100PA00X+097365Y+143142X0200Y         S0      
317P5V_AUX          VIA   -    MD0100PA00X+126231Y+142830X0200Y         S0      
317P5V_AUX          VIA   -    MD0100PA00X+069238Y+143833X0200Y         S0      
327P5V_AUX          PR376 -1          A18X+066274Y+137684X0198Y0197     S2      
317P5V_AUX          VIA   -    MD0100PA00X+066517Y+137684X0200Y         S0      
317P5V_AUX          VIA   -    MD0100PA00X+069773Y+139751X0200Y    R180 S0      
327P5V_AUX          PR387 -2          A01X+069773Y+139511X0198Y0197R090 S1      
327P5V_AUX          PR885 -1          A18X+004509Y+162540X0198Y0197R180 S2      
317P5V_AUX          VIA   -    MD0100PA00X+004017Y+163240X0200Y    R090 S0      
327P5V_AUX          PR6619-1          A01X+004615Y+155366X0198Y0197R270 S1      
317P5V_AUX          VIA   -    MD0100PA00X+004891Y+155497X0200Y         S0      
317P5V_AUX          VIA   -    MD0100PA00X+001923Y+144646X0200Y         S0      
327P5V_AUX          PR340 -2   M      A01X+009471Y+138591X0198Y0197R090 S1      
317P5V_AUX          VIA   -    MD0100PA00X+009755Y+138591X0200Y         S0      
327P5V_AUX          PR230 -1   M      A18X+014058Y+142500X0198Y0197     S2      
327P5V_AUX          PR442 -2   M      A01X+106240Y+138559X0198Y0197R090 S1      
317P5V_AUX          VIA   -    MD0100PA00X+105814Y+143381X0200Y    R180 S0      
317P5V_AUX          VIA   -    MD0100PA00X+126700Y+142362X0200Y         S0      
317P5V_AUX          VIA   -    MD0100PA00X+177568Y+146657X0200Y         S0      
317P5V_AUX          VIA   -    MD0100PA00X+168778Y+147207X0200Y         S0      
317P5V_AUX          VIA   -    M      A01X+178838Y+055832X0200Y         S2      
017P5V_AUX          VIA   -    M      A18X+178838Y+055832X0260Y         S2      
017P5V_AUX                -    MD0100PA00X+178838Y+055832                       
317P5V_AUX          VIA   -    M      A01X+178238Y+055832X0200Y         S2      
017P5V_AUX          VIA   -    M      A18X+178238Y+055832X0260Y         S2      
017P5V_AUX                -    MD0100PA00X+178238Y+055832                       
317P5V_AUX          VIA   -    MD0100PA00X+178538Y+055832X0200Y         S0      
317P5V_AUX          VIA   -    MD0100PA00X+177938Y+055832X0200Y         S0      
317P5V_AUX          VIA   -    MD0100PA00X+161477Y+144351X0200Y         S0      
317P5V_AUX          VIA   -    MD0100PA00X+164920Y+139674X0200Y    R180 S0      
327P5V_AUX          PR411 -2          A01X+164920Y+139434X0198Y0197R090 S1      
327P5V_AUX          PR113 -1          A18X+167341Y+142669X0198Y0197     S2      
317P5V_AUX          VIA   -    MD0100PA00X+167564Y+143289X0200Y         S0      
327P5V_AUX          PR53  -1   M      A01X+125686Y+141992X0198Y0197R090 S1      
317P5V_AUX          VIA   -    MD0100PA00X+125759Y+141700X0200Y         S0      
327P5V_AUX          PR6550-1          A01X+173020Y+159917X0198Y0197R270 S1      
317P5V_AUX          VIA   -    MD0100PA00X+173020Y+160209X0200Y         S0      
327P5V_AUX          PR6604-1          A18X+176400Y+165896X0198Y0197     S2      
317P5V_AUX          VIA   -    MD0100PA00X+176893Y+165196X0200Y    R270 S0      
317m4073            VIA   -    MD0080PA01X+047084Y+108865X0160Y         S0      
317m4073            VIA   -    MD0100PA01X+049382Y+145290X0200Y    R180 S0      
327m4073            C1529 -2          A01X+049372Y+145790X0120Y0150R270 S1      
327m4073            U26   -CE30       A01X+046901Y+108760X0177Y    R180 S1      
317m4074            VIA   -    MD0080PA01X+047084Y+109502X0160Y         S0      
317m4074            VIA   -    MD0100PA01X+048712Y+146260X0200Y    R180 S0      
327m4074            C1531 -2          A01X+048702Y+146760X0120Y0150R270 S1      
327m4074            U26   -CG30       A01X+046901Y+109398X0177Y    R180 S1      
317m4075            VIA   -    MD0080PA01X+047084Y+108227X0160Y         S0      
317m4075            VIA   -    MD0100PA01X+048042Y+147230X0200Y    R180 S0      
327m4075            C1533 -2          A01X+048032Y+147730X0120Y0150R270 S1      
327m4075            U26   -CC30       A01X+046901Y+108122X0177Y    R180 S1      
317m4076            VIA   -    MD0080PA01X+045974Y+108865X0160Y         S0      
317m4076            VIA   -    MD0100PA01X+046702Y+145290X0200Y    R180 S0      
327m4076            C1535 -2          A01X+046692Y+145790X0120Y0150R270 S1      
327m4076            U26   -CE33       A01X+045790Y+108760X0177Y    R180 S1      
317m4077            VIA   -    MD0080PA01X+045974Y+109502X0160Y         S0      
317m4077            VIA   -    MD0100PA01X+046032Y+146260X0200Y    R180 S0      
327m4077            C1537 -2          A01X+046022Y+146760X0120Y0150R270 S1      
327m4077            U26   -CG33       A01X+045790Y+109398X0177Y    R180 S1      
317m4078            VIA   -    MD0080PA01X+045974Y+110140X0160Y         S0      
317m4078            VIA   -    MD0100PA01X+045362Y+147230X0200Y    R180 S0      
327m4078            C1539 -2          A01X+045352Y+147730X0120Y0150R270 S1      
327m4078            U26   -CJ33       A01X+045790Y+110036X0177Y    R180 S1      
317m4079            VIA   -    MD0080PA01X+045974Y+108227X0160Y         S0      
317m4079            VIA   -    MD0100PA01X+044022Y+145290X0200Y    R180 S0      
327m4079            C1541 -2          A01X+044012Y+145790X0120Y0150R270 S1      
327m4079            U26   -CC33       A01X+045790Y+108122X0177Y    R180 S1      
317m4080            VIA   -    MD0080PA01X+045049Y+109821X0160Y         S0      
317m4080            VIA   -    MD0100PA01X+043352Y+146260X0200Y    R180 S0      
327m4080            C1543 -2          A01X+043342Y+146760X0120Y0150R270 S1      
327m4080            U26   -CH36       A01X+044865Y+109717X0177Y    R180 S1      
317m4081            VIA   -    MD0080PA01X+045049Y+109184X0160Y         S0      
317m4081            VIA   -    MD0100PA01X+042729Y+148019X0200Y    R270 S0      
327m4081            C1545 -2          A01X+043229Y+148009X0120Y0150R180 S1      
327m4081            U26   -CF36       A01X+044865Y+109079X0177Y    R180 S1      
317m4082            VIA   -    MD0080PA01X+049305Y+108865X0160Y         S0      
317m4082            VIA   -    MD0100PA01X+054479Y+149408X0200Y    R270 S0      
327m4082            C49   -2          A01X+053979Y+149398X0120Y0150     S1      
327m4082            U26   -CE24       A01X+049121Y+108760X0177Y    R180 S1      
317m4083            VIA   -    MD0080PA01X+049305Y+109502X0160Y         S0      
317m4083            VIA   -    MD0100PA01X+054479Y+148408X0200Y    R270 S0      
327m4083            C51   -2          A01X+053979Y+148418X0120Y0150     S1      
327m4083            U26   -CG24       A01X+049121Y+109398X0177Y    R180 S1      
317m4084            VIA   -    MD0080PA01X+049305Y+108227X0160Y         S0      
317m4084            VIA   -    MD0100PA01X+053402Y+145290X0200Y    R180 S0      
327m4084            C53   -2          A01X+053392Y+145790X0120Y0150R270 S1      
327m4084            U26   -CC24       A01X+049121Y+108122X0177Y    R180 S1      
317m4085            VIA   -    MD0080PA01X+048195Y+108865X0160Y         S0      
317m4085            VIA   -    MD0100PA01X+052062Y+145290X0200Y    R180 S0      
327m4085            C55   -2          A01X+052052Y+145790X0120Y0150R270 S1      
327m4085            U26   -CE27       A01X+048011Y+108760X0177Y    R180 S1      
317m4086            VIA   -    MD0080PA01X+048195Y+109502X0160Y         S0      
317m4086            VIA   -    MD0100PA01X+051392Y+146260X0200Y    R180 S0      
327m4086            C1525 -2          A01X+051382Y+146760X0120Y0150R270 S1      
327m4086            U26   -CG27       A01X+048011Y+109398X0177Y    R180 S1      
317m4087            VIA   -    MD0080PA01X+048195Y+108227X0160Y         S0      
317m4087            VIA   -    MD0100PA01X+050722Y+147230X0200Y    R180 S0      
327m4087            C1527 -2          A01X+050712Y+147730X0120Y0150R270 S1      
327m4087            U26   -CC27       A01X+048011Y+108122X0177Y    R180 S1      
317m4088            VIA   -    MD0080PA01X+045049Y+108546X0160Y         S0      
317m4088            VIA   -    MD0100PA01X+042729Y+150539X0200Y    R270 S0      
327m4088            C1547 -2          A01X+043229Y+150549X0120Y0150R180 S1      
327m4088            U26   -CD36       A01X+044865Y+108441X0177Y    R180 S1      
317m4089            VIA   -    MD0080PA01X+047455Y+108865X0160Y         S0      
317m4089            VIA   -    MD0100PA01X+049722Y+145290X0200Y    R180 S0      
327m4089            C1528 -2          A01X+049732Y+145790X0120Y0150R270 S1      
327m4089            U26   -CE29       A01X+047271Y+108760X0177Y    R180 S1      
317m4090            VIA   -    MD0080PA01X+047455Y+109502X0160Y         S0      
317m4090            VIA   -    MD0100PA01X+049052Y+146260X0200Y    R180 S0      
327m4090            C1530 -2          A01X+049062Y+146760X0120Y0150R270 S1      
327m4090            U26   -CG29       A01X+047271Y+109398X0177Y    R180 S1      
317m4091            VIA   -    MD0080PA01X+047455Y+108227X0160Y         S0      
317m4091            VIA   -    MD0100PA01X+048382Y+147230X0200Y    R180 S0      
327m4091            C1532 -2          A01X+048392Y+147730X0120Y0150R270 S1      
327m4091            U26   -CC29       A01X+047271Y+108122X0177Y    R180 S1      
317m4092            VIA   -    MD0080PA01X+046344Y+108865X0160Y         S0      
317m4092            VIA   -    MD0100PA01X+047042Y+145290X0200Y    R180 S0      
327m4092            C1534 -2          A01X+047052Y+145790X0120Y0150R270 S1      
327m4092            U26   -CE32       A01X+046161Y+108760X0177Y    R180 S1      
317m4093            VIA   -    MD0080PA01X+046344Y+109502X0160Y         S0      
317m4093            VIA   -    MD0100PA01X+046372Y+146260X0200Y    R180 S0      
327m4093            C1536 -2          A01X+046382Y+146760X0120Y0150R270 S1      
327m4093            U26   -CG32       A01X+046161Y+109398X0177Y    R180 S1      
317m4094            VIA   -    MD0080PA01X+046344Y+110140X0160Y         S0      
317m4094            VIA   -    MD0100PA01X+045702Y+147230X0200Y    R180 S0      
327m4094            C1538 -2          A01X+045712Y+147730X0120Y0150R270 S1      
327m4094            U26   -CJ32       A01X+046161Y+110036X0177Y    R180 S1      
317m4095            VIA   -    MD0080PA01X+046344Y+108227X0160Y         S0      
317m4095            VIA   -    MD0100PA01X+044362Y+145290X0200Y    R180 S0      
327m4095            C1540 -2          A01X+044372Y+145790X0120Y0150R270 S1      
327m4095            U26   -CC32       A01X+046161Y+108122X0177Y    R180 S1      
317m4096            VIA   -    MD0080PA01X+045419Y+109821X0160Y         S0      
317m4096            VIA   -    MD0100PA01X+043692Y+146260X0200Y    R180 S0      
327m4096            C1542 -2          A01X+043702Y+146760X0120Y0150R270 S1      
327m4096            U26   -CH35       A01X+045235Y+109717X0177Y    R180 S1      
317m4097            VIA   -    MD0080PA01X+045419Y+109184X0160Y         S0      
317m4097            VIA   -    MD0100PA01X+042729Y+148359X0200Y    R270 S0      
327m4097            C1544 -2          A01X+043229Y+148369X0120Y0150R180 S1      
327m4097            U26   -CF35       A01X+045235Y+109079X0177Y    R180 S1      
317m4098            VIA   -    MD0080PA01X+049675Y+108865X0160Y         S0      
317m4098            VIA   -    MD0100PA01X+054479Y+149748X0200Y    R270 S0      
327m4098            C48   -2          A01X+053979Y+149758X0120Y0150     S1      
327m4098            U26   -CE23       A01X+049491Y+108760X0177Y    R180 S1      
317m4099            VIA   -    MD0080PA01X+049675Y+109502X0160Y         S0      
317m4099            VIA   -    MD0100PA01X+054479Y+148068X0200Y    R270 S0      
327m4099            C50   -2          A01X+053979Y+148058X0120Y0150     S1      
327m4099            U26   -CG23       A01X+049491Y+109398X0177Y    R180 S1      
317m4100            VIA   -    MD0080PA01X+049675Y+108227X0160Y         S0      
317m4100            VIA   -    MD0100PA01X+053742Y+145290X0200Y    R180 S0      
327m4100            C52   -2          A01X+053752Y+145790X0120Y0150R270 S1      
327m4100            U26   -CC23       A01X+049491Y+108122X0177Y    R180 S1      
317m4101            VIA   -    MD0080PA01X+048565Y+108865X0160Y         S0      
317m4101            VIA   -    MD0100PA01X+052402Y+145290X0200Y    R180 S0      
327m4101            C54   -2          A01X+052412Y+145790X0120Y0150R270 S1      
327m4101            U26   -CE26       A01X+048381Y+108760X0177Y    R180 S1      
317m4102            VIA   -    MD0080PA01X+048565Y+109502X0160Y         S0      
317m4102            VIA   -    MD0100PA01X+051732Y+146260X0200Y    R180 S0      
327m4102            C1524 -2          A01X+051742Y+146760X0120Y0150R270 S1      
327m4102            U26   -CG26       A01X+048381Y+109398X0177Y    R180 S1      
317m4103            VIA   -    MD0080PA01X+048565Y+108227X0160Y         S0      
317m4103            VIA   -    MD0100PA01X+051062Y+147230X0200Y    R180 S0      
327m4103            C1526 -2          A01X+051072Y+147730X0120Y0150R270 S1      
327m4103            U26   -CC26       A01X+048381Y+108122X0177Y    R180 S1      
317m4104            VIA   -    MD0080PA01X+045419Y+108546X0160Y         S0      
317m4104            VIA   -    MD0100PA01X+042729Y+150199X0200Y    R270 S0      
327m4104            C1546 -2          A01X+043229Y+150189X0120Y0150R180 S1      
327m4104            U26   -CD35       A01X+045235Y+108441X0177Y    R180 S1      
317m4105            VIA   -    MD0080PA01X+049642Y+151970X0160Y         S0      
317m4105            VIA   -    MD0080PA01X+048565Y+113329X0160Y         S0      
327m4105            U6017 -BP26       A01X+049437Y+151970X0150Y         S1      
327m4105            U26   -CW26       A01X+048381Y+113225X0177Y    R180 S1      
317m4106            VIA   -    MD0080PA01X+049170Y+151970X0160Y         S0      
317m4106            VIA   -    MD0080PA01X+047455Y+113967X0160Y         S0      
327m4106            U26   -DA29       A01X+047271Y+113862X0177Y    R180 S1      
327m4106            U6017 -CA26       A01X+048965Y+151970X0150Y         S1      
317m4107            VIA   -    MD0080PA01X+048697Y+151970X0160Y         S0      
317m4107            VIA   -    MD0080PA01X+047455Y+114605X0160Y         S0      
327m4107            U6017 -CH26       A01X+048492Y+151970X0150Y         S1      
327m4107            U26   -DC29       A01X+047271Y+114500X0177Y    R180 S1      
317m4108            VIA   -    MD0080PA01X+048225Y+151970X0160Y         S0      
317m4108            VIA   -    MD0080PA01X+047455Y+113329X0160Y         S0      
327m4108            U6017 -CR26       A01X+048020Y+151970X0150Y         S1      
327m4108            U26   -CW29       A01X+047271Y+113225X0177Y    R180 S1      
317m4109            VIA   -    MD0080PA01X+047752Y+151970X0160Y         S0      
327m4109            U26   -DA32       A01X+046161Y+113862X0177Y    R180 S1      
317m4109            VIA   -    MD0080PA01X+046344Y+113967X0160Y         S0      
327m4109            U6017 -DB26       A01X+047548Y+151970X0150Y         S1      
317m4110            VIA   -    MD0080PA01X+047280Y+151970X0160Y         S0      
317m4110            VIA   -    MD0080PA01X+046344Y+114605X0160Y         S0      
327m4110            U6017 -DJ26       A01X+047075Y+151970X0150Y         S1      
327m4110            U26   -DC32       A01X+046161Y+114500X0177Y    R180 S1      
317m4111            VIA   -    MD0080PA01X+046808Y+151970X0160Y         S0      
317m4111            VIA   -    MD0080PA01X+046344Y+113329X0160Y         S0      
327m4111            U6017 -DT26       A01X+046603Y+151970X0150Y         S1      
327m4111            U26   -CW32       A01X+046161Y+113225X0177Y    R180 S1      
317m4112            VIA   -    MD0080PA01X+046335Y+151970X0160Y         S0      
327m4112            U26   -DB35       A01X+045235Y+114181X0177Y    R180 S1      
317m4112            VIA   -    MD0080PA01X+045419Y+114286X0160Y         S0      
327m4112            U6017 -EC26       A01X+046130Y+151970X0150Y         S1      
317m4113            VIA   -    MD0080PA01X+045863Y+151970X0160Y         S0      
317m4113            VIA   -    MD0080PA01X+045419Y+113648X0160Y         S0      
327m4113            U6017 -EK26       A01X+045658Y+151970X0150Y         S1      
327m4113            U26   -CY35       A01X+045235Y+113543X0177Y    R180 S1      
317m4114            VIA   -    MD0080PA01X+052477Y+151970X0160Y         S0      
317m4114            VIA   -    MD0080PA01X+049675Y+112692X0160Y         S0      
327m4114            U26   -CU23       A01X+049491Y+112587X0177Y    R180 S1      
327m4114            U6017 -M26        A01X+052272Y+151970X0150Y         S1      
317m4115            VIA   -    MD0080PA01X+052004Y+151970X0160Y         S0      
317m4115            VIA   -    MD0080PA01X+049675Y+113967X0160Y         S0      
327m4115            U26   -DA23       A01X+049491Y+113862X0177Y    R180 S1      
327m4115            U6017 -W26        A01X+051799Y+151970X0150Y         S1      
317m4116            VIA   -    MD0080PA01X+051532Y+151970X0160Y         S0      
317m4116            VIA   -    MD0080PA01X+049675Y+114605X0160Y         S0      
327m4116            U6017 -AF26       A01X+051327Y+151970X0150Y         S1      
327m4116            U26   -DC23       A01X+049491Y+114500X0177Y    R180 S1      
317m4117            VIA   -    MD0080PA01X+051060Y+151970X0160Y         S0      
317m4117            VIA   -    MD0080PA01X+049675Y+113329X0160Y         S0      
327m4117            U6017 -AN26       A01X+050854Y+151970X0150Y         S1      
327m4117            U26   -CW23       A01X+049491Y+113225X0177Y    R180 S1      
317m4118            VIA   -    MD0080PA01X+050587Y+151970X0160Y         S0      
327m4118            U26   -DA26       A01X+048381Y+113862X0177Y    R180 S1      
317m4118            VIA   -    MD0080PA01X+048565Y+113967X0160Y         S0      
327m4118            U6017 -AY26       A01X+050382Y+151970X0150Y         S1      
317m4119            VIA   -    MD0080PA01X+050115Y+151970X0160Y         S0      
317m4119            VIA   -    MD0080PA01X+048565Y+114605X0160Y         S0      
327m4119            U6017 -BG26       A01X+049910Y+151970X0150Y         S1      
327m4119            U26   -DC26       A01X+048381Y+114500X0177Y    R180 S1      
317m4120            VIA   -    MD0080PA01X+045390Y+151970X0160Y         S0      
317m4120            VIA   -    MD0080PA01X+045419Y+113010X0160Y         S0      
327m4120            U6017 -EU26       A01X+045185Y+151970X0150Y         S1      
327m4120            U26   -CV35       A01X+045235Y+112906X0177Y    R180 S1      
317m4121            VIA   -    MD0080PA01X+049485Y+151697X0160Y         S0      
317m4121            VIA   -    MD0080PA01X+048195Y+113329X0160Y         S0      
327m4121            U6017 -BT29       A01X+049280Y+151697X0150Y         S1      
327m4121            U26   -CW27       A01X+048011Y+113225X0177Y    R180 S1      
317m4122            VIA   -    MD0080PA01X+049012Y+151697X0160Y         S0      
317m4122            VIA   -    MD0080PA01X+047084Y+113967X0160Y         S0      
327m4122            U26   -DA30       A01X+046901Y+113862X0177Y    R180 S1      
327m4122            U6017 -CC29       A01X+048807Y+151697X0150Y         S1      
317m4123            VIA   -    MD0080PA01X+048540Y+151697X0160Y         S0      
317m4123            VIA   -    MD0080PA01X+047084Y+114605X0160Y         S0      
327m4123            U6017 -CK29       A01X+048335Y+151697X0150Y         S1      
327m4123            U26   -DC30       A01X+046901Y+114500X0177Y    R180 S1      
317m4124            VIA   -    MD0080PA01X+048067Y+151697X0160Y         S0      
317m4124            VIA   -    MD0080PA01X+047084Y+113329X0160Y         S0      
327m4124            U6017 -CU29       A01X+047862Y+151697X0150Y         S1      
327m4124            U26   -CW30       A01X+046901Y+113225X0177Y    R180 S1      
317m4125            VIA   -    MD0080PA01X+047595Y+151697X0160Y         S0      
327m4125            U26   -DA33       A01X+045790Y+113862X0177Y    R180 S1      
317m4125            VIA   -    MD0080PA01X+045974Y+113967X0160Y         S0      
327m4125            U6017 -DD29       A01X+047390Y+151697X0150Y         S1      
317m4126            VIA   -    MD0080PA01X+047122Y+151697X0160Y         S0      
317m4126            VIA   -    MD0080PA01X+045974Y+114605X0160Y         S0      
327m4126            U6017 -DL29       A01X+046918Y+151697X0150Y         S1      
327m4126            U26   -DC33       A01X+045790Y+114500X0177Y    R180 S1      
317m4127            VIA   -    MD0080PA01X+046650Y+151697X0160Y         S0      
317m4127            VIA   -    MD0080PA01X+045974Y+113329X0160Y         S0      
327m4127            U6017 -DV29       A01X+046445Y+151697X0150Y         S1      
327m4127            U26   -CW33       A01X+045790Y+113225X0177Y    R180 S1      
317m4128            VIA   -    MD0080PA01X+046178Y+151697X0160Y         S0      
327m4128            U26   -DB36       A01X+044865Y+114181X0177Y    R180 S1      
317m4128            VIA   -    MD0080PA01X+045049Y+114286X0160Y         S0      
327m4128            U6017 -EE29       A01X+045973Y+151697X0150Y         S1      
317m4129            VIA   -    MD0080PA01X+045705Y+151697X0160Y         S0      
317m4129            VIA   -    MD0080PA01X+045049Y+113648X0160Y         S0      
327m4129            U6017 -EM29       A01X+045500Y+151697X0150Y         S1      
327m4129            U26   -CY36       A01X+044865Y+113543X0177Y    R180 S1      
317m4130            VIA   -    MD0080PA01X+052319Y+151697X0160Y         S0      
317m4130            VIA   -    MD0080PA01X+049305Y+112692X0160Y         S0      
327m4130            U26   -CU24       A01X+049121Y+112587X0177Y    R180 S1      
327m4130            U6017 -P29        A01X+052114Y+151697X0150Y         S1      
317m4131            VIA   -    MD0080PA01X+051847Y+151697X0160Y         S0      
317m4131            VIA   -    MD0080PA01X+049305Y+113967X0160Y         S0      
327m4131            U26   -DA24       A01X+049121Y+113862X0177Y    R180 S1      
327m4131            U6017 -AA29       A01X+051642Y+151697X0150Y         S1      
317m4132            VIA   -    MD0080PA01X+051374Y+151697X0160Y         S0      
317m4132            VIA   -    MD0080PA01X+049305Y+114605X0160Y         S0      
327m4132            U6017 -AH29       A01X+051170Y+151697X0150Y         S1      
327m4132            U26   -DC24       A01X+049121Y+114500X0177Y    R180 S1      
317m4133            VIA   -    MD0080PA01X+050902Y+151697X0160Y         S0      
317m4133            VIA   -    MD0080PA01X+049305Y+113329X0160Y         S0      
327m4133            U6017 -AR29       A01X+050697Y+151697X0150Y         S1      
327m4133            U26   -CW24       A01X+049121Y+113225X0177Y    R180 S1      
317m4134            VIA   -    MD0080PA01X+050430Y+151697X0160Y         S0      
317m4134            VIA   -    MD0080PA01X+048195Y+113967X0160Y         S0      
327m4134            U26   -DA27       A01X+048011Y+113862X0177Y    R180 S1      
327m4134            U6017 -BB29       A01X+050225Y+151697X0150Y         S1      
317m4135            VIA   -    MD0080PA01X+049957Y+151697X0160Y         S0      
317m4135            VIA   -    MD0080PA01X+048195Y+114605X0160Y         S0      
327m4135            U6017 -BJ29       A01X+049752Y+151697X0150Y         S1      
327m4135            U26   -DC27       A01X+048011Y+114500X0177Y    R180 S1      
317m4136            VIA   -    MD0080PA01X+045233Y+151697X0160Y         S0      
317m4136            VIA   -    MD0080PA01X+045049Y+113010X0160Y         S0      
327m4136            U6017 -EW29       A01X+045028Y+151697X0150Y         S1      
327m4136            U26   -CV36       A01X+044865Y+112906X0177Y    R180 S1      
317m4137            VIA   -    MD0080PA01X+047084Y+106951X0160Y         S0      
317m4137            VIA   -    MD0100PA01X+062189Y+145290X0200Y    R180 S0      
327m4137            C755  -2          A01X+062179Y+145790X0120Y0150R270 S1      
327m4137            U26   -BW30       A01X+046901Y+106847X0177Y    R180 S1      
317m4138            VIA   -    MD0080PA01X+047084Y+107589X0160Y         S0      
317m4138            VIA   -    MD0100PA01X+061519Y+146260X0200Y    R180 S0      
327m4138            C757  -2          A01X+061509Y+146760X0120Y0150R270 S1      
327m4138            U26   -CA30       A01X+046901Y+107484X0177Y    R180 S1      
317m4139            VIA   -    MD0080PA01X+047084Y+106314X0160Y         S0      
317m4139            VIA   -    MD0100PA01X+060849Y+147230X0200Y    R180 S0      
327m4139            C759  -2          A01X+060839Y+147730X0120Y0150R270 S1      
327m4139            U26   -BU30       A01X+046901Y+106209X0177Y    R180 S1      
317m4140            VIA   -    MD0080PA01X+045974Y+106951X0160Y         S0      
317m4140            VIA   -    MD0100PA01X+059509Y+145290X0200Y    R180 S0      
327m4140            C761  -2          A01X+059499Y+145790X0120Y0150R270 S1      
327m4140            U26   -BW33       A01X+045790Y+106847X0177Y    R180 S1      
317m4141            VIA   -    MD0080PA01X+045974Y+107589X0160Y         S0      
317m4141            VIA   -    MD0100PA01X+058839Y+146260X0200Y    R180 S0      
327m4141            C763  -2          A01X+058829Y+146760X0120Y0150R270 S1      
327m4141            U26   -CA33       A01X+045790Y+107484X0177Y    R180 S1      
317m4142            VIA   -    MD0080PA01X+045974Y+106314X0160Y         S0      
317m4142            VIA   -    MD0100PA01X+058169Y+147230X0200Y    R180 S0      
327m4142            C765  -2          A01X+058159Y+147730X0120Y0150R270 S1      
327m4142            U26   -BU33       A01X+045790Y+106209X0177Y    R180 S1      
317m4143            VIA   -    MD0080PA01X+045049Y+107270X0160Y         S0      
317m4143            VIA   -    MD0100PA01X+056829Y+145290X0200Y    R180 S0      
327m4143            C767  -2          A01X+056819Y+145790X0120Y0150R270 S1      
327m4143            U26   -BY36       A01X+044865Y+107166X0177Y    R180 S1      
317m4144            VIA   -    MD0080PA01X+045049Y+107908X0160Y         S0      
317m4144            VIA   -    MD0100PA01X+056159Y+146260X0200Y    R180 S0      
327m4144            C769  -2          A01X+056149Y+146760X0120Y0150R270 S1      
327m4144            U26   -CB36       A01X+044865Y+107803X0177Y    R180 S1      
317m4145            VIA   -    MD0080PA01X+045049Y+106632X0160Y         S0      
317m4145            VIA   -    MD0100PA01X+055535Y+148019X0200Y    R270 S0      
327m4145            C771  -2          A01X+056035Y+148009X0120Y0150R180 S1      
327m4145            U26   -BV36       A01X+044865Y+106528X0177Y    R180 S1      
317m4146            VIA   -    MD0080PA01X+049305Y+106951X0160Y         S0      
317m4146            VIA   -    MD0100PA01X+067286Y+149408X0200Y    R270 S0      
327m4146            C743  -2          A01X+066786Y+149398X0120Y0150     S1      
327m4146            U26   -BW24       A01X+049121Y+106847X0177Y    R180 S1      
317m4147            VIA   -    MD0080PA01X+049305Y+107589X0160Y         S0      
317m4147            VIA   -    MD0100PA01X+067286Y+148068X0200Y    R270 S0      
327m4147            C745  -2          A01X+066786Y+148058X0120Y0150     S1      
327m4147            U26   -CA24       A01X+049121Y+107484X0177Y    R180 S1      
317m4148            VIA   -    MD0080PA01X+049305Y+106314X0160Y         S0      
317m4148            VIA   -    MD0100PA01X+066209Y+145290X0200Y    R180 S0      
327m4148            C747  -2          A01X+066199Y+145790X0120Y0150R270 S1      
327m4148            U26   -BU24       A01X+049121Y+106209X0177Y    R180 S1      
317m4149            VIA   -    MD0080PA01X+048195Y+106951X0160Y         S0      
317m4149            VIA   -    MD0100PA01X+064869Y+145290X0200Y    R180 S0      
327m4149            C749  -2          A01X+064859Y+145790X0120Y0150R270 S1      
327m4149            U26   -BW27       A01X+048011Y+106847X0177Y    R180 S1      
317m4150            VIA   -    MD0080PA01X+048195Y+107589X0160Y         S0      
317m4150            VIA   -    MD0100PA01X+064199Y+146260X0200Y    R180 S0      
327m4150            C751  -2          A01X+064189Y+146760X0120Y0150R270 S1      
327m4150            U26   -CA27       A01X+048011Y+107484X0177Y    R180 S1      
317m4151            VIA   -    MD0080PA01X+048195Y+106314X0160Y         S0      
317m4151            VIA   -    MD0100PA01X+063529Y+147230X0200Y    R180 S0      
327m4151            C753  -2          A01X+063519Y+147730X0120Y0150R270 S1      
327m4151            U26   -BU27       A01X+048011Y+106209X0177Y    R180 S1      
317m4152            VIA   -    MD0080PA01X+045049Y+105995X0160Y         S0      
317m4152            VIA   -    MD0100PA01X+055535Y+150539X0200Y    R270 S0      
327m4152            C773  -2          A01X+056035Y+150549X0120Y0150R180 S1      
327m4152            U26   -BT36       A01X+044865Y+105890X0177Y    R180 S1      
317m4153            VIA   -    MD0080PA01X+047455Y+106951X0160Y         S0      
317m4153            VIA   -    MD0100PA01X+062529Y+145290X0200Y    R180 S0      
327m4153            C754  -2          A01X+062539Y+145790X0120Y0150R270 S1      
327m4153            U26   -BW29       A01X+047271Y+106847X0177Y    R180 S1      
317m4154            VIA   -    MD0080PA01X+047455Y+107589X0160Y         S0      
317m4154            VIA   -    MD0100PA01X+061859Y+146260X0200Y    R180 S0      
327m4154            C756  -2          A01X+061869Y+146760X0120Y0150R270 S1      
327m4154            U26   -CA29       A01X+047271Y+107484X0177Y    R180 S1      
317m4155            VIA   -    MD0080PA01X+047455Y+106314X0160Y         S0      
317m4155            VIA   -    MD0100PA01X+061189Y+147230X0200Y    R180 S0      
327m4155            C758  -2          A01X+061199Y+147730X0120Y0150R270 S1      
327m4155            U26   -BU29       A01X+047271Y+106209X0177Y    R180 S1      
317m4156            VIA   -    MD0080PA01X+046344Y+106951X0160Y         S0      
317m4156            VIA   -    MD0100PA01X+059849Y+145290X0200Y    R180 S0      
327m4156            C760  -2          A01X+059859Y+145790X0120Y0150R270 S1      
327m4156            U26   -BW32       A01X+046161Y+106847X0177Y    R180 S1      
317m4157            VIA   -    MD0080PA01X+046344Y+107589X0160Y         S0      
317m4157            VIA   -    MD0100PA01X+059179Y+146260X0200Y    R180 S0      
327m4157            C762  -2          A01X+059189Y+146760X0120Y0150R270 S1      
327m4157            U26   -CA32       A01X+046161Y+107484X0177Y    R180 S1      
317m4158            VIA   -    MD0080PA01X+046344Y+106314X0160Y         S0      
317m4158            VIA   -    MD0100PA01X+058509Y+147230X0200Y    R180 S0      
327m4158            C764  -2          A01X+058519Y+147730X0120Y0150R270 S1      
327m4158            U26   -BU32       A01X+046161Y+106209X0177Y    R180 S1      
317m4159            VIA   -    MD0080PA01X+045419Y+107270X0160Y         S0      
317m4159            VIA   -    MD0100PA01X+057169Y+145290X0200Y    R180 S0      
327m4159            C766  -2          A01X+057179Y+145790X0120Y0150R270 S1      
327m4159            U26   -BY35       A01X+045235Y+107166X0177Y    R180 S1      
317m4160            VIA   -    MD0080PA01X+045419Y+107908X0160Y         S0      
317m4160            VIA   -    MD0100PA01X+056499Y+146260X0200Y    R180 S0      
327m4160            C768  -2          A01X+056509Y+146760X0120Y0150R270 S1      
327m4160            U26   -CB35       A01X+045235Y+107803X0177Y    R180 S1      
317m4161            VIA   -    MD0080PA01X+045419Y+106632X0160Y         S0      
317m4161            VIA   -    MD0100PA01X+055535Y+148359X0200Y    R270 S0      
327m4161            C770  -2          A01X+056035Y+148369X0120Y0150R180 S1      
327m4161            U26   -BV35       A01X+045235Y+106528X0177Y    R180 S1      
317m4162            VIA   -    MD0080PA01X+049675Y+106951X0160Y         S0      
317m4162            VIA   -    MD0100PA01X+067286Y+149748X0200Y    R270 S0      
327m4162            C742  -2          A01X+066786Y+149758X0120Y0150     S1      
327m4162            U26   -BW23       A01X+049491Y+106847X0177Y    R180 S1      
317m4163            VIA   -    MD0080PA01X+049675Y+107589X0160Y         S0      
317m4163            VIA   -    MD0100PA01X+067286Y+148408X0200Y    R270 S0      
327m4163            C744  -2          A01X+066786Y+148418X0120Y0150     S1      
327m4163            U26   -CA23       A01X+049491Y+107484X0177Y    R180 S1      
317m4164            VIA   -    MD0080PA01X+049675Y+106314X0160Y         S0      
317m4164            VIA   -    MD0100PA01X+066549Y+145290X0200Y    R180 S0      
327m4164            C746  -2          A01X+066559Y+145790X0120Y0150R270 S1      
327m4164            U26   -BU23       A01X+049491Y+106209X0177Y    R180 S1      
317m4165            VIA   -    MD0080PA01X+048565Y+106951X0160Y         S0      
317m4165            VIA   -    MD0100PA01X+065209Y+145290X0200Y    R180 S0      
327m4165            C748  -2          A01X+065219Y+145790X0120Y0150R270 S1      
327m4165            U26   -BW26       A01X+048381Y+106847X0177Y    R180 S1      
317m4166            VIA   -    MD0080PA01X+048565Y+107589X0160Y         S0      
317m4166            VIA   -    MD0100PA01X+064539Y+146260X0200Y    R180 S0      
327m4166            C750  -2          A01X+064549Y+146760X0120Y0150R270 S1      
327m4166            U26   -CA26       A01X+048381Y+107484X0177Y    R180 S1      
317m4167            VIA   -    MD0080PA01X+048565Y+106314X0160Y         S0      
317m4167            VIA   -    MD0100PA01X+063869Y+147230X0200Y    R180 S0      
327m4167            C752  -2          A01X+063879Y+147730X0120Y0150R270 S1      
327m4167            U26   -BU26       A01X+048381Y+106209X0177Y    R180 S1      
317m4168            VIA   -    MD0080PA01X+045419Y+105995X0160Y         S0      
317m4168            VIA   -    MD0100PA01X+055535Y+150199X0200Y    R270 S0      
327m4168            C772  -2          A01X+056035Y+150189X0120Y0150R180 S1      
327m4168            U26   -BT35       A01X+045235Y+105890X0177Y    R180 S1      
317m4169            VIA   -    MD0080PA01X+062448Y+151970X0160Y         S0      
327m4169            U6016 -BP26       A01X+062243Y+151970X0150Y         S1      
317m4169            VIA   -    MD0080PA01X+048565Y+110778X0160Y         S0      
327m4169            U26   -CL26       A01X+048381Y+110673X0177Y    R180 S1      
317m4170            VIA   -    MD0080PA01X+061976Y+151970X0160Y         S0      
327m4170            U6016 -CA26       A01X+061771Y+151970X0150Y         S1      
317m4170            VIA   -    MD0080PA01X+047455Y+112054X0160Y         S0      
327m4170            U26   -CR29       A01X+047271Y+111949X0177Y    R180 S1      
317m4171            VIA   -    MD0080PA01X+061504Y+151970X0160Y         S0      
327m4171            U6016 -CH26       A01X+061298Y+151970X0150Y         S1      
317m4171            VIA   -    MD0080PA01X+047455Y+112692X0160Y         S0      
327m4171            U26   -CU29       A01X+047271Y+112587X0177Y    R180 S1      
317m4172            VIA   -    MD0080PA01X+061031Y+151970X0160Y         S0      
317m4172            VIA   -    MD0080PA01X+047455Y+111416X0160Y         S0      
327m4172            U26   -CN29       A01X+047271Y+111311X0177Y    R180 S1      
327m4172            U6016 -CR26       A01X+060826Y+151970X0150Y         S1      
317m4173            VIA   -    MD0080PA01X+060559Y+151970X0160Y         S0      
327m4173            U6016 -DB26       A01X+060354Y+151970X0150Y         S1      
317m4173            VIA   -    MD0080PA01X+046344Y+112054X0160Y         S0      
327m4173            U26   -CR32       A01X+046161Y+111949X0177Y    R180 S1      
317m4174            VIA   -    MD0080PA01X+060086Y+151970X0160Y         S0      
317m4174            VIA   -    MD0080PA01X+046344Y+112692X0160Y         S0      
327m4174            U26   -CU32       A01X+046161Y+112587X0177Y    R180 S1      
327m4174            U6016 -DJ26       A01X+059881Y+151970X0150Y         S1      
317m4175            VIA   -    MD0080PA01X+059614Y+151970X0160Y         S0      
327m4175            U6016 -DT26       A01X+059409Y+151970X0150Y         S1      
317m4175            VIA   -    MD0080PA01X+046344Y+111416X0160Y         S0      
327m4175            U26   -CN32       A01X+046161Y+111311X0177Y    R180 S1      
317m4176            VIA   -    MD0080PA01X+059141Y+151970X0160Y         S0      
327m4176            U6016 -EC26       A01X+058936Y+151970X0150Y         S1      
317m4176            VIA   -    MD0080PA01X+045419Y+112373X0160Y         S0      
327m4176            U26   -CT35       A01X+045235Y+112268X0177Y    R180 S1      
317m4177            VIA   -    MD0080PA01X+058669Y+151970X0160Y         S0      
317m4177            VIA   -    MD0080PA01X+045419Y+111735X0160Y         S0      
327m4177            U26   -CP35       A01X+045235Y+111630X0177Y    R180 S1      
327m4177            U6016 -EK26       A01X+058464Y+151970X0150Y         S1      
317m4178            VIA   -    MD0080PA01X+065283Y+151970X0160Y         S0      
317m4178            VIA   -    MD0080PA01X+049675Y+111416X0160Y         S0      
327m4178            U26   -CN23       A01X+049491Y+111311X0177Y    R180 S1      
327m4178            U6016 -M26        A01X+065078Y+151970X0150Y         S1      
317m4179            VIA   -    MD0080PA01X+064811Y+151970X0160Y         S0      
317m4179            VIA   -    MD0080PA01X+049675Y+112054X0160Y         S0      
327m4179            U26   -CR23       A01X+049491Y+111949X0177Y    R180 S1      
327m4179            U6016 -W26        A01X+064606Y+151970X0150Y         S1      
317m4180            VIA   -    MD0080PA01X+064338Y+151970X0160Y         S0      
317m4180            VIA   -    MD0080PA01X+049675Y+110778X0160Y         S0      
327m4180            U26   -CL23       A01X+049491Y+110673X0177Y    R180 S1      
327m4180            U6016 -AF26       A01X+064133Y+151970X0150Y         S1      
317m4181            VIA   -    MD0080PA01X+063866Y+151970X0160Y         S0      
327m4181            U26   -CN26       A01X+048381Y+111311X0177Y    R180 S1      
317m4181            VIA   -    MD0080PA01X+048565Y+111416X0160Y         S0      
327m4181            U6016 -AN26       A01X+063661Y+151970X0150Y         S1      
317m4182            VIA   -    MD0080PA01X+063393Y+151970X0160Y         S0      
317m4182            VIA   -    MD0080PA01X+048565Y+112054X0160Y         S0      
327m4182            U26   -CR26       A01X+048381Y+111949X0177Y    R180 S1      
327m4182            U6016 -AY26       A01X+063188Y+151970X0150Y         S1      
317m4183            VIA   -    MD0080PA01X+062921Y+151970X0160Y         S0      
327m4183            U6016 -BG26       A01X+062716Y+151970X0150Y         S1      
317m4183            VIA   -    MD0080PA01X+048565Y+112692X0160Y         S0      
327m4183            U26   -CU26       A01X+048381Y+112587X0177Y    R180 S1      
317m4184            VIA   -    MD0080PA01X+058196Y+151970X0160Y         S0      
317m4184            VIA   -    MD0080PA01X+045419Y+111097X0160Y         S0      
327m4184            U26   -CM35       A01X+045235Y+110992X0177Y    R180 S1      
327m4184            U6016 -EU26       A01X+057992Y+151970X0150Y         S1      
317m4185            VIA   -    MD0080PA01X+062291Y+151697X0160Y         S0      
327m4185            U6016 -BT29       A01X+062086Y+151697X0150Y         S1      
317m4185            VIA   -    MD0080PA01X+048195Y+110778X0160Y         S0      
327m4185            U26   -CL27       A01X+048011Y+110673X0177Y    R180 S1      
317m4186            VIA   -    MD0080PA01X+061818Y+151697X0160Y         S0      
327m4186            U6016 -CC29       A01X+061614Y+151697X0150Y         S1      
317m4186            VIA   -    MD0080PA01X+047084Y+112054X0160Y         S0      
327m4186            U26   -CR30       A01X+046901Y+111949X0177Y    R180 S1      
317m4187            VIA   -    MD0080PA01X+061346Y+151697X0160Y         S0      
327m4187            U6016 -CK29       A01X+061141Y+151697X0150Y         S1      
317m4187            VIA   -    MD0080PA01X+047084Y+112692X0160Y         S0      
327m4187            U26   -CU30       A01X+046901Y+112587X0177Y    R180 S1      
317m4188            VIA   -    MD0080PA01X+060874Y+151697X0160Y         S0      
317m4188            VIA   -    MD0080PA01X+047084Y+111416X0160Y         S0      
327m4188            U26   -CN30       A01X+046901Y+111311X0177Y    R180 S1      
327m4188            U6016 -CU29       A01X+060669Y+151697X0150Y         S1      
317m4189            VIA   -    MD0080PA01X+060401Y+151697X0160Y         S0      
327m4189            U6016 -DD29       A01X+060196Y+151697X0150Y         S1      
317m4189            VIA   -    MD0080PA01X+045974Y+112054X0160Y         S0      
327m4189            U26   -CR33       A01X+045790Y+111949X0177Y    R180 S1      
317m4190            VIA   -    MD0080PA01X+059929Y+151697X0160Y         S0      
317m4190            VIA   -    MD0080PA01X+045974Y+112692X0160Y         S0      
327m4190            U26   -CU33       A01X+045790Y+112587X0177Y    R180 S1      
327m4190            U6016 -DL29       A01X+059724Y+151697X0150Y         S1      
317m4191            VIA   -    MD0080PA01X+059456Y+151697X0160Y         S0      
327m4191            U6016 -DV29       A01X+059251Y+151697X0150Y         S1      
317m4191            VIA   -    MD0080PA01X+045974Y+111416X0160Y         S0      
327m4191            U26   -CN33       A01X+045790Y+111311X0177Y    R180 S1      
317m4192            VIA   -    MD0080PA01X+058984Y+151697X0160Y         S0      
327m4192            U6016 -EE29       A01X+058779Y+151697X0150Y         S1      
317m4192            VIA   -    MD0080PA01X+045049Y+112373X0160Y         S0      
327m4192            U26   -CT36       A01X+044865Y+112268X0177Y    R180 S1      
317m4193            VIA   -    MD0080PA01X+058511Y+151697X0160Y         S0      
317m4193            VIA   -    MD0080PA01X+045049Y+111735X0160Y         S0      
327m4193            U26   -CP36       A01X+044865Y+111630X0177Y    R180 S1      
327m4193            U6016 -EM29       A01X+058306Y+151697X0150Y         S1      
317m4194            VIA   -    MD0080PA01X+065126Y+151697X0160Y         S0      
317m4194            VIA   -    MD0080PA01X+049305Y+111416X0160Y         S0      
327m4194            U26   -CN24       A01X+049121Y+111311X0177Y    R180 S1      
327m4194            U6016 -P29        A01X+064921Y+151697X0150Y         S1      
317m4195            VIA   -    MD0080PA01X+064653Y+151697X0160Y         S0      
317m4195            VIA   -    MD0080PA01X+049305Y+112054X0160Y         S0      
327m4195            U26   -CR24       A01X+049121Y+111949X0177Y    R180 S1      
327m4195            U6016 -AA29       A01X+064448Y+151697X0150Y         S1      
317m4196            VIA   -    MD0080PA01X+064181Y+151697X0160Y         S0      
317m4196            VIA   -    MD0080PA01X+049305Y+110778X0160Y         S0      
327m4196            U26   -CL24       A01X+049121Y+110673X0177Y    R180 S1      
327m4196            U6016 -AH29       A01X+063976Y+151697X0150Y         S1      
317m4197            VIA   -    MD0080PA01X+063708Y+151697X0160Y         S0      
327m4197            U26   -CN27       A01X+048011Y+111311X0177Y    R180 S1      
317m4197            VIA   -    MD0080PA01X+048195Y+111416X0160Y         S0      
327m4197            U6016 -AR29       A01X+063503Y+151697X0150Y         S1      
317m4198            VIA   -    MD0080PA01X+063236Y+151697X0160Y         S0      
317m4198            VIA   -    MD0080PA01X+048195Y+112054X0160Y         S0      
327m4198            U26   -CR27       A01X+048011Y+111949X0177Y    R180 S1      
327m4198            U6016 -BB29       A01X+063031Y+151697X0150Y         S1      
317m4199            VIA   -    MD0080PA01X+062763Y+151697X0160Y         S0      
327m4199            U6016 -BJ29       A01X+062558Y+151697X0150Y         S1      
317m4199            VIA   -    MD0080PA01X+048195Y+112692X0160Y         S0      
327m4199            U26   -CU27       A01X+048011Y+112587X0177Y    R180 S1      
317m4200            VIA   -    MD0080PA01X+058039Y+151697X0160Y         S0      
317m4200            VIA   -    MD0080PA01X+045049Y+111097X0160Y         S0      
327m4200            U26   -CM36       A01X+044865Y+110992X0177Y    R180 S1      
327m4200            U6016 -EW29       A01X+057834Y+151697X0150Y         S1      
317m4201            VIA   -    MD0080PA01X+040796Y+113329X0160Y         S0      
327m4201            C723  -2          A01X+035761Y+145790X0120Y0150R270 S1      
317m4201            VIA   -    MD0100PA01X+035771Y+145290X0200Y    R180 S0      
327m4201            U26   -CW47       A01X+040980Y+113225X0177Y    R180 S1      
317m4202            VIA   -    MD0080PA01X+040796Y+114605X0160Y         S0      
327m4202            C725  -2          A01X+035091Y+146760X0120Y0150R270 S1      
317m4202            VIA   -    MD0100PA01X+035101Y+146260X0200Y    R180 S0      
327m4202            U26   -DC47       A01X+040980Y+114500X0177Y    R180 S1      
317m4203            VIA   -    MD0080PA01X+040796Y+113967X0160Y         S0      
327m4203            C727  -2          A01X+034421Y+147730X0120Y0150R270 S1      
317m4203            VIA   -    MD0100PA01X+034431Y+147230X0200Y    R180 S0      
327m4203            U26   -DA47       A01X+040980Y+113862X0177Y    R180 S1      
317m4204            VIA   -    MD0080PA01X+039686Y+113329X0160Y         S0      
327m4204            C729  -2          A01X+033081Y+145790X0120Y0150R270 S1      
317m4204            VIA   -    MD0100PA01X+033091Y+145290X0200Y    R180 S0      
327m4204            U26   -CW50       A01X+039869Y+113225X0177Y    R180 S1      
317m4205            VIA   -    MD0080PA01X+039686Y+114605X0160Y         S0      
327m4205            C731  -2          A01X+032411Y+146760X0120Y0150R270 S1      
317m4205            VIA   -    MD0100PA01X+032421Y+146260X0200Y    R180 S0      
327m4205            U26   -DC50       A01X+039869Y+114500X0177Y    R180 S1      
317m4206            VIA   -    MD0080PA01X+039686Y+113967X0160Y         S0      
327m4206            C733  -2          A01X+031741Y+147730X0120Y0150R270 S1      
317m4206            VIA   -    MD0100PA01X+031751Y+147230X0200Y    R180 S0      
327m4206            U26   -DA50       A01X+039869Y+113862X0177Y    R180 S1      
317m4207            VIA   -    MD0080PA01X+038575Y+113329X0160Y         S0      
327m4207            C735  -2          A01X+030401Y+145790X0120Y0150R270 S1      
317m4207            VIA   -    MD0100PA01X+030411Y+145290X0200Y    R180 S0      
327m4207            U26   -CW53       A01X+038759Y+113225X0177Y    R180 S1      
317m4208            VIA   -    MD0080PA01X+038575Y+114605X0160Y         S0      
327m4208            C737  -2          A01X+029731Y+146760X0120Y0150R270 S1      
317m4208            VIA   -    MD0100PA01X+029741Y+146260X0200Y    R180 S0      
327m4208            U26   -DC53       A01X+038759Y+114500X0177Y    R180 S1      
317m4209            VIA   -    MD0080PA01X+038575Y+113967X0160Y         S0      
327m4209            C739  -2          A01X+029618Y+148009X0120Y0150R180 S1      
317m4209            VIA   -    MD0100PA01X+029118Y+148019X0200Y    R270 S0      
327m4209            U26   -DA53       A01X+038759Y+113862X0177Y    R180 S1      
317m4210            VIA   -    MD0080PA01X+042831Y+113010X0160Y         S0      
327m4210            C711  -2          A01X+040368Y+149398X0120Y0150     S1      
317m4210            VIA   -    MD0100PA01X+040868Y+149408X0200Y    R270 S0      
327m4210            U26   -CV41       A01X+043015Y+112906X0177Y    R180 S1      
317m4211            VIA   -    MD0080PA01X+042831Y+113648X0160Y         S0      
327m4211            C713  -2          A01X+040368Y+148418X0120Y0150     S1      
317m4211            VIA   -    MD0100PA01X+040868Y+148408X0200Y    R270 S0      
327m4211            U26   -CY41       A01X+043015Y+113543X0177Y    R180 S1      
317m4212            VIA   -    MD0080PA01X+042831Y+114286X0160Y         S0      
327m4212            C715  -2          A01X+039781Y+145790X0120Y0150R270 S1      
317m4212            VIA   -    MD0100PA01X+039791Y+145290X0200Y    R180 S0      
327m4212            U26   -DB41       A01X+043015Y+114181X0177Y    R180 S1      
317m4213            VIA   -    MD0080PA01X+041906Y+113329X0160Y         S0      
327m4213            C717  -2          A01X+038441Y+145790X0120Y0150R270 S1      
317m4213            VIA   -    MD0100PA01X+038451Y+145290X0200Y    R180 S0      
327m4213            U26   -CW44       A01X+042090Y+113225X0177Y    R180 S1      
317m4214            VIA   -    MD0080PA01X+041906Y+114605X0160Y         S0      
327m4214            C719  -2          A01X+037771Y+146760X0120Y0150R270 S1      
317m4214            VIA   -    MD0100PA01X+037781Y+146260X0200Y    R180 S0      
327m4214            U26   -DC44       A01X+042090Y+114500X0177Y    R180 S1      
317m4215            VIA   -    MD0080PA01X+041906Y+113967X0160Y         S0      
327m4215            C721  -2          A01X+037101Y+147730X0120Y0150R270 S1      
317m4215            VIA   -    MD0100PA01X+037111Y+147230X0200Y    R180 S0      
327m4215            U26   -DA44       A01X+042090Y+113862X0177Y    R180 S1      
317m4216            VIA   -    MD0080PA01X+038575Y+112692X0160Y         S0      
327m4216            C741  -2          A01X+029618Y+150549X0120Y0150R180 S1      
317m4216            VIA   -    MD0100PA01X+029118Y+150539X0200Y    R270 S0      
327m4216            U26   -CU53       A01X+038759Y+112587X0177Y    R180 S1      
317m4217            VIA   -    MD0080PA01X+041166Y+113329X0160Y         S0      
327m4217            C722  -2          A01X+036121Y+145790X0120Y0150R270 S1      
317m4217            VIA   -    MD0100PA01X+036111Y+145290X0200Y    R180 S0      
327m4217            U26   -CW46       A01X+041350Y+113225X0177Y    R180 S1      
317m4218            VIA   -    MD0080PA01X+041166Y+114605X0160Y         S0      
327m4218            C724  -2          A01X+035451Y+146760X0120Y0150R270 S1      
317m4218            VIA   -    MD0100PA01X+035441Y+146260X0200Y    R180 S0      
327m4218            U26   -DC46       A01X+041350Y+114500X0177Y    R180 S1      
317m4219            VIA   -    MD0080PA01X+041166Y+113967X0160Y         S0      
327m4219            C726  -2          A01X+034781Y+147730X0120Y0150R270 S1      
317m4219            VIA   -    MD0100PA01X+034771Y+147230X0200Y    R180 S0      
327m4219            U26   -DA46       A01X+041350Y+113862X0177Y    R180 S1      
317m4220            VIA   -    MD0080PA01X+040056Y+113329X0160Y         S0      
327m4220            C728  -2          A01X+033441Y+145790X0120Y0150R270 S1      
317m4220            VIA   -    MD0100PA01X+033431Y+145290X0200Y    R180 S0      
327m4220            U26   -CW49       A01X+040239Y+113225X0177Y    R180 S1      
317m4221            VIA   -    MD0080PA01X+040056Y+114605X0160Y         S0      
327m4221            C730  -2          A01X+032771Y+146760X0120Y0150R270 S1      
317m4221            VIA   -    MD0100PA01X+032761Y+146260X0200Y    R180 S0      
327m4221            U26   -DC49       A01X+040239Y+114500X0177Y    R180 S1      
317m4222            VIA   -    MD0080PA01X+040056Y+113967X0160Y         S0      
327m4222            C732  -2          A01X+032101Y+147730X0120Y0150R270 S1      
317m4222            VIA   -    MD0100PA01X+032091Y+147230X0200Y    R180 S0      
327m4222            U26   -DA49       A01X+040239Y+113862X0177Y    R180 S1      
317m4223            VIA   -    MD0080PA01X+038945Y+113329X0160Y         S0      
327m4223            C734  -2          A01X+030761Y+145790X0120Y0150R270 S1      
317m4223            VIA   -    MD0100PA01X+030751Y+145290X0200Y    R180 S0      
327m4223            U26   -CW52       A01X+039129Y+113225X0177Y    R180 S1      
317m4224            VIA   -    MD0080PA01X+038945Y+114605X0160Y         S0      
327m4224            C736  -2          A01X+030091Y+146760X0120Y0150R270 S1      
317m4224            VIA   -    MD0100PA01X+030081Y+146260X0200Y    R180 S0      
327m4224            U26   -DC52       A01X+039129Y+114500X0177Y    R180 S1      
317m4225            VIA   -    MD0080PA01X+038945Y+113967X0160Y         S0      
327m4225            C738  -2          A01X+029618Y+148369X0120Y0150R180 S1      
317m4225            VIA   -    MD0100PA01X+029118Y+148359X0200Y    R270 S0      
327m4225            U26   -DA52       A01X+039129Y+113862X0177Y    R180 S1      
317m4226            VIA   -    MD0080PA01X+043201Y+113010X0160Y         S0      
327m4226            C710  -2          A01X+040368Y+149758X0120Y0150     S1      
317m4226            VIA   -    MD0100PA01X+040868Y+149748X0200Y    R270 S0      
327m4226            U26   -CV40       A01X+043385Y+112906X0177Y    R180 S1      
317m4227            VIA   -    MD0080PA01X+043201Y+113648X0160Y         S0      
327m4227            C712  -2          A01X+040368Y+148058X0120Y0150     S1      
317m4227            VIA   -    MD0100PA01X+040868Y+148068X0200Y    R270 S0      
327m4227            U26   -CY40       A01X+043385Y+113543X0177Y    R180 S1      
317m4228            VIA   -    MD0080PA01X+043201Y+114286X0160Y         S0      
327m4228            C714  -2          A01X+040141Y+145790X0120Y0150R270 S1      
317m4228            VIA   -    MD0100PA01X+040131Y+145290X0200Y    R180 S0      
327m4228            U26   -DB40       A01X+043385Y+114181X0177Y    R180 S1      
317m4229            VIA   -    MD0080PA01X+042276Y+113329X0160Y         S0      
327m4229            C716  -2          A01X+038801Y+145790X0120Y0150R270 S1      
317m4229            VIA   -    MD0100PA01X+038791Y+145290X0200Y    R180 S0      
327m4229            U26   -CW43       A01X+042460Y+113225X0177Y    R180 S1      
317m4230            VIA   -    MD0080PA01X+042276Y+114605X0160Y         S0      
327m4230            C718  -2          A01X+038131Y+146760X0120Y0150R270 S1      
317m4230            VIA   -    MD0100PA01X+038121Y+146260X0200Y    R180 S0      
327m4230            U26   -DC43       A01X+042460Y+114500X0177Y    R180 S1      
317m4231            VIA   -    MD0080PA01X+042276Y+113967X0160Y         S0      
327m4231            C720  -2          A01X+037461Y+147730X0120Y0150R270 S1      
317m4231            VIA   -    MD0100PA01X+037451Y+147230X0200Y    R180 S0      
327m4231            U26   -DA43       A01X+042460Y+113862X0177Y    R180 S1      
317m4232            VIA   -    MD0080PA01X+038945Y+112692X0160Y         S0      
327m4232            C740  -2          A01X+029618Y+150189X0120Y0150R180 S1      
317m4232            VIA   -    MD0100PA01X+029118Y+150199X0200Y    R270 S0      
327m4232            U26   -CU52       A01X+039129Y+112587X0177Y    R180 S1      
317m4233            VIA   -    MD0080PA01X+042276Y+108865X0160Y         S0      
317m4233            VIA   -    MD0080PA01X+036031Y+151970X0160Y         S0      
327m4233            U26   -CE43       A01X+042460Y+108760X0177Y    R180 S1      
327m4233            U6015 -BP26       A01X+035826Y+151970X0150Y         S1      
317m4234            VIA   -    MD0080PA01X+041166Y+108227X0160Y         S0      
317m4234            VIA   -    MD0080PA01X+035559Y+151970X0160Y         S0      
327m4234            U26   -CC46       A01X+041350Y+108122X0177Y    R180 S1      
327m4234            U6015 -CA26       A01X+035354Y+151970X0150Y         S1      
317m4235            VIA   -    MD0080PA01X+041166Y+109502X0160Y         S0      
317m4235            VIA   -    MD0080PA01X+035086Y+151970X0160Y         S0      
327m4235            U26   -CG46       A01X+041350Y+109398X0177Y    R180 S1      
327m4235            U6015 -CH26       A01X+034881Y+151970X0150Y         S1      
317m4236            VIA   -    MD0080PA01X+041166Y+108865X0160Y         S0      
317m4236            VIA   -    MD0080PA01X+034614Y+151970X0160Y         S0      
327m4236            U6015 -CR26       A01X+034409Y+151970X0150Y         S1      
327m4236            U26   -CE46       A01X+041350Y+108760X0177Y    R180 S1      
317m4237            VIA   -    MD0080PA01X+040056Y+108227X0160Y         S0      
317m4237            VIA   -    MD0080PA01X+034141Y+151970X0160Y         S0      
327m4237            U6015 -DB26       A01X+033936Y+151970X0150Y         S1      
327m4237            U26   -CC49       A01X+040239Y+108122X0177Y    R180 S1      
317m4238            VIA   -    MD0080PA01X+040056Y+109502X0160Y         S0      
317m4238            VIA   -    MD0080PA01X+033669Y+151970X0160Y         S0      
327m4238            U26   -CG49       A01X+040239Y+109398X0177Y    R180 S1      
327m4238            U6015 -DJ26       A01X+033464Y+151970X0150Y         S1      
317m4239            VIA   -    MD0080PA01X+040056Y+108865X0160Y         S0      
317m4239            VIA   -    MD0080PA01X+033196Y+151970X0160Y         S0      
327m4239            U6015 -DT26       A01X+032992Y+151970X0150Y         S1      
327m4239            U26   -CE49       A01X+040239Y+108760X0177Y    R180 S1      
317m4240            VIA   -    MD0080PA01X+038945Y+108227X0160Y         S0      
317m4240            VIA   -    MD0080PA01X+032724Y+151970X0160Y         S0      
327m4240            U26   -CC52       A01X+039129Y+108122X0177Y    R180 S1      
327m4240            U6015 -EC26       A01X+032519Y+151970X0150Y         S1      
317m4241            VIA   -    MD0080PA01X+038945Y+109502X0160Y         S0      
317m4241            VIA   -    MD0080PA01X+032252Y+151970X0160Y         S0      
327m4241            U26   -CG52       A01X+039129Y+109398X0177Y    R180 S1      
327m4241            U6015 -EK26       A01X+032047Y+151970X0150Y         S1      
317m4242            VIA   -    MD0080PA01X+043201Y+108546X0160Y         S0      
317m4242            VIA   -    MD0080PA01X+038866Y+151970X0160Y         S0      
327m4242            U26   -CD40       A01X+043385Y+108441X0177Y    R180 S1      
327m4242            U6015 -M26        A01X+038661Y+151970X0150Y         S1      
317m4243            VIA   -    MD0080PA01X+043201Y+109184X0160Y         S0      
317m4243            VIA   -    MD0080PA01X+038393Y+151970X0160Y         S0      
327m4243            U6015 -W26        A01X+038188Y+151970X0150Y         S1      
327m4243            U26   -CF40       A01X+043385Y+109079X0177Y    R180 S1      
317m4244            VIA   -    MD0080PA01X+043201Y+109821X0160Y         S0      
317m4244            VIA   -    MD0080PA01X+037921Y+151970X0160Y         S0      
327m4244            U6015 -AF26       A01X+037716Y+151970X0150Y         S1      
327m4244            U26   -CH40       A01X+043385Y+109717X0177Y    R180 S1      
317m4245            VIA   -    MD0080PA01X+042276Y+108227X0160Y         S0      
317m4245            VIA   -    MD0080PA01X+037448Y+151970X0160Y         S0      
327m4245            U6015 -AN26       A01X+037243Y+151970X0150Y         S1      
327m4245            U26   -CC43       A01X+042460Y+108122X0177Y    R180 S1      
317m4246            VIA   -    MD0080PA01X+042276Y+110140X0160Y         S0      
317m4246            VIA   -    MD0080PA01X+036976Y+151970X0160Y         S0      
327m4246            U6015 -AY26       A01X+036771Y+151970X0150Y         S1      
327m4246            U26   -CJ43       A01X+042460Y+110036X0177Y    R180 S1      
317m4247            VIA   -    MD0080PA01X+042276Y+109502X0160Y         S0      
317m4247            VIA   -    MD0080PA01X+036504Y+151970X0160Y         S0      
327m4247            U6015 -BG26       A01X+036299Y+151970X0150Y         S1      
327m4247            U26   -CG43       A01X+042460Y+109398X0177Y    R180 S1      
317m4248            VIA   -    MD0080PA01X+038945Y+108865X0160Y         S0      
317m4248            VIA   -    MD0080PA01X+031779Y+151970X0160Y         S0      
327m4248            U26   -CE52       A01X+039129Y+108760X0177Y    R180 S1      
327m4248            U6015 -EU26       A01X+031574Y+151970X0150Y         S1      
317m4249            VIA   -    MD0080PA01X+041906Y+108865X0160Y         S0      
317m4249            VIA   -    MD0080PA01X+035874Y+151697X0160Y         S0      
327m4249            U26   -CE44       A01X+042090Y+108760X0177Y    R180 S1      
327m4249            U6015 -BT29       A01X+035669Y+151697X0150Y         S1      
317m4250            VIA   -    MD0080PA01X+040796Y+108227X0160Y         S0      
317m4250            VIA   -    MD0080PA01X+035401Y+151697X0160Y         S0      
327m4250            U26   -CC47       A01X+040980Y+108122X0177Y    R180 S1      
327m4250            U6015 -CC29       A01X+035196Y+151697X0150Y         S1      
317m4251            VIA   -    MD0080PA01X+040796Y+109502X0160Y         S0      
317m4251            VIA   -    MD0080PA01X+034929Y+151697X0160Y         S0      
327m4251            U26   -CG47       A01X+040980Y+109398X0177Y    R180 S1      
327m4251            U6015 -CK29       A01X+034724Y+151697X0150Y         S1      
317m4252            VIA   -    MD0080PA01X+040796Y+108865X0160Y         S0      
317m4252            VIA   -    MD0080PA01X+034456Y+151697X0160Y         S0      
327m4252            U6015 -CU29       A01X+034251Y+151697X0150Y         S1      
327m4252            U26   -CE47       A01X+040980Y+108760X0177Y    R180 S1      
317m4253            VIA   -    MD0080PA01X+039686Y+108227X0160Y         S0      
317m4253            VIA   -    MD0080PA01X+033984Y+151697X0160Y         S0      
327m4253            U6015 -DD29       A01X+033779Y+151697X0150Y         S1      
327m4253            U26   -CC50       A01X+039869Y+108122X0177Y    R180 S1      
317m4254            VIA   -    MD0080PA01X+039686Y+109502X0160Y         S0      
317m4254            VIA   -    MD0080PA01X+033511Y+151697X0160Y         S0      
327m4254            U26   -CG50       A01X+039869Y+109398X0177Y    R180 S1      
327m4254            U6015 -DL29       A01X+033306Y+151697X0150Y         S1      
317m4255            VIA   -    MD0080PA01X+039686Y+108865X0160Y         S0      
317m4255            VIA   -    MD0080PA01X+033039Y+151697X0160Y         S0      
327m4255            U6015 -DV29       A01X+032834Y+151697X0150Y         S1      
327m4255            U26   -CE50       A01X+039869Y+108760X0177Y    R180 S1      
317m4256            VIA   -    MD0080PA01X+038575Y+108227X0160Y         S0      
317m4256            VIA   -    MD0080PA01X+032567Y+151697X0160Y         S0      
327m4256            U26   -CC53       A01X+038759Y+108122X0177Y    R180 S1      
327m4256            U6015 -EE29       A01X+032362Y+151697X0150Y         S1      
317m4257            VIA   -    MD0080PA01X+038575Y+109502X0160Y         S0      
317m4257            VIA   -    MD0080PA01X+032094Y+151697X0160Y         S0      
327m4257            U26   -CG53       A01X+038759Y+109398X0177Y    R180 S1      
327m4257            U6015 -EM29       A01X+031889Y+151697X0150Y         S1      
317m4258            VIA   -    MD0080PA01X+042831Y+108546X0160Y         S0      
317m4258            VIA   -    MD0080PA01X+038708Y+151697X0160Y         S0      
327m4258            U26   -CD41       A01X+043015Y+108441X0177Y    R180 S1      
327m4258            U6015 -P29        A01X+038503Y+151697X0150Y         S1      
317m4259            VIA   -    MD0080PA01X+042831Y+109184X0160Y         S0      
317m4259            VIA   -    MD0080PA01X+038236Y+151697X0160Y         S0      
327m4259            U6015 -AA29       A01X+038031Y+151697X0150Y         S1      
327m4259            U26   -CF41       A01X+043015Y+109079X0177Y    R180 S1      
317m4260            VIA   -    MD0080PA01X+042831Y+109821X0160Y         S0      
317m4260            VIA   -    MD0080PA01X+037763Y+151697X0160Y         S0      
327m4260            U6015 -AH29       A01X+037558Y+151697X0150Y         S1      
327m4260            U26   -CH41       A01X+043015Y+109717X0177Y    R180 S1      
317m4261            VIA   -    MD0080PA01X+041906Y+108227X0160Y         S0      
317m4261            VIA   -    MD0080PA01X+037291Y+151697X0160Y         S0      
327m4261            U6015 -AR29       A01X+037086Y+151697X0150Y         S1      
327m4261            U26   -CC44       A01X+042090Y+108122X0177Y    R180 S1      
317m4262            VIA   -    MD0080PA01X+041906Y+110140X0160Y         S0      
317m4262            VIA   -    MD0080PA01X+036818Y+151697X0160Y         S0      
327m4262            U6015 -BB29       A01X+036614Y+151697X0150Y         S1      
327m4262            U26   -CJ44       A01X+042090Y+110036X0177Y    R180 S1      
317m4263            VIA   -    MD0080PA01X+041906Y+109502X0160Y         S0      
317m4263            VIA   -    MD0080PA01X+036346Y+151697X0160Y         S0      
327m4263            U6015 -BJ29       A01X+036141Y+151697X0150Y         S1      
327m4263            U26   -CG44       A01X+042090Y+109398X0177Y    R180 S1      
317m4264            VIA   -    MD0080PA01X+038575Y+108865X0160Y         S0      
317m4264            VIA   -    MD0080PA01X+031622Y+151697X0160Y         S0      
327m4264            U26   -CE53       A01X+038759Y+108760X0177Y    R180 S1      
327m4264            U6015 -EW29       A01X+031417Y+151697X0150Y         S1      
317m4265            VIA   -    MD0080PA01X+040796Y+111416X0160Y         S0      
317m4265            VIA   -    MD0100PA01X+022965Y+145290X0200Y    R180 S0      
327m4265            C819  -2          A01X+022955Y+145790X0120Y0150R270 S1      
327m4265            U26   -CN47       A01X+040980Y+111311X0177Y    R180 S1      
317m4266            VIA   -    MD0080PA01X+040796Y+112692X0160Y         S0      
317m4266            VIA   -    MD0100PA01X+022295Y+146260X0200Y    R180 S0      
327m4266            C821  -2          A01X+022285Y+146760X0120Y0150R270 S1      
327m4266            U26   -CU47       A01X+040980Y+112587X0177Y    R180 S1      
317m4267            VIA   -    MD0080PA01X+040796Y+112054X0160Y         S0      
317m4267            VIA   -    MD0100PA01X+021625Y+147230X0200Y    R180 S0      
327m4267            C823  -2          A01X+021615Y+147730X0120Y0150R270 S1      
327m4267            U26   -CR47       A01X+040980Y+111949X0177Y    R180 S1      
317m4268            VIA   -    MD0080PA01X+039686Y+110778X0160Y         S0      
317m4268            VIA   -    MD0100PA01X+020285Y+145290X0200Y    R180 S0      
327m4268            C825  -2          A01X+020275Y+145790X0120Y0150R270 S1      
327m4268            U26   -CL50       A01X+039869Y+110673X0177Y    R180 S1      
317m4269            VIA   -    MD0080PA01X+039686Y+112692X0160Y         S0      
317m4269            VIA   -    MD0100PA01X+019615Y+146260X0200Y    R180 S0      
327m4269            C827  -2          A01X+019605Y+146760X0120Y0150R270 S1      
327m4269            U26   -CU50       A01X+039869Y+112587X0177Y    R180 S1      
317m4270            VIA   -    MD0080PA01X+039686Y+112054X0160Y         S0      
317m4270            VIA   -    MD0100PA01X+018945Y+147230X0200Y    R180 S0      
327m4270            C829  -2          A01X+018935Y+147730X0120Y0150R270 S1      
327m4270            U26   -CR50       A01X+039869Y+111949X0177Y    R180 S1      
317m4271            VIA   -    MD0080PA01X+039686Y+111416X0160Y         S0      
317m4271            VIA   -    MD0100PA01X+017605Y+145290X0200Y    R180 S0      
327m4271            C831  -2          A01X+017595Y+145790X0120Y0150R270 S1      
327m4271            U26   -CN50       A01X+039869Y+111311X0177Y    R180 S1      
317m4272            VIA   -    MD0080PA01X+038575Y+110778X0160Y         S0      
317m4272            VIA   -    MD0100PA01X+016935Y+146260X0200Y    R180 S0      
327m4272            C833  -2          A01X+016925Y+146760X0120Y0150R270 S1      
327m4272            U26   -CL53       A01X+038759Y+110673X0177Y    R180 S1      
317m4273            VIA   -    MD0080PA01X+038575Y+112054X0160Y         S0      
317m4273            VIA   -    MD0100PA01X+016311Y+148019X0200Y    R090 S0      
327m4273            C835  -2          A01X+016811Y+148009X0120Y0150R180 S1      
327m4273            U26   -CR53       A01X+038759Y+111949X0177Y    R180 S1      
317m4274            VIA   -    MD0100PA01X+028062Y+149408X0200Y    R270 S0      
317m4274            VIA   -    MD0080PA01X+042831Y+111097X0160Y         S0      
327m4274            C807  -2          A01X+027562Y+149398X0120Y0150     S1      
327m4274            U26   -CM41       A01X+043015Y+110992X0177Y    R180 S1      
317m4275            VIA   -    MD0080PA01X+042831Y+111735X0160Y         S0      
317m4275            VIA   -    MD0100PA01X+028062Y+148068X0200Y    R270 S0      
327m4275            C809  -2          A01X+027562Y+148058X0120Y0150     S1      
327m4275            U26   -CP41       A01X+043015Y+111630X0177Y    R180 S1      
317m4276            VIA   -    MD0080PA01X+042831Y+112373X0160Y         S0      
317m4276            VIA   -    MD0100PA01X+027325Y+145290X0200Y    R180 S0      
327m4276            C811  -2          A01X+027335Y+145790X0120Y0150R270 S1      
327m4276            U26   -CT41       A01X+043015Y+112268X0177Y    R180 S1      
317m4277            VIA   -    MD0080PA01X+041906Y+111416X0160Y         S0      
317m4277            VIA   -    MD0100PA01X+025645Y+145290X0200Y    R180 S0      
327m4277            C813  -2          A01X+025635Y+145790X0120Y0150R270 S1      
327m4277            U26   -CN44       A01X+042090Y+111311X0177Y    R180 S1      
317m4278            VIA   -    MD0080PA01X+041906Y+112692X0160Y         S0      
317m4278            VIA   -    MD0100PA01X+024975Y+146260X0200Y    R180 S0      
327m4278            C815  -2          A01X+024965Y+146760X0120Y0150R270 S1      
327m4278            U26   -CU44       A01X+042090Y+112587X0177Y    R180 S1      
317m4279            VIA   -    MD0080PA01X+041906Y+112054X0160Y         S0      
317m4279            VIA   -    MD0100PA01X+024305Y+147230X0200Y    R180 S0      
327m4279            C817  -2          A01X+024295Y+147730X0120Y0150R270 S1      
327m4279            U26   -CR44       A01X+042090Y+111949X0177Y    R180 S1      
317m4280            VIA   -    MD0080PA01X+038575Y+111416X0160Y         S0      
317m4280            VIA   -    MD0100PA01X+016311Y+150539X0200Y    R090 S0      
327m4280            C837  -2          A01X+016811Y+150549X0120Y0150R180 S1      
327m4280            U26   -CN53       A01X+038759Y+111311X0177Y    R180 S1      
317m4281            VIA   -    MD0080PA01X+041166Y+111416X0160Y         S0      
317m4281            VIA   -    MD0100PA01X+023305Y+145290X0200Y    R180 S0      
327m4281            C818  -2          A01X+023315Y+145790X0120Y0150R270 S1      
327m4281            U26   -CN46       A01X+041350Y+111311X0177Y    R180 S1      
317m4282            VIA   -    MD0080PA01X+041166Y+112692X0160Y         S0      
317m4282            VIA   -    MD0100PA01X+022635Y+146260X0200Y    R180 S0      
327m4282            C820  -2          A01X+022645Y+146760X0120Y0150R270 S1      
327m4282            U26   -CU46       A01X+041350Y+112587X0177Y    R180 S1      
317m4283            VIA   -    MD0080PA01X+041166Y+112054X0160Y         S0      
317m4283            VIA   -    MD0100PA01X+021965Y+147230X0200Y    R180 S0      
327m4283            C822  -2          A01X+021975Y+147730X0120Y0150R270 S1      
327m4283            U26   -CR46       A01X+041350Y+111949X0177Y    R180 S1      
317m4284            VIA   -    MD0080PA01X+040056Y+110778X0160Y         S0      
317m4284            VIA   -    MD0100PA01X+020625Y+145290X0200Y    R180 S0      
327m4284            C824  -2          A01X+020635Y+145790X0120Y0150R270 S1      
327m4284            U26   -CL49       A01X+040239Y+110673X0177Y    R180 S1      
317m4285            VIA   -    MD0080PA01X+040056Y+112692X0160Y         S0      
317m4285            VIA   -    MD0100PA01X+019955Y+146260X0200Y    R180 S0      
327m4285            C826  -2          A01X+019965Y+146760X0120Y0150R270 S1      
327m4285            U26   -CU49       A01X+040239Y+112587X0177Y    R180 S1      
317m4286            VIA   -    MD0080PA01X+040056Y+112054X0160Y         S0      
317m4286            VIA   -    MD0100PA01X+019285Y+147230X0200Y    R180 S0      
327m4286            C828  -2          A01X+019295Y+147730X0120Y0150R270 S1      
327m4286            U26   -CR49       A01X+040239Y+111949X0177Y    R180 S1      
317m4287            VIA   -    MD0080PA01X+040056Y+111416X0160Y         S0      
317m4287            VIA   -    MD0100PA01X+017945Y+145290X0200Y    R180 S0      
327m4287            C830  -2          A01X+017955Y+145790X0120Y0150R270 S1      
327m4287            U26   -CN49       A01X+040239Y+111311X0177Y    R180 S1      
317m4288            VIA   -    MD0080PA01X+038945Y+110778X0160Y         S0      
317m4288            VIA   -    MD0100PA01X+017275Y+146260X0200Y    R180 S0      
327m4288            C832  -2          A01X+017285Y+146760X0120Y0150R270 S1      
327m4288            U26   -CL52       A01X+039129Y+110673X0177Y    R180 S1      
317m4289            VIA   -    MD0080PA01X+038945Y+112054X0160Y         S0      
317m4289            VIA   -    MD0100PA01X+016311Y+148359X0200Y    R090 S0      
327m4289            C834  -2          A01X+016811Y+148369X0120Y0150R180 S1      
327m4289            U26   -CR52       A01X+039129Y+111949X0177Y    R180 S1      
317m4290            VIA   -    MD0100PA01X+028062Y+149748X0200Y    R270 S0      
317m4290            VIA   -    MD0080PA01X+043201Y+111097X0160Y         S0      
327m4290            C806  -2          A01X+027562Y+149758X0120Y0150     S1      
327m4290            U26   -CM40       A01X+043385Y+110992X0177Y    R180 S1      
317m4291            VIA   -    MD0080PA01X+043201Y+111735X0160Y         S0      
317m4291            VIA   -    MD0100PA01X+028062Y+148408X0200Y    R270 S0      
327m4291            C808  -2          A01X+027562Y+148418X0120Y0150     S1      
327m4291            U26   -CP40       A01X+043385Y+111630X0177Y    R180 S1      
317m4292            VIA   -    MD0080PA01X+043201Y+112373X0160Y         S0      
317m4292            VIA   -    MD0100PA01X+026985Y+145290X0200Y    R180 S0      
327m4292            C810  -2          A01X+026975Y+145790X0120Y0150R270 S1      
327m4292            U26   -CT40       A01X+043385Y+112268X0177Y    R180 S1      
317m4293            VIA   -    MD0080PA01X+042276Y+111416X0160Y         S0      
317m4293            VIA   -    MD0100PA01X+025985Y+145290X0200Y    R180 S0      
327m4293            C812  -2          A01X+025995Y+145790X0120Y0150R270 S1      
327m4293            U26   -CN43       A01X+042460Y+111311X0177Y    R180 S1      
317m4294            VIA   -    MD0080PA01X+042276Y+112692X0160Y         S0      
317m4294            VIA   -    MD0100PA01X+025315Y+146260X0200Y    R180 S0      
327m4294            C814  -2          A01X+025325Y+146760X0120Y0150R270 S1      
327m4294            U26   -CU43       A01X+042460Y+112587X0177Y    R180 S1      
317m4295            VIA   -    MD0080PA01X+042276Y+112054X0160Y         S0      
317m4295            VIA   -    MD0100PA01X+024645Y+147230X0200Y    R180 S0      
327m4295            C816  -2          A01X+024655Y+147730X0120Y0150R270 S1      
327m4295            U26   -CR43       A01X+042460Y+111949X0177Y    R180 S1      
317m4296            VIA   -    MD0080PA01X+038945Y+111416X0160Y         S0      
317m4296            VIA   -    MD0100PA01X+016311Y+150199X0200Y    R090 S0      
327m4296            C836  -2          A01X+016811Y+150189X0120Y0150R180 S1      
327m4296            U26   -CN52       A01X+039129Y+111311X0177Y    R180 S1      
317m4297            VIA   -    MD0080PA01X+042276Y+106951X0160Y         S0      
317m4297            VIA   -    MD0080PA01X+023225Y+151970X0160Y         S0      
327m4297            U26   -BW43       A01X+042460Y+106847X0177Y    R180 S1      
327m4297            U6014 -BP26       A01X+023020Y+151970X0150Y         S1      
317m4298            VIA   -    MD0080PA01X+041166Y+106314X0160Y         S0      
317m4298            VIA   -    MD0080PA01X+022752Y+151970X0160Y         S0      
327m4298            U26   -BU46       A01X+041350Y+106209X0177Y    R180 S1      
327m4298            U6014 -CA26       A01X+022548Y+151970X0150Y         S1      
317m4299            VIA   -    MD0080PA01X+041166Y+107589X0160Y         S0      
317m4299            VIA   -    MD0080PA01X+022280Y+151970X0160Y         S0      
327m4299            U26   -CA46       A01X+041350Y+107484X0177Y    R180 S1      
327m4299            U6014 -CH26       A01X+022075Y+151970X0150Y         S1      
317m4300            VIA   -    MD0080PA01X+041166Y+106951X0160Y         S0      
317m4300            VIA   -    MD0080PA01X+021808Y+151970X0160Y         S0      
327m4300            U26   -BW46       A01X+041350Y+106847X0177Y    R180 S1      
327m4300            U6014 -CR26       A01X+021603Y+151970X0150Y         S1      
317m4301            VIA   -    MD0080PA01X+040056Y+106314X0160Y         S0      
317m4301            VIA   -    MD0080PA01X+021335Y+151970X0160Y         S0      
327m4301            U26   -BU49       A01X+040239Y+106209X0177Y    R180 S1      
327m4301            U6014 -DB26       A01X+021130Y+151970X0150Y         S1      
317m4302            VIA   -    MD0080PA01X+040056Y+107589X0160Y         S0      
317m4302            VIA   -    MD0080PA01X+020863Y+151970X0160Y         S0      
327m4302            U26   -CA49       A01X+040239Y+107484X0177Y    R180 S1      
327m4302            U6014 -DJ26       A01X+020658Y+151970X0150Y         S1      
317m4303            VIA   -    MD0080PA01X+040056Y+106951X0160Y         S0      
317m4303            VIA   -    MD0080PA01X+020390Y+151970X0160Y         S0      
327m4303            U26   -BW49       A01X+040239Y+106847X0177Y    R180 S1      
327m4303            U6014 -DT26       A01X+020185Y+151970X0150Y         S1      
317m4304            VIA   -    MD0080PA01X+038945Y+106314X0160Y         S0      
317m4304            VIA   -    MD0080PA01X+019918Y+151970X0160Y         S0      
327m4304            U26   -BU52       A01X+039129Y+106209X0177Y    R180 S1      
327m4304            U6014 -EC26       A01X+019713Y+151970X0150Y         S1      
317m4305            VIA   -    MD0080PA01X+038945Y+107589X0160Y         S0      
317m4305            VIA   -    MD0080PA01X+019445Y+151970X0160Y         S0      
327m4305            U26   -CA52       A01X+039129Y+107484X0177Y    R180 S1      
327m4305            U6014 -EK26       A01X+019240Y+151970X0150Y         S1      
317m4306            VIA   -    MD0080PA01X+043201Y+105995X0160Y         S0      
317m4306            VIA   -    MD0080PA01X+026060Y+151970X0160Y         S0      
327m4306            U26   -BT40       A01X+043385Y+105890X0177Y    R180 S1      
327m4306            U6014 -M26        A01X+025855Y+151970X0150Y         S1      
317m4307            VIA   -    MD0080PA01X+043201Y+106632X0160Y         S0      
317m4307            VIA   -    MD0080PA01X+025587Y+151970X0160Y         S0      
327m4307            U26   -BV40       A01X+043385Y+106528X0177Y    R180 S1      
327m4307            U6014 -W26        A01X+025382Y+151970X0150Y         S1      
317m4308            VIA   -    MD0080PA01X+043201Y+107908X0160Y         S0      
317m4308            VIA   -    MD0080PA01X+025115Y+151970X0160Y         S0      
327m4308            U26   -CB40       A01X+043385Y+107803X0177Y    R180 S1      
327m4308            U6014 -AF26       A01X+024910Y+151970X0150Y         S1      
317m4309            VIA   -    MD0080PA01X+043201Y+107270X0160Y         S0      
317m4309            VIA   -    MD0080PA01X+024642Y+151970X0160Y         S0      
327m4309            U26   -BY40       A01X+043385Y+107166X0177Y    R180 S1      
327m4309            U6014 -AN26       A01X+024437Y+151970X0150Y         S1      
317m4310            VIA   -    MD0080PA01X+042276Y+106314X0160Y         S0      
317m4310            VIA   -    MD0080PA01X+024170Y+151970X0160Y         S0      
327m4310            U26   -BU43       A01X+042460Y+106209X0177Y    R180 S1      
327m4310            U6014 -AY26       A01X+023965Y+151970X0150Y         S1      
317m4311            VIA   -    MD0080PA01X+042276Y+107589X0160Y         S0      
317m4311            VIA   -    MD0080PA01X+023697Y+151970X0160Y         S0      
327m4311            U26   -CA43       A01X+042460Y+107484X0177Y    R180 S1      
327m4311            U6014 -BG26       A01X+023492Y+151970X0150Y         S1      
317m4312            VIA   -    MD0080PA01X+038945Y+106951X0160Y         S0      
317m4312            VIA   -    MD0080PA01X+018973Y+151970X0160Y         S0      
327m4312            U26   -BW52       A01X+039129Y+106847X0177Y    R180 S1      
327m4312            U6014 -EU26       A01X+018768Y+151970X0150Y         S1      
317m4313            VIA   -    MD0080PA01X+041906Y+106951X0160Y         S0      
317m4313            VIA   -    MD0080PA01X+023067Y+151697X0160Y         S0      
327m4313            U26   -BW44       A01X+042090Y+106847X0177Y    R180 S1      
327m4313            U6014 -BT29       A01X+022862Y+151697X0150Y         S1      
317m4314            VIA   -    MD0080PA01X+040796Y+106314X0160Y         S0      
317m4314            VIA   -    MD0080PA01X+022595Y+151697X0160Y         S0      
327m4314            U26   -BU47       A01X+040980Y+106209X0177Y    R180 S1      
327m4314            U6014 -CC29       A01X+022390Y+151697X0150Y         S1      
317m4315            VIA   -    MD0080PA01X+040796Y+107589X0160Y         S0      
317m4315            VIA   -    MD0080PA01X+022123Y+151697X0160Y         S0      
327m4315            U26   -CA47       A01X+040980Y+107484X0177Y    R180 S1      
327m4315            U6014 -CK29       A01X+021918Y+151697X0150Y         S1      
317m4316            VIA   -    MD0080PA01X+040796Y+106951X0160Y         S0      
317m4316            VIA   -    MD0080PA01X+021650Y+151697X0160Y         S0      
327m4316            U26   -BW47       A01X+040980Y+106847X0177Y    R180 S1      
327m4316            U6014 -CU29       A01X+021445Y+151697X0150Y         S1      
317m4317            VIA   -    MD0080PA01X+039686Y+106314X0160Y         S0      
317m4317            VIA   -    MD0080PA01X+021178Y+151697X0160Y         S0      
327m4317            U26   -BU50       A01X+039869Y+106209X0177Y    R180 S1      
327m4317            U6014 -DD29       A01X+020973Y+151697X0150Y         S1      
317m4318            VIA   -    MD0080PA01X+039686Y+107589X0160Y         S0      
317m4318            VIA   -    MD0080PA01X+020705Y+151697X0160Y         S0      
327m4318            U26   -CA50       A01X+039869Y+107484X0177Y    R180 S1      
327m4318            U6014 -DL29       A01X+020500Y+151697X0150Y         S1      
317m4319            VIA   -    MD0080PA01X+039686Y+106951X0160Y         S0      
317m4319            VIA   -    MD0080PA01X+020233Y+151697X0160Y         S0      
327m4319            U26   -BW50       A01X+039869Y+106847X0177Y    R180 S1      
327m4319            U6014 -DV29       A01X+020028Y+151697X0150Y         S1      
317m4320            VIA   -    MD0080PA01X+038575Y+106314X0160Y         S0      
317m4320            VIA   -    MD0080PA01X+019760Y+151697X0160Y         S0      
327m4320            U26   -BU53       A01X+038759Y+106209X0177Y    R180 S1      
327m4320            U6014 -EE29       A01X+019555Y+151697X0150Y         S1      
317m4321            VIA   -    MD0080PA01X+038575Y+107589X0160Y         S0      
317m4321            VIA   -    MD0080PA01X+019288Y+151697X0160Y         S0      
327m4321            U26   -CA53       A01X+038759Y+107484X0177Y    R180 S1      
327m4321            U6014 -EM29       A01X+019083Y+151697X0150Y         S1      
317m4322            VIA   -    MD0080PA01X+042831Y+105995X0160Y         S0      
317m4322            VIA   -    MD0080PA01X+025902Y+151697X0160Y         S0      
327m4322            U26   -BT41       A01X+043015Y+105890X0177Y    R180 S1      
327m4322            U6014 -P29        A01X+025697Y+151697X0150Y         S1      
317m4323            VIA   -    MD0080PA01X+042831Y+106632X0160Y         S0      
317m4323            VIA   -    MD0080PA01X+025430Y+151697X0160Y         S0      
327m4323            U26   -BV41       A01X+043015Y+106528X0177Y    R180 S1      
327m4323            U6014 -AA29       A01X+025225Y+151697X0150Y         S1      
317m4324            VIA   -    MD0080PA01X+042831Y+107908X0160Y         S0      
317m4324            VIA   -    MD0080PA01X+024957Y+151697X0160Y         S0      
327m4324            U26   -CB41       A01X+043015Y+107803X0177Y    R180 S1      
327m4324            U6014 -AH29       A01X+024752Y+151697X0150Y         S1      
317m4325            VIA   -    MD0080PA01X+042831Y+107270X0160Y         S0      
317m4325            VIA   -    MD0080PA01X+024485Y+151697X0160Y         S0      
327m4325            U26   -BY41       A01X+043015Y+107166X0177Y    R180 S1      
327m4325            U6014 -AR29       A01X+024280Y+151697X0150Y         S1      
317m4326            VIA   -    MD0080PA01X+041906Y+106314X0160Y         S0      
317m4326            VIA   -    MD0080PA01X+024012Y+151697X0160Y         S0      
327m4326            U26   -BU44       A01X+042090Y+106209X0177Y    R180 S1      
327m4326            U6014 -BB29       A01X+023807Y+151697X0150Y         S1      
317m4327            VIA   -    MD0080PA01X+041906Y+107589X0160Y         S0      
317m4327            VIA   -    MD0080PA01X+023540Y+151697X0160Y         S0      
327m4327            U26   -CA44       A01X+042090Y+107484X0177Y    R180 S1      
327m4327            U6014 -BJ29       A01X+023335Y+151697X0150Y         S1      
317m4328            VIA   -    MD0080PA01X+038575Y+106951X0160Y         S0      
317m4328            VIA   -    MD0080PA01X+018816Y+151697X0160Y         S0      
327m4328            U26   -BW53       A01X+038759Y+106847X0177Y    R180 S1      
327m4328            U6014 -EW29       A01X+018610Y+151697X0150Y         S1      
317m4329            VIA   -    MD0080PA01X+144699Y+108227X0160Y         S0      
327m4329            U25   -CC30       A01X+144515Y+108122X0177Y    R180 S1      
317m4329            VIA   -    MD0100PA01X+148830Y+150530X0200Y    R180 S0      
327m4329            C887  -2          A01X+148820Y+151030X0120Y0150R270 S1      
317m4330            VIA   -    MD0080PA01X+143588Y+108865X0160Y         S0      
317m4330            VIA   -    MD0100PA01X+147490Y+148590X0200Y    R180 S0      
327m4330            C889  -2          A01X+147480Y+149090X0120Y0150R270 S1      
327m4330            U25   -CE33       A01X+143405Y+108760X0177Y    R180 S1      
317m4331            VIA   -    MD0080PA01X+143588Y+109502X0160Y         S0      
317m4331            VIA   -    MD0100PA01X+146820Y+149560X0200Y    R180 S0      
327m4331            C891  -2          A01X+146810Y+150060X0120Y0150R270 S1      
327m4331            U25   -CG33       A01X+143405Y+109398X0177Y    R180 S1      
317m4332            VIA   -    MD0080PA01X+143588Y+110140X0160Y         S0      
317m4332            VIA   -    MD0100PA01X+146150Y+150530X0200Y    R180 S0      
327m4332            C893  -2          A01X+146140Y+151030X0120Y0150R270 S1      
327m4332            U25   -CJ33       A01X+143405Y+110036X0177Y    R180 S1      
317m4333            VIA   -    MD0080PA01X+145069Y+108227X0160Y         S0      
327m4333            U25   -CC29       A01X+144885Y+108122X0177Y    R180 S1      
317m4333            VIA   -    MD0100PA01X+149170Y+150530X0200Y    R180 S0      
327m4333            C886  -2          A01X+149180Y+151030X0120Y0150R270 S1      
317m4334            VIA   -    MD0080PA01X+143959Y+108865X0160Y         S0      
317m4334            VIA   -    MD0100PA01X+147830Y+148590X0200Y    R180 S0      
327m4334            C888  -2          A01X+147840Y+149090X0120Y0150R270 S1      
327m4334            U25   -CE32       A01X+143775Y+108760X0177Y    R180 S1      
317m4335            VIA   -    MD0080PA01X+143959Y+109502X0160Y         S0      
317m4335            VIA   -    MD0100PA01X+147160Y+149560X0200Y    R180 S0      
327m4335            C890  -2          A01X+147170Y+150060X0120Y0150R270 S1      
327m4335            U25   -CG32       A01X+143775Y+109398X0177Y    R180 S1      
317m4336            VIA   -    MD0080PA01X+143959Y+110140X0160Y         S0      
317m4336            VIA   -    MD0100PA01X+146490Y+150530X0200Y    R180 S0      
327m4336            C892  -2          A01X+146500Y+151030X0120Y0150R270 S1      
327m4336            U25   -CJ32       A01X+143775Y+110036X0177Y    R180 S1      
317m4337            VIA   -    MD0080PA01X+149485Y+155270X0160Y         S0      
317m4337            VIA   -    MD0080PA01X+145069Y+114605X0160Y         S0      
327m4337            U25   -DC29       A01X+144885Y+114500X0177Y    R180 S1      
327m4337            U6013 -CH26       A01X+149280Y+155270X0150Y         S1      
317m4338            VIA   -    MD0080PA01X+149012Y+155270X0160Y         S0      
317m4338            VIA   -    MD0080PA01X+145069Y+113329X0160Y         S0      
327m4338            U25   -CW29       A01X+144885Y+113224X0177Y    R180 S1      
327m4338            U6013 -CR26       A01X+148807Y+155270X0150Y         S1      
317m4339            VIA   -    MD0080PA01X+148540Y+155270X0160Y         S0      
317m4339            VIA   -    MD0080PA01X+143959Y+113967X0160Y         S0      
327m4339            U25   -DA32       A01X+143775Y+113862X0177Y    R180 S1      
327m4339            U6013 -DB26       A01X+148335Y+155270X0150Y         S1      
317m4340            VIA   -    MD0080PA01X+148067Y+155270X0160Y         S0      
317m4340            VIA   -    MD0080PA01X+143959Y+114605X0160Y         S0      
327m4340            U25   -DC32       A01X+143775Y+114500X0177Y    R180 S1      
327m4340            U6013 -DJ26       A01X+147862Y+155270X0150Y         S1      
317m4341            VIA   -    MD0080PA01X+149327Y+154997X0160Y         S0      
317m4341            VIA   -    MD0080PA01X+144699Y+114605X0160Y         S0      
327m4341            U25   -DC30       A01X+144515Y+114500X0177Y    R180 S1      
327m4341            U6013 -CK29       A01X+149122Y+154997X0150Y         S1      
317m4342            VIA   -    MD0080PA01X+148855Y+154997X0160Y         S0      
317m4342            VIA   -    MD0080PA01X+144699Y+113329X0160Y         S0      
327m4342            U25   -CW30       A01X+144515Y+113224X0177Y    R180 S1      
327m4342            U6013 -CU29       A01X+148650Y+154997X0150Y         S1      
317m4343            VIA   -    MD0080PA01X+148382Y+154997X0160Y         S0      
317m4343            VIA   -    MD0080PA01X+143588Y+113967X0160Y         S0      
327m4343            U25   -DA33       A01X+143405Y+113862X0177Y    R180 S1      
327m4343            U6013 -DD29       A01X+148177Y+154997X0150Y         S1      
317m4344            VIA   -    MD0080PA01X+147910Y+154997X0160Y         S0      
317m4344            VIA   -    MD0080PA01X+143588Y+114605X0160Y         S0      
327m4344            U25   -DC33       A01X+143405Y+114500X0177Y    R180 S1      
327m4344            U6013 -DL29       A01X+147705Y+154997X0150Y         S1      
317m4345            VIA   -    MD0080PA01X+144699Y+106951X0160Y         S0      
317m4345            VIA   -    MD0100PA01X+162976Y+148590X0200Y    R180 S0      
327m4345            C851  -2          A01X+162966Y+149090X0120Y0150R270 S1      
327m4345            U25   -BW30       A01X+144515Y+106846X0177Y    R180 S1      
317m4346            VIA   -    MD0080PA01X+144699Y+107589X0160Y         S0      
317m4346            VIA   -    MD0100PA01X+162306Y+149560X0200Y    R180 S0      
327m4346            C853  -2          A01X+162296Y+150060X0120Y0150R270 S1      
327m4346            U25   -CA30       A01X+144515Y+107484X0177Y    R180 S1      
317m4347            VIA   -    MD0080PA01X+144699Y+106313X0160Y         S0      
317m4347            VIA   -    MD0100PA01X+161636Y+150530X0200Y    R180 S0      
327m4347            C855  -2          A01X+161626Y+151030X0120Y0150R270 S1      
327m4347            U25   -BU30       A01X+144515Y+106209X0177Y    R180 S1      
317m4348            VIA   -    MD0080PA01X+143588Y+106951X0160Y         S0      
317m4348            VIA   -    MD0100PA01X+160296Y+148590X0200Y    R180 S0      
327m4348            C857  -2          A01X+160286Y+149090X0120Y0150R270 S1      
327m4348            U25   -BW33       A01X+143405Y+106846X0177Y    R180 S1      
317m4349            VIA   -    MD0080PA01X+143588Y+107589X0160Y         S0      
317m4349            VIA   -    MD0100PA01X+159626Y+149560X0200Y    R180 S0      
327m4349            C859  -2          A01X+159616Y+150060X0120Y0150R270 S1      
327m4349            U25   -CA33       A01X+143405Y+107484X0177Y    R180 S1      
317m4350            VIA   -    MD0080PA01X+143588Y+106313X0160Y         S0      
317m4350            VIA   -    MD0100PA01X+158956Y+150530X0200Y    R180 S0      
327m4350            C861  -2          A01X+158946Y+151030X0120Y0150R270 S1      
327m4350            U25   -BU33       A01X+143405Y+106209X0177Y    R180 S1      
317m4351            VIA   -    MD0080PA01X+142663Y+107270X0160Y         S0      
317m4351            VIA   -    MD0100PA01X+157616Y+148590X0200Y    R180 S0      
327m4351            C863  -2          A01X+157606Y+149090X0120Y0150R270 S1      
327m4351            U25   -BY36       A01X+142480Y+107165X0177Y    R180 S1      
317m4352            VIA   -    MD0080PA01X+142663Y+107908X0160Y         S0      
317m4352            VIA   -    MD0100PA01X+156946Y+149560X0200Y    R180 S0      
327m4352            C865  -2          A01X+156936Y+150060X0120Y0150R270 S1      
327m4352            U25   -CB36       A01X+142480Y+107803X0177Y    R180 S1      
317m4353            VIA   -    MD0080PA01X+142663Y+106632X0160Y         S0      
317m4353            VIA   -    MD0100PA01X+156322Y+151319X0200Y    R270 S0      
327m4353            C867  -2          A01X+156822Y+151309X0120Y0150R180 S1      
327m4353            U25   -BV36       A01X+142480Y+106528X0177Y    R180 S1      
317m4354            VIA   -    MD0080PA01X+146919Y+106951X0160Y         S0      
317m4354            VIA   -    MD0100PA01X+168073Y+152708X0200Y    R270 S0      
327m4354            U25   -BW24       A01X+146735Y+106846X0177Y    R180 S1      
327m4354            C839  -2          A01X+167573Y+152698X0120Y0150     S1      
317m4355            VIA   -    MD0080PA01X+146919Y+107589X0160Y         S0      
317m4355            VIA   -    MD0100PA01X+168073Y+151368X0200Y    R270 S0      
327m4355            U25   -CA24       A01X+146735Y+107484X0177Y    R180 S1      
327m4355            C841  -2          A01X+167573Y+151358X0120Y0150     S1      
317m4356            VIA   -    MD0080PA01X+146919Y+106313X0160Y         S0      
317m4356            VIA   -    MD0100PA01X+166996Y+148590X0200Y    R180 S0      
327m4356            C843  -2          A01X+166986Y+149090X0120Y0150R270 S1      
327m4356            U25   -BU24       A01X+146735Y+106209X0177Y    R180 S1      
317m4357            VIA   -    MD0080PA01X+145809Y+106951X0160Y         S0      
317m4357            VIA   -    MD0100PA01X+165656Y+148590X0200Y    R180 S0      
327m4357            C845  -2          A01X+165646Y+149090X0120Y0150R270 S1      
327m4357            U25   -BW27       A01X+145625Y+106846X0177Y    R180 S1      
317m4358            VIA   -    MD0080PA01X+145809Y+107589X0160Y         S0      
317m4358            VIA   -    MD0100PA01X+164986Y+149560X0200Y    R180 S0      
327m4358            C847  -2          A01X+164976Y+150060X0120Y0150R270 S1      
327m4358            U25   -CA27       A01X+145625Y+107484X0177Y    R180 S1      
317m4359            VIA   -    MD0080PA01X+145809Y+106313X0160Y         S0      
317m4359            VIA   -    MD0100PA01X+164316Y+150530X0200Y    R180 S0      
327m4359            C849  -2          A01X+164306Y+151030X0120Y0150R270 S1      
327m4359            U25   -BU27       A01X+145625Y+106209X0177Y    R180 S1      
317m4360            VIA   -    MD0080PA01X+142663Y+105994X0160Y         S0      
317m4360            VIA   -    MD0100PA01X+156322Y+153839X0200Y    R270 S0      
327m4360            C869  -2          A01X+156822Y+153849X0120Y0150R180 S1      
327m4360            U25   -BT36       A01X+142480Y+105890X0177Y    R180 S1      
317m4361            VIA   -    MD0080PA01X+145069Y+106951X0160Y         S0      
317m4361            VIA   -    MD0100PA01X+163316Y+148590X0200Y    R180 S0      
327m4361            C850  -2          A01X+163326Y+149090X0120Y0150R270 S1      
327m4361            U25   -BW29       A01X+144885Y+106846X0177Y    R180 S1      
317m4362            VIA   -    MD0080PA01X+145069Y+107589X0160Y         S0      
317m4362            VIA   -    MD0100PA01X+162646Y+149560X0200Y    R180 S0      
327m4362            C852  -2          A01X+162656Y+150060X0120Y0150R270 S1      
327m4362            U25   -CA29       A01X+144885Y+107484X0177Y    R180 S1      
317m4363            VIA   -    MD0080PA01X+145069Y+106313X0160Y         S0      
317m4363            VIA   -    MD0100PA01X+161976Y+150530X0200Y    R180 S0      
327m4363            C854  -2          A01X+161986Y+151030X0120Y0150R270 S1      
327m4363            U25   -BU29       A01X+144885Y+106209X0177Y    R180 S1      
317m4364            VIA   -    MD0080PA01X+143959Y+106951X0160Y         S0      
317m4364            VIA   -    MD0100PA01X+160636Y+148590X0200Y    R180 S0      
327m4364            C856  -2          A01X+160646Y+149090X0120Y0150R270 S1      
327m4364            U25   -BW32       A01X+143775Y+106846X0177Y    R180 S1      
317m4365            VIA   -    MD0080PA01X+143959Y+107589X0160Y         S0      
317m4365            VIA   -    MD0100PA01X+159966Y+149560X0200Y    R180 S0      
327m4365            C858  -2          A01X+159976Y+150060X0120Y0150R270 S1      
327m4365            U25   -CA32       A01X+143775Y+107484X0177Y    R180 S1      
317m4366            VIA   -    MD0080PA01X+143959Y+106313X0160Y         S0      
317m4366            VIA   -    MD0100PA01X+159296Y+150530X0200Y    R180 S0      
327m4366            C860  -2          A01X+159306Y+151030X0120Y0150R270 S1      
327m4366            U25   -BU32       A01X+143775Y+106209X0177Y    R180 S1      
317m4367            VIA   -    MD0080PA01X+143033Y+107270X0160Y         S0      
317m4367            VIA   -    MD0100PA01X+157956Y+148590X0200Y    R180 S0      
327m4367            C862  -2          A01X+157966Y+149090X0120Y0150R270 S1      
327m4367            U25   -BY35       A01X+142850Y+107165X0177Y    R180 S1      
317m4368            VIA   -    MD0080PA01X+143033Y+107908X0160Y         S0      
317m4368            VIA   -    MD0100PA01X+157286Y+149560X0200Y    R180 S0      
327m4368            C864  -2          A01X+157296Y+150060X0120Y0150R270 S1      
327m4368            U25   -CB35       A01X+142850Y+107803X0177Y    R180 S1      
317m4369            VIA   -    MD0080PA01X+143033Y+106632X0160Y         S0      
317m4369            VIA   -    MD0100PA01X+156322Y+151659X0200Y    R270 S0      
327m4369            C866  -2          A01X+156822Y+151669X0120Y0150R180 S1      
327m4369            U25   -BV35       A01X+142850Y+106528X0177Y    R180 S1      
317m4370            VIA   -    MD0080PA01X+147289Y+106951X0160Y         S0      
317m4370            VIA   -    MD0100PA01X+168073Y+153048X0200Y    R270 S0      
327m4370            U25   -BW23       A01X+147106Y+106846X0177Y    R180 S1      
327m4370            C838  -2          A01X+167573Y+153058X0120Y0150     S1      
317m4371            VIA   -    MD0080PA01X+147289Y+107589X0160Y         S0      
317m4371            VIA   -    MD0100PA01X+168073Y+151708X0200Y    R270 S0      
327m4371            U25   -CA23       A01X+147106Y+107484X0177Y    R180 S1      
327m4371            C840  -2          A01X+167573Y+151718X0120Y0150     S1      
317m4372            VIA   -    MD0080PA01X+147289Y+106313X0160Y         S0      
317m4372            VIA   -    MD0100PA01X+167336Y+148590X0200Y    R180 S0      
327m4372            C842  -2          A01X+167346Y+149090X0120Y0150R270 S1      
327m4372            U25   -BU23       A01X+147106Y+106209X0177Y    R180 S1      
317m4373            VIA   -    MD0080PA01X+146179Y+106951X0160Y         S0      
317m4373            VIA   -    MD0100PA01X+165996Y+148590X0200Y    R180 S0      
327m4373            C844  -2          A01X+166006Y+149090X0120Y0150R270 S1      
327m4373            U25   -BW26       A01X+145995Y+106846X0177Y    R180 S1      
317m4374            VIA   -    MD0080PA01X+146179Y+107589X0160Y         S0      
317m4374            VIA   -    MD0100PA01X+165326Y+149560X0200Y    R180 S0      
327m4374            C846  -2          A01X+165336Y+150060X0120Y0150R270 S1      
327m4374            U25   -CA26       A01X+145995Y+107484X0177Y    R180 S1      
317m4375            VIA   -    MD0080PA01X+146179Y+106313X0160Y         S0      
317m4375            VIA   -    MD0100PA01X+164656Y+150530X0200Y    R180 S0      
327m4375            C848  -2          A01X+164666Y+151030X0120Y0150R270 S1      
327m4375            U25   -BU26       A01X+145995Y+106209X0177Y    R180 S1      
317m4376            VIA   -    MD0080PA01X+143033Y+105994X0160Y         S0      
317m4376            VIA   -    MD0100PA01X+156322Y+153499X0200Y    R270 S0      
327m4376            C868  -2          A01X+156822Y+153489X0120Y0150R180 S1      
327m4376            U25   -BT35       A01X+142850Y+105890X0177Y    R180 S1      
317m4377            VIA   -    MD0080PA01X+163236Y+155270X0160Y         S0      
317m4377            VIA   -    MD0080PA01X+146179Y+110778X0160Y         S0      
327m4377            U25   -CL26       A01X+145995Y+110673X0177Y    R180 S1      
327m4377            U6012 -BP26       A01X+163031Y+155270X0150Y         S1      
317m4378            VIA   -    MD0080PA01X+162763Y+155270X0160Y         S0      
317m4378            VIA   -    MD0080PA01X+145069Y+112054X0160Y         S0      
327m4378            U25   -CR29       A01X+144885Y+111949X0177Y    R180 S1      
327m4378            U6012 -CA26       A01X+162558Y+155270X0150Y         S1      
317m4379            VIA   -    MD0080PA01X+162291Y+155270X0160Y         S0      
317m4379            VIA   -    MD0080PA01X+145069Y+112691X0160Y         S0      
327m4379            U25   -CU29       A01X+144885Y+112587X0177Y    R180 S1      
327m4379            U6012 -CH26       A01X+162086Y+155270X0150Y         S1      
317m4380            VIA   -    MD0080PA01X+161818Y+155270X0160Y         S0      
317m4380            VIA   -    MD0080PA01X+145069Y+111416X0160Y         S0      
327m4380            U25   -CN29       A01X+144885Y+111311X0177Y    R180 S1      
327m4380            U6012 -CR26       A01X+161614Y+155270X0150Y         S1      
317m4381            VIA   -    MD0080PA01X+161346Y+155270X0160Y         S0      
317m4381            VIA   -    MD0080PA01X+143959Y+112054X0160Y         S0      
327m4381            U25   -CR32       A01X+143775Y+111949X0177Y    R180 S1      
327m4381            U6012 -DB26       A01X+161141Y+155270X0150Y         S1      
317m4382            VIA   -    MD0080PA01X+160874Y+155270X0160Y         S0      
317m4382            VIA   -    MD0080PA01X+143959Y+112691X0160Y         S0      
327m4382            U25   -CU32       A01X+143775Y+112587X0177Y    R180 S1      
327m4382            U6012 -DJ26       A01X+160669Y+155270X0150Y         S1      
317m4383            VIA   -    MD0080PA01X+160401Y+155270X0160Y         S0      
317m4383            VIA   -    MD0080PA01X+143959Y+111416X0160Y         S0      
327m4383            U25   -CN32       A01X+143775Y+111311X0177Y    R180 S1      
327m4383            U6012 -DT26       A01X+160196Y+155270X0150Y         S1      
317m4384            VIA   -    MD0080PA01X+159929Y+155270X0160Y         S0      
317m4384            VIA   -    MD0080PA01X+143033Y+112372X0160Y         S0      
327m4384            U25   -CT35       A01X+142850Y+112268X0177Y    R180 S1      
327m4384            U6012 -EC26       A01X+159724Y+155270X0150Y         S1      
317m4385            VIA   -    MD0080PA01X+159456Y+155270X0160Y         S0      
317m4385            VIA   -    MD0080PA01X+143033Y+111735X0160Y         S0      
327m4385            U25   -CP35       A01X+142850Y+111630X0177Y    R180 S1      
327m4385            U6012 -EK26       A01X+159251Y+155270X0150Y         S1      
317m4386            VIA   -    MD0080PA01X+166070Y+155270X0160Y         S0      
317m4386            VIA   -    MD0080PA01X+147289Y+111416X0160Y         S0      
327m4386            U25   -CN23       A01X+147106Y+111311X0177Y    R180 S1      
327m4386            U6012 -M26        A01X+165866Y+155270X0150Y         S1      
317m4387            VIA   -    MD0080PA01X+165598Y+155270X0160Y         S0      
317m4387            VIA   -    MD0080PA01X+147289Y+112054X0160Y         S0      
327m4387            U25   -CR23       A01X+147106Y+111949X0177Y    R180 S1      
327m4387            U6012 -W26        A01X+165393Y+155270X0150Y         S1      
317m4388            VIA   -    MD0080PA01X+165126Y+155270X0160Y         S0      
317m4388            VIA   -    MD0080PA01X+147289Y+110778X0160Y         S0      
327m4388            U25   -CL23       A01X+147106Y+110673X0177Y    R180 S1      
327m4388            U6012 -AF26       A01X+164921Y+155270X0150Y         S1      
317m4389            VIA   -    MD0080PA01X+164653Y+155270X0160Y         S0      
317m4389            VIA   -    MD0080PA01X+146179Y+111416X0160Y         S0      
327m4389            U25   -CN26       A01X+145995Y+111311X0177Y    R180 S1      
327m4389            U6012 -AN26       A01X+164448Y+155270X0150Y         S1      
317m4390            VIA   -    MD0080PA01X+164181Y+155270X0160Y         S0      
317m4390            VIA   -    MD0080PA01X+146179Y+112054X0160Y         S0      
327m4390            U25   -CR26       A01X+145995Y+111949X0177Y    R180 S1      
327m4390            U6012 -AY26       A01X+163976Y+155270X0150Y         S1      
317m4391            VIA   -    MD0080PA01X+163708Y+155270X0160Y         S0      
317m4391            VIA   -    MD0080PA01X+146179Y+112691X0160Y         S0      
327m4391            U25   -CU26       A01X+145995Y+112587X0177Y    R180 S1      
327m4391            U6012 -BG26       A01X+163503Y+155270X0150Y         S1      
317m4392            VIA   -    MD0080PA01X+158984Y+155270X0160Y         S0      
317m4392            VIA   -    MD0080PA01X+143033Y+111097X0160Y         S0      
327m4392            U25   -CM35       A01X+142850Y+110992X0177Y    R180 S1      
327m4392            U6012 -EU26       A01X+158779Y+155270X0150Y         S1      
317m4393            VIA   -    MD0080PA01X+163078Y+154997X0160Y         S0      
317m4393            VIA   -    MD0080PA01X+145809Y+110778X0160Y         S0      
327m4393            U25   -CL27       A01X+145625Y+110673X0177Y    R180 S1      
327m4393            U6012 -BT29       A01X+162873Y+154997X0150Y         S1      
317m4394            VIA   -    MD0080PA01X+162606Y+154997X0160Y         S0      
317m4394            VIA   -    MD0080PA01X+144699Y+112054X0160Y         S0      
327m4394            U25   -CR30       A01X+144515Y+111949X0177Y    R180 S1      
327m4394            U6012 -CC29       A01X+162401Y+154997X0150Y         S1      
317m4395            VIA   -    MD0080PA01X+162134Y+154997X0160Y         S0      
317m4395            VIA   -    MD0080PA01X+144699Y+112691X0160Y         S0      
327m4395            U25   -CU30       A01X+144515Y+112587X0177Y    R180 S1      
327m4395            U6012 -CK29       A01X+161928Y+154997X0150Y         S1      
317m4396            VIA   -    MD0080PA01X+161661Y+154997X0160Y         S0      
317m4396            VIA   -    MD0080PA01X+144699Y+111416X0160Y         S0      
327m4396            U25   -CN30       A01X+144515Y+111311X0177Y    R180 S1      
327m4396            U6012 -CU29       A01X+161456Y+154997X0150Y         S1      
317m4397            VIA   -    MD0080PA01X+161189Y+154997X0160Y         S0      
317m4397            VIA   -    MD0080PA01X+143588Y+112054X0160Y         S0      
327m4397            U25   -CR33       A01X+143405Y+111949X0177Y    R180 S1      
327m4397            U6012 -DD29       A01X+160984Y+154997X0150Y         S1      
317m4398            VIA   -    MD0080PA01X+160716Y+154997X0160Y         S0      
317m4398            VIA   -    MD0080PA01X+143588Y+112691X0160Y         S0      
327m4398            U25   -CU33       A01X+143405Y+112587X0177Y    R180 S1      
327m4398            U6012 -DL29       A01X+160511Y+154997X0150Y         S1      
317m4399            VIA   -    MD0080PA01X+160244Y+154997X0160Y         S0      
317m4399            VIA   -    MD0080PA01X+143588Y+111416X0160Y         S0      
327m4399            U25   -CN33       A01X+143405Y+111311X0177Y    R180 S1      
327m4399            U6012 -DV29       A01X+160039Y+154997X0150Y         S1      
317m4400            VIA   -    MD0080PA01X+159771Y+154997X0160Y         S0      
317m4400            VIA   -    MD0080PA01X+142663Y+112372X0160Y         S0      
327m4400            U25   -CT36       A01X+142480Y+112268X0177Y    R180 S1      
327m4400            U6012 -EE29       A01X+159566Y+154997X0150Y         S1      
317m4401            VIA   -    MD0080PA01X+159299Y+154997X0160Y         S0      
317m4401            VIA   -    MD0080PA01X+142663Y+111735X0160Y         S0      
327m4401            U25   -CP36       A01X+142480Y+111630X0177Y    R180 S1      
327m4401            U6012 -EM29       A01X+159094Y+154997X0150Y         S1      
317m4402            VIA   -    MD0080PA01X+165913Y+154997X0160Y         S0      
317m4402            VIA   -    MD0080PA01X+146919Y+111416X0160Y         S0      
327m4402            U25   -CN24       A01X+146735Y+111311X0177Y    R180 S1      
327m4402            U6012 -P29        A01X+165708Y+154997X0150Y         S1      
317m4403            VIA   -    MD0080PA01X+165441Y+154997X0160Y         S0      
317m4403            VIA   -    MD0080PA01X+146919Y+112054X0160Y         S0      
327m4403            U25   -CR24       A01X+146735Y+111949X0177Y    R180 S1      
327m4403            U6012 -AA29       A01X+165236Y+154997X0150Y         S1      
317m4404            VIA   -    MD0080PA01X+164968Y+154997X0160Y         S0      
317m4404            VIA   -    MD0080PA01X+146919Y+110778X0160Y         S0      
327m4404            U25   -CL24       A01X+146735Y+110673X0177Y    R180 S1      
327m4404            U6012 -AH29       A01X+164763Y+154997X0150Y         S1      
317m4405            VIA   -    MD0080PA01X+164496Y+154997X0160Y         S0      
317m4405            VIA   -    MD0080PA01X+145809Y+111416X0160Y         S0      
327m4405            U25   -CN27       A01X+145625Y+111311X0177Y    R180 S1      
327m4405            U6012 -AR29       A01X+164291Y+154997X0150Y         S1      
317m4406            VIA   -    MD0080PA01X+164023Y+154997X0160Y         S0      
317m4406            VIA   -    MD0080PA01X+145809Y+112054X0160Y         S0      
327m4406            U25   -CR27       A01X+145625Y+111949X0177Y    R180 S1      
327m4406            U6012 -BB29       A01X+163818Y+154997X0150Y         S1      
317m4407            VIA   -    MD0080PA01X+163551Y+154997X0160Y         S0      
317m4407            VIA   -    MD0080PA01X+145809Y+112691X0160Y         S0      
327m4407            U25   -CU27       A01X+145625Y+112587X0177Y    R180 S1      
327m4407            U6012 -BJ29       A01X+163346Y+154997X0150Y         S1      
317m4408            VIA   -    MD0080PA01X+158826Y+154997X0160Y         S0      
317m4408            VIA   -    MD0080PA01X+142663Y+111097X0160Y         S0      
327m4408            U25   -CM36       A01X+142480Y+110992X0177Y    R180 S1      
327m4408            U6012 -EW29       A01X+158621Y+154997X0150Y         S1      
317m4409            VIA   -    MD0080PA01X+138410Y+113329X0160Y         S0      
317m4409            VIA   -    MD0100PA01X+136559Y+148590X0200Y    R180 S0      
327m4409            C947  -2          A01X+136549Y+149090X0120Y0150R270 S1      
327m4409            U25   -CW47       A01X+138594Y+113224X0177Y    R180 S1      
317m4410            VIA   -    MD0080PA01X+138410Y+114605X0160Y         S0      
317m4410            VIA   -    MD0100PA01X+135889Y+149560X0200Y    R180 S0      
327m4410            C949  -2          A01X+135879Y+150060X0120Y0150R270 S1      
327m4410            U25   -DC47       A01X+138594Y+114500X0177Y    R180 S1      
317m4411            VIA   -    MD0080PA01X+138410Y+113967X0160Y         S0      
317m4411            VIA   -    MD0100PA01X+135219Y+150530X0200Y    R180 S0      
327m4411            C951  -2          A01X+135209Y+151030X0120Y0150R270 S1      
327m4411            U25   -DA47       A01X+138594Y+113862X0177Y    R180 S1      
317m4412            VIA   -    MD0080PA01X+137300Y+113329X0160Y         S0      
317m4412            VIA   -    MD0100PA01X+133879Y+148590X0200Y    R180 S0      
327m4412            C953  -2          A01X+133869Y+149090X0120Y0150R270 S1      
327m4412            U25   -CW50       A01X+137484Y+113224X0177Y    R180 S1      
317m4413            VIA   -    MD0080PA01X+137300Y+114605X0160Y         S0      
317m4413            VIA   -    MD0100PA01X+133209Y+149560X0200Y    R180 S0      
327m4413            C955  -2          A01X+133199Y+150060X0120Y0150R270 S1      
327m4413            U25   -DC50       A01X+137484Y+114500X0177Y    R180 S1      
317m4414            VIA   -    MD0080PA01X+137300Y+113967X0160Y         S0      
317m4414            VIA   -    MD0100PA01X+132539Y+150530X0200Y    R180 S0      
327m4414            C957  -2          A01X+132529Y+151030X0120Y0150R270 S1      
327m4414            U25   -DA50       A01X+137484Y+113862X0177Y    R180 S1      
317m4415            VIA   -    MD0080PA01X+136189Y+113329X0160Y         S0      
317m4415            VIA   -    MD0100PA01X+131199Y+148590X0200Y    R180 S0      
327m4415            C959  -2          A01X+131189Y+149090X0120Y0150R270 S1      
327m4415            U25   -CW53       A01X+136373Y+113224X0177Y    R180 S1      
317m4416            VIA   -    MD0080PA01X+136189Y+114605X0160Y         S0      
317m4416            VIA   -    MD0100PA01X+130529Y+149560X0200Y    R180 S0      
327m4416            C961  -2          A01X+130519Y+150060X0120Y0150R270 S1      
327m4416            U25   -DC53       A01X+136373Y+114500X0177Y    R180 S1      
317m4417            VIA   -    MD0080PA01X+136189Y+113967X0160Y         S0      
317m4417            VIA   -    MD0100PA01X+129905Y+151319X0200Y    R270 S0      
327m4417            C963  -2          A01X+130405Y+151309X0120Y0150R180 S1      
327m4417            U25   -DA53       A01X+136373Y+113862X0177Y    R180 S1      
317m4418            VIA   -    MD0080PA01X+140445Y+113010X0160Y         S0      
317m4418            VIA   -    MD0100PA01X+141656Y+152708X0200Y    R270 S0      
327m4418            C935  -2          A01X+141156Y+152698X0120Y0150     S1      
327m4418            U25   -CV41       A01X+140629Y+112906X0177Y    R180 S1      
317m4419            VIA   -    MD0080PA01X+140445Y+113648X0160Y         S0      
317m4419            VIA   -    MD0100PA01X+141656Y+151708X0200Y    R270 S0      
327m4419            C937  -2          A01X+141156Y+151718X0120Y0150     S1      
327m4419            U25   -CY41       A01X+140629Y+113543X0177Y    R180 S1      
317m4420            VIA   -    MD0080PA01X+140445Y+114286X0160Y         S0      
317m4420            VIA   -    MD0100PA01X+140579Y+148590X0200Y    R180 S0      
327m4420            C939  -2          A01X+140569Y+149090X0120Y0150R270 S1      
327m4420            U25   -DB41       A01X+140629Y+114181X0177Y    R180 S1      
317m4421            VIA   -    MD0080PA01X+139520Y+113329X0160Y         S0      
317m4421            VIA   -    MD0100PA01X+139239Y+148590X0200Y    R180 S0      
327m4421            C941  -2          A01X+139229Y+149090X0120Y0150R270 S1      
327m4421            U25   -CW44       A01X+139704Y+113224X0177Y    R180 S1      
317m4422            VIA   -    MD0080PA01X+139520Y+114605X0160Y         S0      
317m4422            VIA   -    MD0100PA01X+138569Y+149560X0200Y    R180 S0      
327m4422            C943  -2          A01X+138559Y+150060X0120Y0150R270 S1      
327m4422            U25   -DC44       A01X+139704Y+114500X0177Y    R180 S1      
317m4423            VIA   -    MD0080PA01X+139520Y+113967X0160Y         S0      
317m4423            VIA   -    MD0100PA01X+137899Y+150530X0200Y    R180 S0      
327m4423            C945  -2          A01X+137889Y+151030X0120Y0150R270 S1      
327m4423            U25   -DA44       A01X+139704Y+113862X0177Y    R180 S1      
317m4424            VIA   -    MD0080PA01X+136189Y+112691X0160Y         S0      
317m4424            VIA   -    MD0100PA01X+129905Y+153839X0200Y    R270 S0      
327m4424            C965  -2          A01X+130405Y+153849X0120Y0150R180 S1      
327m4424            U25   -CU53       A01X+136373Y+112587X0177Y    R180 S1      
317m4425            VIA   -    MD0080PA01X+138780Y+113329X0160Y         S0      
317m4425            VIA   -    MD0100PA01X+136899Y+148590X0200Y    R180 S0      
327m4425            C946  -2          A01X+136909Y+149090X0120Y0150R270 S1      
327m4425            U25   -CW46       A01X+138964Y+113224X0177Y    R180 S1      
317m4426            VIA   -    MD0080PA01X+138780Y+114605X0160Y         S0      
317m4426            VIA   -    MD0100PA01X+136229Y+149560X0200Y    R180 S0      
327m4426            C948  -2          A01X+136239Y+150060X0120Y0150R270 S1      
327m4426            U25   -DC46       A01X+138964Y+114500X0177Y    R180 S1      
317m4427            VIA   -    MD0080PA01X+138780Y+113967X0160Y         S0      
317m4427            VIA   -    MD0100PA01X+135559Y+150530X0200Y    R180 S0      
327m4427            C950  -2          A01X+135569Y+151030X0120Y0150R270 S1      
327m4427            U25   -DA46       A01X+138964Y+113862X0177Y    R180 S1      
317m4428            VIA   -    MD0080PA01X+137670Y+113329X0160Y         S0      
317m4428            VIA   -    MD0100PA01X+134219Y+148590X0200Y    R180 S0      
327m4428            C952  -2          A01X+134229Y+149090X0120Y0150R270 S1      
327m4428            U25   -CW49       A01X+137854Y+113224X0177Y    R180 S1      
317m4429            VIA   -    MD0080PA01X+137670Y+114605X0160Y         S0      
317m4429            VIA   -    MD0100PA01X+133549Y+149560X0200Y    R180 S0      
327m4429            C954  -2          A01X+133559Y+150060X0120Y0150R270 S1      
327m4429            U25   -DC49       A01X+137854Y+114500X0177Y    R180 S1      
317m4430            VIA   -    MD0080PA01X+137670Y+113967X0160Y         S0      
317m4430            VIA   -    MD0100PA01X+132879Y+150530X0200Y    R180 S0      
327m4430            C956  -2          A01X+132889Y+151030X0120Y0150R270 S1      
327m4430            U25   -DA49       A01X+137854Y+113862X0177Y    R180 S1      
317m4431            VIA   -    MD0080PA01X+136560Y+113329X0160Y         S0      
317m4431            VIA   -    MD0100PA01X+131539Y+148590X0200Y    R180 S0      
327m4431            C958  -2          A01X+131549Y+149090X0120Y0150R270 S1      
327m4431            U25   -CW52       A01X+136743Y+113224X0177Y    R180 S1      
317m4432            VIA   -    MD0080PA01X+136560Y+114605X0160Y         S0      
317m4432            VIA   -    MD0100PA01X+130869Y+149560X0200Y    R180 S0      
327m4432            C960  -2          A01X+130879Y+150060X0120Y0150R270 S1      
327m4432            U25   -DC52       A01X+136743Y+114500X0177Y    R180 S1      
317m4433            VIA   -    MD0080PA01X+136560Y+113967X0160Y         S0      
317m4433            VIA   -    MD0100PA01X+129905Y+151659X0200Y    R270 S0      
327m4433            C962  -2          A01X+130405Y+151669X0120Y0150R180 S1      
327m4433            U25   -DA52       A01X+136743Y+113862X0177Y    R180 S1      
317m4434            VIA   -    MD0080PA01X+140815Y+113010X0160Y         S0      
317m4434            VIA   -    MD0100PA01X+141656Y+153048X0200Y    R270 S0      
327m4434            C934  -2          A01X+141156Y+153058X0120Y0150     S1      
327m4434            U25   -CV40       A01X+140999Y+112906X0177Y    R180 S1      
317m4435            VIA   -    MD0080PA01X+140815Y+113648X0160Y         S0      
317m4435            VIA   -    MD0100PA01X+141656Y+151368X0200Y    R270 S0      
327m4435            C936  -2          A01X+141156Y+151358X0120Y0150     S1      
327m4435            U25   -CY40       A01X+140999Y+113543X0177Y    R180 S1      
317m4436            VIA   -    MD0080PA01X+140815Y+114286X0160Y         S0      
317m4436            VIA   -    MD0100PA01X+140919Y+148590X0200Y    R180 S0      
327m4436            C938  -2          A01X+140929Y+149090X0120Y0150R270 S1      
327m4436            U25   -DB40       A01X+140999Y+114181X0177Y    R180 S1      
317m4437            VIA   -    MD0080PA01X+139890Y+113329X0160Y         S0      
317m4437            VIA   -    MD0100PA01X+139579Y+148590X0200Y    R180 S0      
327m4437            C940  -2          A01X+139589Y+149090X0120Y0150R270 S1      
327m4437            U25   -CW43       A01X+140074Y+113224X0177Y    R180 S1      
317m4438            VIA   -    MD0080PA01X+139890Y+114605X0160Y         S0      
317m4438            VIA   -    MD0100PA01X+138909Y+149560X0200Y    R180 S0      
327m4438            C942  -2          A01X+138919Y+150060X0120Y0150R270 S1      
327m4438            U25   -DC43       A01X+140074Y+114500X0177Y    R180 S1      
317m4439            VIA   -    MD0080PA01X+139890Y+113967X0160Y         S0      
317m4439            VIA   -    MD0100PA01X+138239Y+150530X0200Y    R180 S0      
327m4439            C944  -2          A01X+138249Y+151030X0120Y0150R270 S1      
327m4439            U25   -DA43       A01X+140074Y+113862X0177Y    R180 S1      
317m4440            VIA   -    MD0080PA01X+136560Y+112691X0160Y         S0      
317m4440            VIA   -    MD0100PA01X+129905Y+153499X0200Y    R270 S0      
327m4440            C964  -2          A01X+130405Y+153489X0120Y0150R180 S1      
327m4440            U25   -CU52       A01X+136743Y+112587X0177Y    R180 S1      
317m4441            VIA   -    MD0080PA01X+139890Y+108865X0160Y         S0      
317m4441            VIA   -    MD0080PA01X+136818Y+155270X0160Y         S0      
327m4441            U25   -CE43       A01X+140074Y+108760X0177Y    R180 S1      
327m4441            U6011 -BP26       A01X+136613Y+155270X0150Y         S1      
317m4442            VIA   -    MD0080PA01X+138780Y+108227X0160Y         S0      
317m4442            VIA   -    MD0080PA01X+136346Y+155270X0160Y         S0      
327m4442            U25   -CC46       A01X+138964Y+108122X0177Y    R180 S1      
327m4442            U6011 -CA26       A01X+136141Y+155270X0150Y         S1      
317m4443            VIA   -    MD0080PA01X+138780Y+109502X0160Y         S0      
317m4443            VIA   -    MD0080PA01X+135874Y+155270X0160Y         S0      
327m4443            U25   -CG46       A01X+138964Y+109398X0177Y    R180 S1      
327m4443            U6011 -CH26       A01X+135668Y+155270X0150Y         S1      
317m4444            VIA   -    MD0080PA01X+138780Y+108865X0160Y         S0      
317m4444            VIA   -    MD0080PA01X+135401Y+155270X0160Y         S0      
327m4444            U25   -CE46       A01X+138964Y+108760X0177Y    R180 S1      
327m4444            U6011 -CR26       A01X+135196Y+155270X0150Y         S1      
317m4445            VIA   -    MD0080PA01X+137670Y+108227X0160Y         S0      
317m4445            VIA   -    MD0080PA01X+134929Y+155270X0160Y         S0      
327m4445            U25   -CC49       A01X+137854Y+108122X0177Y    R180 S1      
327m4445            U6011 -DB26       A01X+134724Y+155270X0150Y         S1      
317m4446            VIA   -    MD0080PA01X+137670Y+109502X0160Y         S0      
317m4446            VIA   -    MD0080PA01X+134456Y+155270X0160Y         S0      
327m4446            U25   -CG49       A01X+137854Y+109398X0177Y    R180 S1      
327m4446            U6011 -DJ26       A01X+134251Y+155270X0150Y         S1      
317m4447            VIA   -    MD0080PA01X+137670Y+108865X0160Y         S0      
317m4447            VIA   -    MD0080PA01X+133984Y+155270X0160Y         S0      
327m4447            U25   -CE49       A01X+137854Y+108760X0177Y    R180 S1      
327m4447            U6011 -DT26       A01X+133779Y+155270X0150Y         S1      
317m4448            VIA   -    MD0080PA01X+136560Y+108227X0160Y         S0      
317m4448            VIA   -    MD0080PA01X+133511Y+155270X0160Y         S0      
327m4448            U25   -CC52       A01X+136743Y+108122X0177Y    R180 S1      
327m4448            U6011 -EC26       A01X+133306Y+155270X0150Y         S1      
317m4449            VIA   -    MD0080PA01X+136560Y+109502X0160Y         S0      
317m4449            VIA   -    MD0080PA01X+133039Y+155270X0160Y         S0      
327m4449            U25   -CG52       A01X+136743Y+109398X0177Y    R180 S1      
327m4449            U6011 -EK26       A01X+132834Y+155270X0150Y         S1      
317m4450            VIA   -    MD0080PA01X+140815Y+108546X0160Y         S0      
317m4450            VIA   -    MD0080PA01X+139653Y+155270X0160Y         S0      
327m4450            U25   -CD40       A01X+140999Y+108441X0177Y    R180 S1      
327m4450            U6011 -M26        A01X+139448Y+155270X0150Y         S1      
317m4451            VIA   -    MD0080PA01X+140815Y+109184X0160Y         S0      
317m4451            VIA   -    MD0080PA01X+139181Y+155270X0160Y         S0      
327m4451            U25   -CF40       A01X+140999Y+109079X0177Y    R180 S1      
327m4451            U6011 -W26        A01X+138976Y+155270X0150Y         S1      
317m4452            VIA   -    MD0080PA01X+140815Y+109821X0160Y         S0      
317m4452            VIA   -    MD0080PA01X+138708Y+155270X0160Y         S0      
327m4452            U25   -CH40       A01X+140999Y+109717X0177Y    R180 S1      
327m4452            U6011 -AF26       A01X+138503Y+155270X0150Y         S1      
317m4453            VIA   -    MD0080PA01X+139890Y+108227X0160Y         S0      
317m4453            VIA   -    MD0080PA01X+138236Y+155270X0160Y         S0      
327m4453            U25   -CC43       A01X+140074Y+108122X0177Y    R180 S1      
327m4453            U6011 -AN26       A01X+138031Y+155270X0150Y         S1      
317m4454            VIA   -    MD0080PA01X+139890Y+110140X0160Y         S0      
317m4454            VIA   -    MD0080PA01X+137763Y+155270X0160Y         S0      
327m4454            U25   -CJ43       A01X+140074Y+110036X0177Y    R180 S1      
327m4454            U6011 -AY26       A01X+137558Y+155270X0150Y         S1      
317m4455            VIA   -    MD0080PA01X+139890Y+109502X0160Y         S0      
317m4455            VIA   -    MD0080PA01X+137291Y+155270X0160Y         S0      
327m4455            U25   -CG43       A01X+140074Y+109398X0177Y    R180 S1      
327m4455            U6011 -BG26       A01X+137086Y+155270X0150Y         S1      
317m4456            VIA   -    MD0080PA01X+136560Y+108865X0160Y         S0      
317m4456            VIA   -    MD0080PA01X+132566Y+155270X0160Y         S0      
327m4456            U25   -CE52       A01X+136743Y+108760X0177Y    R180 S1      
327m4456            U6011 -EU26       A01X+132362Y+155270X0150Y         S1      
317m4457            VIA   -    MD0080PA01X+139520Y+108865X0160Y         S0      
317m4457            VIA   -    MD0080PA01X+136661Y+154997X0160Y         S0      
327m4457            U25   -CE44       A01X+139704Y+108760X0177Y    R180 S1      
327m4457            U6011 -BT29       A01X+136456Y+154997X0150Y         S1      
317m4458            VIA   -    MD0080PA01X+138410Y+108227X0160Y         S0      
317m4458            VIA   -    MD0080PA01X+136188Y+154997X0160Y         S0      
327m4458            U25   -CC47       A01X+138594Y+108122X0177Y    R180 S1      
327m4458            U6011 -CC29       A01X+135984Y+154997X0150Y         S1      
317m4459            VIA   -    MD0080PA01X+138410Y+109502X0160Y         S0      
317m4459            VIA   -    MD0080PA01X+135716Y+154997X0160Y         S0      
327m4459            U25   -CG47       A01X+138594Y+109398X0177Y    R180 S1      
327m4459            U6011 -CK29       A01X+135511Y+154997X0150Y         S1      
317m4460            VIA   -    MD0080PA01X+138410Y+108865X0160Y         S0      
317m4460            VIA   -    MD0080PA01X+135244Y+154997X0160Y         S0      
327m4460            U25   -CE47       A01X+138594Y+108760X0177Y    R180 S1      
327m4460            U6011 -CU29       A01X+135039Y+154997X0150Y         S1      
317m4461            VIA   -    MD0080PA01X+137300Y+108227X0160Y         S0      
317m4461            VIA   -    MD0080PA01X+134771Y+154997X0160Y         S0      
327m4461            U25   -CC50       A01X+137484Y+108122X0177Y    R180 S1      
327m4461            U6011 -DD29       A01X+134566Y+154997X0150Y         S1      
317m4462            VIA   -    MD0080PA01X+137300Y+109502X0160Y         S0      
317m4462            VIA   -    MD0080PA01X+134299Y+154997X0160Y         S0      
327m4462            U25   -CG50       A01X+137484Y+109398X0177Y    R180 S1      
327m4462            U6011 -DL29       A01X+134094Y+154997X0150Y         S1      
317m4463            VIA   -    MD0080PA01X+137300Y+108865X0160Y         S0      
317m4463            VIA   -    MD0080PA01X+133826Y+154997X0160Y         S0      
327m4463            U25   -CE50       A01X+137484Y+108760X0177Y    R180 S1      
327m4463            U6011 -DV29       A01X+133621Y+154997X0150Y         S1      
317m4464            VIA   -    MD0080PA01X+136189Y+108227X0160Y         S0      
317m4464            VIA   -    MD0080PA01X+133354Y+154997X0160Y         S0      
327m4464            U25   -CC53       A01X+136373Y+108122X0177Y    R180 S1      
327m4464            U6011 -EE29       A01X+133149Y+154997X0150Y         S1      
317m4465            VIA   -    MD0080PA01X+136189Y+109502X0160Y         S0      
317m4465            VIA   -    MD0080PA01X+132881Y+154997X0160Y         S0      
327m4465            U25   -CG53       A01X+136373Y+109398X0177Y    R180 S1      
327m4465            U6011 -EM29       A01X+132676Y+154997X0150Y         S1      
317m4466            VIA   -    MD0080PA01X+140445Y+108546X0160Y         S0      
317m4466            VIA   -    MD0080PA01X+139496Y+154997X0160Y         S0      
327m4466            U25   -CD41       A01X+140629Y+108441X0177Y    R180 S1      
327m4466            U6011 -P29        A01X+139291Y+154997X0150Y         S1      
317m4467            VIA   -    MD0080PA01X+140445Y+109184X0160Y         S0      
317m4467            VIA   -    MD0080PA01X+139023Y+154997X0160Y         S0      
327m4467            U25   -CF41       A01X+140629Y+109079X0177Y    R180 S1      
327m4467            U6011 -AA29       A01X+138818Y+154997X0150Y         S1      
317m4468            VIA   -    MD0080PA01X+140445Y+109821X0160Y         S0      
317m4468            VIA   -    MD0080PA01X+138551Y+154997X0160Y         S0      
327m4468            U25   -CH41       A01X+140629Y+109717X0177Y    R180 S1      
327m4468            U6011 -AH29       A01X+138346Y+154997X0150Y         S1      
317m4469            VIA   -    MD0080PA01X+139520Y+108227X0160Y         S0      
317m4469            VIA   -    MD0080PA01X+138078Y+154997X0160Y         S0      
327m4469            U25   -CC44       A01X+139704Y+108122X0177Y    R180 S1      
327m4469            U6011 -AR29       A01X+137873Y+154997X0150Y         S1      
317m4470            VIA   -    MD0080PA01X+139520Y+110140X0160Y         S0      
317m4470            VIA   -    MD0080PA01X+137606Y+154997X0160Y         S0      
327m4470            U25   -CJ44       A01X+139704Y+110036X0177Y    R180 S1      
327m4470            U6011 -BB29       A01X+137401Y+154997X0150Y         S1      
317m4471            VIA   -    MD0080PA01X+139520Y+109502X0160Y         S0      
317m4471            VIA   -    MD0080PA01X+137133Y+154997X0160Y         S0      
327m4471            U25   -CG44       A01X+139704Y+109398X0177Y    R180 S1      
327m4471            U6011 -BJ29       A01X+136928Y+154997X0150Y         S1      
317m4472            VIA   -    MD0080PA01X+136189Y+108865X0160Y         S0      
317m4472            VIA   -    MD0080PA01X+132409Y+154997X0160Y         S0      
327m4472            U25   -CE53       A01X+136373Y+108760X0177Y    R180 S1      
327m4472            U6011 -EW29       A01X+132204Y+154997X0150Y         S1      
317m4473            VIA   -    MD0080PA01X+138410Y+111416X0160Y         S0      
317m4473            VIA   -    MD0100PA01X+123752Y+148590X0200Y    R180 S0      
327m4473            C915  -2          A01X+123742Y+149090X0120Y0150R270 S1      
327m4473            U25   -CN47       A01X+138594Y+111311X0177Y    R180 S1      
317m4474            VIA   -    MD0080PA01X+138410Y+112691X0160Y         S0      
317m4474            VIA   -    MD0100PA01X+123082Y+149560X0200Y    R180 S0      
327m4474            C917  -2          A01X+123072Y+150060X0120Y0150R270 S1      
327m4474            U25   -CU47       A01X+138594Y+112587X0177Y    R180 S1      
317m4475            VIA   -    MD0080PA01X+138410Y+112054X0160Y         S0      
317m4475            VIA   -    MD0100PA01X+122412Y+150530X0200Y    R180 S0      
327m4475            C919  -2          A01X+122402Y+151030X0120Y0150R270 S1      
327m4475            U25   -CR47       A01X+138594Y+111949X0177Y    R180 S1      
317m4476            VIA   -    MD0080PA01X+137300Y+110778X0160Y         S0      
317m4476            VIA   -    MD0100PA01X+121072Y+148590X0200Y    R180 S0      
327m4476            C921  -2          A01X+121062Y+149090X0120Y0150R270 S1      
327m4476            U25   -CL50       A01X+137484Y+110673X0177Y    R180 S1      
317m4477            VIA   -    MD0080PA01X+137300Y+112691X0160Y         S0      
317m4477            VIA   -    MD0100PA01X+120402Y+149560X0200Y    R180 S0      
327m4477            C923  -2          A01X+120392Y+150060X0120Y0150R270 S1      
327m4477            U25   -CU50       A01X+137484Y+112587X0177Y    R180 S1      
317m4478            VIA   -    MD0080PA01X+137300Y+112054X0160Y         S0      
317m4478            VIA   -    MD0100PA01X+119732Y+150530X0200Y    R180 S0      
327m4478            C925  -2          A01X+119722Y+151030X0120Y0150R270 S1      
327m4478            U25   -CR50       A01X+137484Y+111949X0177Y    R180 S1      
317m4479            VIA   -    MD0080PA01X+137300Y+111416X0160Y         S0      
317m4479            VIA   -    MD0100PA01X+118392Y+148590X0200Y    R180 S0      
327m4479            C927  -2          A01X+118382Y+149090X0120Y0150R270 S1      
327m4479            U25   -CN50       A01X+137484Y+111311X0177Y    R180 S1      
317m4480            VIA   -    MD0080PA01X+136189Y+110778X0160Y         S0      
317m4480            VIA   -    MD0100PA01X+117722Y+149560X0200Y    R180 S0      
327m4480            C929  -2          A01X+117712Y+150060X0120Y0150R270 S1      
327m4480            U25   -CL53       A01X+136373Y+110673X0177Y    R180 S1      
317m4481            VIA   -    MD0080PA01X+136189Y+112054X0160Y         S0      
317m4481            VIA   -    MD0100PA01X+117099Y+151319X0200Y    R270 S0      
327m4481            C931  -2          A01X+117599Y+151309X0120Y0150R180 S1      
327m4481            U25   -CR53       A01X+136373Y+111949X0177Y    R180 S1      
317m4482            VIA   -    MD0080PA01X+140445Y+111097X0160Y         S0      
317m4482            VIA   -    MD0100PA01X+128849Y+152708X0200Y    R270 S0      
327m4482            C903  -2          A01X+128349Y+152698X0120Y0150     S1      
327m4482            U25   -CM41       A01X+140629Y+110992X0177Y    R180 S1      
317m4483            VIA   -    MD0080PA01X+140445Y+111735X0160Y         S0      
317m4483            VIA   -    MD0100PA01X+128849Y+151368X0200Y    R270 S0      
327m4483            C905  -2          A01X+128349Y+151358X0120Y0150     S1      
327m4483            U25   -CP41       A01X+140629Y+111630X0177Y    R180 S1      
317m4484            VIA   -    MD0080PA01X+140445Y+112372X0160Y         S0      
317m4484            VIA   -    MD0100PA01X+128112Y+148590X0200Y    R180 S0      
327m4484            C907  -2          A01X+128122Y+149090X0120Y0150R270 S1      
327m4484            U25   -CT41       A01X+140629Y+112268X0177Y    R180 S1      
317m4485            VIA   -    MD0080PA01X+139520Y+111416X0160Y         S0      
317m4485            VIA   -    MD0100PA01X+126432Y+148590X0200Y    R180 S0      
327m4485            C909  -2          A01X+126422Y+149090X0120Y0150R270 S1      
327m4485            U25   -CN44       A01X+139704Y+111311X0177Y    R180 S1      
317m4486            VIA   -    MD0080PA01X+139520Y+112691X0160Y         S0      
317m4486            VIA   -    MD0100PA01X+125762Y+149560X0200Y    R180 S0      
327m4486            C911  -2          A01X+125752Y+150060X0120Y0150R270 S1      
327m4486            U25   -CU44       A01X+139704Y+112587X0177Y    R180 S1      
317m4487            VIA   -    MD0080PA01X+139520Y+112054X0160Y         S0      
317m4487            VIA   -    MD0100PA01X+125092Y+150530X0200Y    R180 S0      
327m4487            C913  -2          A01X+125082Y+151030X0120Y0150R270 S1      
327m4487            U25   -CR44       A01X+139704Y+111949X0177Y    R180 S1      
317m4488            VIA   -    MD0080PA01X+136189Y+111416X0160Y         S0      
317m4488            VIA   -    MD0100PA01X+117099Y+153839X0200Y    R270 S0      
327m4488            C933  -2          A01X+117599Y+153849X0120Y0150R180 S1      
327m4488            U25   -CN53       A01X+136373Y+111311X0177Y    R180 S1      
317m4489            VIA   -    MD0080PA01X+138780Y+111416X0160Y         S0      
317m4489            VIA   -    MD0100PA01X+124092Y+148590X0200Y    R180 S0      
327m4489            C914  -2          A01X+124102Y+149090X0120Y0150R270 S1      
327m4489            U25   -CN46       A01X+138964Y+111311X0177Y    R180 S1      
317m4490            VIA   -    MD0080PA01X+138780Y+112691X0160Y         S0      
317m4490            VIA   -    MD0100PA01X+123422Y+149560X0200Y    R180 S0      
327m4490            C916  -2          A01X+123432Y+150060X0120Y0150R270 S1      
327m4490            U25   -CU46       A01X+138964Y+112587X0177Y    R180 S1      
317m4491            VIA   -    MD0080PA01X+138780Y+112054X0160Y         S0      
317m4491            VIA   -    MD0100PA01X+122752Y+150530X0200Y    R180 S0      
327m4491            C918  -2          A01X+122762Y+151030X0120Y0150R270 S1      
327m4491            U25   -CR46       A01X+138964Y+111949X0177Y    R180 S1      
317m4492            VIA   -    MD0080PA01X+137670Y+110778X0160Y         S0      
317m4492            VIA   -    MD0100PA01X+121412Y+148590X0200Y    R180 S0      
327m4492            C920  -2          A01X+121422Y+149090X0120Y0150R270 S1      
327m4492            U25   -CL49       A01X+137854Y+110673X0177Y    R180 S1      
317m4493            VIA   -    MD0080PA01X+137670Y+112691X0160Y         S0      
317m4493            VIA   -    MD0100PA01X+120742Y+149560X0200Y    R180 S0      
327m4493            C922  -2          A01X+120752Y+150060X0120Y0150R270 S1      
327m4493            U25   -CU49       A01X+137854Y+112587X0177Y    R180 S1      
317m4494            VIA   -    MD0080PA01X+137670Y+112054X0160Y         S0      
317m4494            VIA   -    MD0100PA01X+120072Y+150530X0200Y    R180 S0      
327m4494            C924  -2          A01X+120082Y+151030X0120Y0150R270 S1      
327m4494            U25   -CR49       A01X+137854Y+111949X0177Y    R180 S1      
317m4495            VIA   -    MD0080PA01X+137670Y+111416X0160Y         S0      
317m4495            VIA   -    MD0100PA01X+118732Y+148590X0200Y    R180 S0      
327m4495            C926  -2          A01X+118742Y+149090X0120Y0150R270 S1      
327m4495            U25   -CN49       A01X+137854Y+111311X0177Y    R180 S1      
317m4496            VIA   -    MD0080PA01X+136560Y+110778X0160Y         S0      
317m4496            VIA   -    MD0100PA01X+118062Y+149560X0200Y    R180 S0      
327m4496            C928  -2          A01X+118072Y+150060X0120Y0150R270 S1      
327m4496            U25   -CL52       A01X+136743Y+110673X0177Y    R180 S1      
317m4497            VIA   -    MD0080PA01X+136560Y+112054X0160Y         S0      
317m4497            VIA   -    MD0100PA01X+117099Y+151659X0200Y    R270 S0      
327m4497            C930  -2          A01X+117599Y+151669X0120Y0150R180 S1      
327m4497            U25   -CR52       A01X+136743Y+111949X0177Y    R180 S1      
317m4498            VIA   -    MD0080PA01X+140815Y+111097X0160Y         S0      
317m4498            VIA   -    MD0100PA01X+128849Y+153048X0200Y    R270 S0      
327m4498            C902  -2          A01X+128349Y+153058X0120Y0150     S1      
327m4498            U25   -CM40       A01X+140999Y+110992X0177Y    R180 S1      
317m4499            VIA   -    MD0080PA01X+140815Y+111735X0160Y         S0      
317m4499            VIA   -    MD0100PA01X+128849Y+151708X0200Y    R270 S0      
327m4499            C904  -2          A01X+128349Y+151718X0120Y0150     S1      
327m4499            U25   -CP40       A01X+140999Y+111630X0177Y    R180 S1      
317m4500            VIA   -    MD0080PA01X+140815Y+112372X0160Y         S0      
317m4500            VIA   -    MD0100PA01X+127772Y+148590X0200Y    R180 S0      
327m4500            C906  -2          A01X+127762Y+149090X0120Y0150R270 S1      
327m4500            U25   -CT40       A01X+140999Y+112268X0177Y    R180 S1      
317m4501            VIA   -    MD0080PA01X+139890Y+111416X0160Y         S0      
317m4501            VIA   -    MD0100PA01X+126772Y+148590X0200Y    R180 S0      
327m4501            C908  -2          A01X+126782Y+149090X0120Y0150R270 S1      
327m4501            U25   -CN43       A01X+140074Y+111311X0177Y    R180 S1      
317m4502            VIA   -    MD0080PA01X+139890Y+112691X0160Y         S0      
317m4502            VIA   -    MD0100PA01X+126102Y+149560X0200Y    R180 S0      
327m4502            C910  -2          A01X+126112Y+150060X0120Y0150R270 S1      
327m4502            U25   -CU43       A01X+140074Y+112587X0177Y    R180 S1      
317m4503            VIA   -    MD0080PA01X+139890Y+112054X0160Y         S0      
317m4503            VIA   -    MD0100PA01X+125432Y+150530X0200Y    R180 S0      
327m4503            C912  -2          A01X+125442Y+151030X0120Y0150R270 S1      
327m4503            U25   -CR43       A01X+140074Y+111949X0177Y    R180 S1      
317m4504            VIA   -    MD0080PA01X+136560Y+111416X0160Y         S0      
317m4504            VIA   -    MD0100PA01X+117099Y+153499X0200Y    R270 S0      
327m4504            C932  -2          A01X+117599Y+153489X0120Y0150R180 S1      
327m4504            U25   -CN52       A01X+136743Y+111311X0177Y    R180 S1      
317m4505            VIA   -    MD0080PA01X+139890Y+106951X0160Y         S0      
317m4505            VIA   -    MD0080PA01X+124012Y+155270X0160Y         S0      
327m4505            U25   -BW43       A01X+140074Y+106846X0177Y    R180 S1      
327m4505            U6010 -BP26       A01X+123807Y+155270X0150Y         S1      
317m4506            VIA   -    MD0080PA01X+138780Y+106313X0160Y         S0      
317m4506            VIA   -    MD0080PA01X+123540Y+155270X0160Y         S0      
327m4506            U25   -BU46       A01X+138964Y+106209X0177Y    R180 S1      
327m4506            U6010 -CA26       A01X+123335Y+155270X0150Y         S1      
317m4507            VIA   -    MD0080PA01X+138780Y+107589X0160Y         S0      
317m4507            VIA   -    MD0080PA01X+123067Y+155270X0160Y         S0      
327m4507            U25   -CA46       A01X+138964Y+107484X0177Y    R180 S1      
327m4507            U6010 -CH26       A01X+122862Y+155270X0150Y         S1      
317m4508            VIA   -    MD0080PA01X+138780Y+106951X0160Y         S0      
317m4508            VIA   -    MD0080PA01X+122595Y+155270X0160Y         S0      
327m4508            U25   -BW46       A01X+138964Y+106846X0177Y    R180 S1      
327m4508            U6010 -CR26       A01X+122390Y+155270X0150Y         S1      
317m4509            VIA   -    MD0080PA01X+137670Y+106313X0160Y         S0      
317m4509            VIA   -    MD0080PA01X+122122Y+155270X0160Y         S0      
327m4509            U25   -BU49       A01X+137854Y+106209X0177Y    R180 S1      
327m4509            U6010 -DB26       A01X+121918Y+155270X0150Y         S1      
317m4510            VIA   -    MD0080PA01X+137670Y+107589X0160Y         S0      
317m4510            VIA   -    MD0080PA01X+121650Y+155270X0160Y         S0      
327m4510            U25   -CA49       A01X+137854Y+107484X0177Y    R180 S1      
327m4510            U6010 -DJ26       A01X+121445Y+155270X0150Y         S1      
317m4511            VIA   -    MD0080PA01X+137670Y+106951X0160Y         S0      
317m4511            VIA   -    MD0080PA01X+121178Y+155270X0160Y         S0      
327m4511            U25   -BW49       A01X+137854Y+106846X0177Y    R180 S1      
327m4511            U6010 -DT26       A01X+120973Y+155270X0150Y         S1      
317m4512            VIA   -    MD0080PA01X+136560Y+106313X0160Y         S0      
317m4512            VIA   -    MD0080PA01X+120705Y+155270X0160Y         S0      
327m4512            U25   -BU52       A01X+136743Y+106209X0177Y    R180 S1      
327m4512            U6010 -EC26       A01X+120500Y+155270X0150Y         S1      
317m4513            VIA   -    MD0080PA01X+136560Y+107589X0160Y         S0      
317m4513            VIA   -    MD0080PA01X+120233Y+155270X0160Y         S0      
327m4513            U25   -CA52       A01X+136743Y+107484X0177Y    R180 S1      
327m4513            U6010 -EK26       A01X+120028Y+155270X0150Y         S1      
317m4514            VIA   -    MD0080PA01X+140815Y+105994X0160Y         S0      
317m4514            VIA   -    MD0080PA01X+126847Y+155270X0160Y         S0      
327m4514            U25   -BT40       A01X+140999Y+105890X0177Y    R180 S1      
327m4514            U6010 -M26        A01X+126642Y+155270X0150Y         S1      
317m4515            VIA   -    MD0080PA01X+140815Y+106632X0160Y         S0      
317m4515            VIA   -    MD0080PA01X+126374Y+155270X0160Y         S0      
327m4515            U25   -BV40       A01X+140999Y+106528X0177Y    R180 S1      
327m4515            U6010 -W26        A01X+126169Y+155270X0150Y         S1      
317m4516            VIA   -    MD0080PA01X+140815Y+107908X0160Y         S0      
317m4516            VIA   -    MD0080PA01X+125902Y+155270X0160Y         S0      
327m4516            U25   -CB40       A01X+140999Y+107803X0177Y    R180 S1      
327m4516            U6010 -AF26       A01X+125697Y+155270X0150Y         S1      
317m4517            VIA   -    MD0080PA01X+140815Y+107270X0160Y         S0      
317m4517            VIA   -    MD0080PA01X+125430Y+155270X0160Y         S0      
327m4517            U25   -BY40       A01X+140999Y+107165X0177Y    R180 S1      
327m4517            U6010 -AN26       A01X+125224Y+155270X0150Y         S1      
317m4518            VIA   -    MD0080PA01X+139890Y+106313X0160Y         S0      
317m4518            VIA   -    MD0080PA01X+124957Y+155270X0160Y         S0      
327m4518            U25   -BU43       A01X+140074Y+106209X0177Y    R180 S1      
327m4518            U6010 -AY26       A01X+124752Y+155270X0150Y         S1      
317m4519            VIA   -    MD0080PA01X+139890Y+107589X0160Y         S0      
317m4519            VIA   -    MD0080PA01X+124485Y+155270X0160Y         S0      
327m4519            U25   -CA43       A01X+140074Y+107484X0177Y    R180 S1      
327m4519            U6010 -BG26       A01X+124280Y+155270X0150Y         S1      
317m4520            VIA   -    MD0080PA01X+136560Y+106951X0160Y         S0      
317m4520            VIA   -    MD0080PA01X+119760Y+155270X0160Y         S0      
327m4520            U25   -BW52       A01X+136743Y+106846X0177Y    R180 S1      
327m4520            U6010 -EU26       A01X+119555Y+155270X0150Y         S1      
317m4521            VIA   -    MD0080PA01X+139520Y+106951X0160Y         S0      
317m4521            VIA   -    MD0080PA01X+123855Y+154997X0160Y         S0      
327m4521            U25   -BW44       A01X+139704Y+106846X0177Y    R180 S1      
327m4521            U6010 -BT29       A01X+123650Y+154997X0150Y         S1      
317m4522            VIA   -    MD0080PA01X+138410Y+106313X0160Y         S0      
317m4522            VIA   -    MD0080PA01X+123382Y+154997X0160Y         S0      
327m4522            U25   -BU47       A01X+138594Y+106209X0177Y    R180 S1      
327m4522            U6010 -CC29       A01X+123177Y+154997X0150Y         S1      
317m4523            VIA   -    MD0080PA01X+138410Y+107589X0160Y         S0      
317m4523            VIA   -    MD0080PA01X+122910Y+154997X0160Y         S0      
327m4523            U25   -CA47       A01X+138594Y+107484X0177Y    R180 S1      
327m4523            U6010 -CK29       A01X+122705Y+154997X0150Y         S1      
317m4524            VIA   -    MD0080PA01X+138410Y+106951X0160Y         S0      
317m4524            VIA   -    MD0080PA01X+122437Y+154997X0160Y         S0      
327m4524            U25   -BW47       A01X+138594Y+106846X0177Y    R180 S1      
327m4524            U6010 -CU29       A01X+122232Y+154997X0150Y         S1      
317m4525            VIA   -    MD0080PA01X+137300Y+106313X0160Y         S0      
317m4525            VIA   -    MD0080PA01X+121965Y+154997X0160Y         S0      
327m4525            U25   -BU50       A01X+137484Y+106209X0177Y    R180 S1      
327m4525            U6010 -DD29       A01X+121760Y+154997X0150Y         S1      
317m4526            VIA   -    MD0080PA01X+137300Y+107589X0160Y         S0      
317m4526            VIA   -    MD0080PA01X+121492Y+154997X0160Y         S0      
327m4526            U25   -CA50       A01X+137484Y+107484X0177Y    R180 S1      
327m4526            U6010 -DL29       A01X+121288Y+154997X0150Y         S1      
317m4527            VIA   -    MD0080PA01X+137300Y+106951X0160Y         S0      
317m4527            VIA   -    MD0080PA01X+121020Y+154997X0160Y         S0      
327m4527            U25   -BW50       A01X+137484Y+106846X0177Y    R180 S1      
327m4527            U6010 -DV29       A01X+120815Y+154997X0150Y         S1      
317m4528            VIA   -    MD0080PA01X+136189Y+106313X0160Y         S0      
317m4528            VIA   -    MD0080PA01X+120548Y+154997X0160Y         S0      
327m4528            U25   -BU53       A01X+136373Y+106209X0177Y    R180 S1      
327m4528            U6010 -EE29       A01X+120343Y+154997X0150Y         S1      
317m4529            VIA   -    MD0080PA01X+136189Y+107589X0160Y         S0      
317m4529            VIA   -    MD0080PA01X+120075Y+154997X0160Y         S0      
327m4529            U25   -CA53       A01X+136373Y+107484X0177Y    R180 S1      
327m4529            U6010 -EM29       A01X+119870Y+154997X0150Y         S1      
317m4530            VIA   -    MD0080PA01X+140445Y+105994X0160Y         S0      
317m4530            VIA   -    MD0080PA01X+126689Y+154997X0160Y         S0      
327m4530            U25   -BT41       A01X+140629Y+105890X0177Y    R180 S1      
327m4530            U6010 -P29        A01X+126484Y+154997X0150Y         S1      
317m4531            VIA   -    MD0080PA01X+140445Y+106632X0160Y         S0      
317m4531            VIA   -    MD0080PA01X+126217Y+154997X0160Y         S0      
327m4531            U25   -BV41       A01X+140629Y+106528X0177Y    R180 S1      
327m4531            U6010 -AA29       A01X+126012Y+154997X0150Y         S1      
317m4532            VIA   -    MD0080PA01X+140445Y+107908X0160Y         S0      
317m4532            VIA   -    MD0080PA01X+125744Y+154997X0160Y         S0      
327m4532            U25   -CB41       A01X+140629Y+107803X0177Y    R180 S1      
327m4532            U6010 -AH29       A01X+125540Y+154997X0150Y         S1      
317m4533            VIA   -    MD0080PA01X+140445Y+107270X0160Y         S0      
317m4533            VIA   -    MD0080PA01X+125272Y+154997X0160Y         S0      
327m4533            U25   -BY41       A01X+140629Y+107165X0177Y    R180 S1      
327m4533            U6010 -AR29       A01X+125067Y+154997X0150Y         S1      
317m4534            VIA   -    MD0080PA01X+139520Y+106313X0160Y         S0      
317m4534            VIA   -    MD0080PA01X+124800Y+154997X0160Y         S0      
327m4534            U25   -BU44       A01X+139704Y+106209X0177Y    R180 S1      
327m4534            U6010 -BB29       A01X+124595Y+154997X0150Y         S1      
317m4535            VIA   -    MD0080PA01X+139520Y+107589X0160Y         S0      
317m4535            VIA   -    MD0080PA01X+124327Y+154997X0160Y         S0      
327m4535            U25   -CA44       A01X+139704Y+107484X0177Y    R180 S1      
327m4535            U6010 -BJ29       A01X+124122Y+154997X0150Y         S1      
317m4536            VIA   -    MD0080PA01X+136189Y+106951X0160Y         S0      
317m4536            VIA   -    MD0080PA01X+119603Y+154997X0160Y         S0      
327m4536            U25   -BW53       A01X+136373Y+106846X0177Y    R180 S1      
327m4536            U6010 -EW29       A01X+119398Y+154997X0150Y         S1      
317m4537            VIA   -    MD0080PA01X+144951Y+092427X0160Y    R180 S0      
327m4537            U25   -U29        A01X+144767Y+092532X0177Y    R180 S1      
317m4537            VIA   -    MD0100PA01X+160496Y+006934X0200Y         S0      
327m4537            C1793 -2          A01X+160506Y+006444X0120Y0150R090 S1      
317m4538            VIA   -    MD0080PA01X+144951Y+091151X0160Y    R180 S0      
327m4538            U25   -N29        A01X+144767Y+091256X0177Y    R180 S1      
317m4538            VIA   -    MD0100PA01X+161597Y+007534X0200Y         S0      
327m4538            C44   -2          A01X+161606Y+007044X0120Y0150R090 S1      
317m4539            VIA   -    MD0080PA01X+144951Y+091789X0160Y    R180 S0      
327m4539            U25   -R29        A01X+144767Y+091894X0177Y    R180 S1      
317m4539            VIA   -    MD0100PA01X+162696Y+006934X0200Y         S0      
327m4539            C1565 -2          A01X+162706Y+006444X0120Y0150R090 S1      
317m4540            VIA   -    MD0080PA01X+146061Y+093065X0160Y    R180 S0      
327m4540            U25   -W26        A01X+145877Y+093169X0177Y    R180 S1      
317m4540            VIA   -    MD0100PA01X+163917Y+007534X0200Y         S0      
327m4540            C47   -2          A01X+163927Y+007044X0120Y0150R090 S1      
317m4541            VIA   -    MD0080PA01X+146061Y+091151X0160Y         S0      
327m4541            U25   -N26        A01X+145877Y+091256X0177Y    R180 S1      
317m4541            VIA   -    MD0100PA01X+165017Y+006934X0200Y         S0      
327m4541            C1569 -2          A01X+165027Y+006444X0120Y0150R090 S1      
317m4542            VIA   -    MD0080PA01X+146061Y+091789X0160Y    R180 S0      
327m4542            U25   -R26        A01X+145877Y+091894X0177Y    R180 S1      
317m4542            VIA   -    MD0100PA01X+166117Y+007534X0200Y         S0      
327m4542            C1571 -2          A01X+166127Y+007044X0120Y0150R090 S1      
317m4543            VIA   -    MD0080PA01X+146061Y+092427X0160Y    R180 S0      
327m4543            U25   -U26        A01X+145877Y+092532X0177Y    R180 S1      
317m4543            VIA   -    MD0100PA01X+167217Y+006934X0200Y         S0      
327m4543            C1573 -2          A01X+167227Y+006444X0120Y0150R090 S1      
317m4544            VIA   -    MD0080PA01X+147171Y+093065X0160Y    R180 S0      
327m4544            U25   -W23        A01X+146987Y+093169X0177Y    R180 S1      
317m4544            VIA   -    MD0100PA01X+168330Y+007534X0200Y         S0      
327m4544            C1575 -2          A01X+168340Y+007044X0120Y0150R090 S1      
317m4545            VIA   -    MD0080PA01X+147171Y+091789X0160Y    R180 S0      
327m4545            U25   -R23        A01X+146987Y+091894X0177Y    R180 S1      
317m4545            VIA   -    MD0100PA01X+169430Y+006934X0200Y         S0      
327m4545            C1577 -2          A01X+169440Y+006444X0120Y0150R090 S1      
317m4546            VIA   -    MD0080PA01X+142915Y+092746X0160Y    R180 S0      
327m4546            U25   -V35        A01X+142732Y+092850X0177Y    R180 S1      
327m4546            C1549 -2          A01X+153906Y+006444X0120Y0150R090 S1      
317m4546            VIA   -    MD0100PA01X+153897Y+006934X0200Y         S0      
317m4547            VIA   -    MD0080PA01X+142915Y+092108X0160Y    R180 S0      
327m4547            U25   -T35        A01X+142732Y+092213X0177Y    R180 S1      
317m4547            VIA   -    MD0100PA01X+154996Y+007534X0200Y         S0      
327m4547            C1792 -2          A01X+155006Y+007044X0120Y0150R090 S1      
317m4548            VIA   -    MD0080PA01X+142915Y+091470X0160Y    R180 S0      
327m4548            U25   -P35        A01X+142732Y+091575X0177Y    R180 S1      
317m4548            VIA   -    MD0100PA01X+156097Y+006934X0200Y         S0      
327m4548            C1553 -2          A01X+156106Y+006444X0120Y0150R090 S1      
317m4549            VIA   -    MD0080PA01X+143840Y+092427X0160Y    R180 S0      
327m4549            U25   -U32        A01X+143657Y+092532X0177Y    R180 S1      
317m4549            VIA   -    MD0100PA01X+157197Y+007534X0200Y         S0      
327m4549            C1555 -2          A01X+157206Y+007044X0120Y0150R090 S1      
317m4550            VIA   -    MD0080PA01X+143840Y+091151X0160Y    R180 S0      
327m4550            U25   -N32        A01X+143657Y+091256X0177Y    R180 S1      
317m4550            VIA   -    MD0100PA01X+158297Y+006934X0200Y         S0      
327m4550            C1557 -2          A01X+158306Y+006444X0120Y0150R090 S1      
317m4551            VIA   -    MD0080PA01X+143840Y+091789X0160Y    R180 S0      
327m4551            U25   -R32        A01X+143657Y+091894X0177Y    R180 S1      
317m4551            VIA   -    MD0100PA01X+159397Y+007534X0200Y         S0      
327m4551            C1559 -2          A01X+159406Y+007044X0120Y0150R090 S1      
317m4552            VIA   -    MD0080PA01X+147171Y+092427X0160Y    R180 S0      
327m4552            U25   -U23        A01X+146987Y+092532X0177Y    R180 S1      
317m4552            VIA   -    MD0100PA01X+170530Y+007534X0200Y         S0      
327m4552            C1579 -2          A01X+170540Y+007044X0120Y0150R090 S1      
317m4553            VIA   -    MD0080PA01X+144581Y+092427X0160Y    R180 S0      
327m4553            U25   -U30        A01X+144397Y+092532X0177Y    R180 S1      
317m4553            VIA   -    MD0100PA01X+160156Y+006934X0200Y         S0      
327m4553            C1560 -2          A01X+160146Y+006444X0120Y0150R090 S1      
317m4554            VIA   -    MD0080PA01X+144581Y+091151X0160Y    R180 S0      
327m4554            U25   -N30        A01X+144397Y+091256X0177Y    R180 S1      
317m4554            VIA   -    MD0100PA01X+161257Y+007534X0200Y         S0      
327m4554            C1794 -2          A01X+161246Y+007044X0120Y0150R090 S1      
317m4555            VIA   -    MD0080PA01X+144581Y+091789X0160Y    R180 S0      
327m4555            U25   -R30        A01X+144397Y+091894X0177Y    R180 S1      
317m4555            VIA   -    MD0100PA01X+162356Y+006934X0200Y         S0      
327m4555            C46   -2          A01X+162346Y+006444X0120Y0150R090 S1      
317m4556            VIA   -    MD0080PA01X+145691Y+093065X0160Y    R180 S0      
327m4556            U25   -W27        A01X+145507Y+093169X0177Y    R180 S1      
317m4556            VIA   -    MD0100PA01X+163577Y+007534X0200Y         S0      
327m4556            C1566 -2          A01X+163567Y+007044X0120Y0150R090 S1      
317m4557            VIA   -    MD0080PA01X+145691Y+091151X0160Y    R180 S0      
327m4557            U25   -N27        A01X+145507Y+091256X0177Y    R180 S1      
317m4557            VIA   -    MD0100PA01X+164677Y+006934X0200Y         S0      
327m4557            C1568 -2          A01X+164667Y+006444X0120Y0150R090 S1      
317m4558            VIA   -    MD0080PA01X+145691Y+091789X0160Y    R180 S0      
327m4558            U25   -R27        A01X+145507Y+091894X0177Y    R180 S1      
317m4558            VIA   -    MD0100PA01X+165777Y+007534X0200Y         S0      
327m4558            C1570 -2          A01X+165767Y+007044X0120Y0150R090 S1      
317m4559            VIA   -    MD0080PA01X+145691Y+092427X0160Y    R180 S0      
327m4559            U25   -U27        A01X+145507Y+092532X0177Y    R180 S1      
317m4559            VIA   -    MD0100PA01X+166877Y+006934X0200Y         S0      
327m4559            C1572 -2          A01X+166867Y+006444X0120Y0150R090 S1      
317m4560            VIA   -    MD0080PA01X+146801Y+093065X0160Y    R180 S0      
327m4560            U25   -W24        A01X+146617Y+093169X0177Y    R180 S1      
317m4560            VIA   -    MD0100PA01X+167990Y+007534X0200Y         S0      
327m4560            C1574 -2          A01X+167980Y+007044X0120Y0150R090 S1      
317m4561            VIA   -    MD0080PA01X+146801Y+091789X0160Y    R180 S0      
327m4561            U25   -R24        A01X+146617Y+091894X0177Y    R180 S1      
317m4561            VIA   -    MD0100PA01X+169090Y+006934X0200Y         S0      
327m4561            C1576 -2          A01X+169080Y+006444X0120Y0150R090 S1      
317m4562            VIA   -    MD0080PA01X+142545Y+092746X0160Y    R180 S0      
327m4562            U25   -V36        A01X+142361Y+092850X0177Y    R180 S1      
327m4562            C1548 -2          A01X+153546Y+006444X0120Y0150R090 S1      
317m4562            VIA   -    MD0100PA01X+153557Y+006934X0200Y         S0      
317m4563            VIA   -    MD0080PA01X+142545Y+092108X0160Y    R180 S0      
327m4563            U25   -T36        A01X+142361Y+092213X0177Y    R180 S1      
317m4563            VIA   -    MD0100PA01X+154656Y+007534X0200Y         S0      
327m4563            C1550 -2          A01X+154646Y+007044X0120Y0150R090 S1      
317m4564            VIA   -    MD0080PA01X+142545Y+091470X0160Y    R180 S0      
327m4564            U25   -P36        A01X+142361Y+091575X0177Y    R180 S1      
317m4564            VIA   -    MD0100PA01X+155757Y+006934X0200Y         S0      
327m4564            C1552 -2          A01X+155746Y+006444X0120Y0150R090 S1      
317m4565            VIA   -    MD0080PA01X+143470Y+092427X0160Y    R180 S0      
327m4565            U25   -U33        A01X+143287Y+092532X0177Y    R180 S1      
317m4565            VIA   -    MD0100PA01X+156857Y+007534X0200Y         S0      
327m4565            C41   -2          A01X+156846Y+007044X0120Y0150R090 S1      
317m4566            VIA   -    MD0080PA01X+143470Y+091151X0160Y    R180 S0      
327m4566            U25   -N33        A01X+143287Y+091256X0177Y    R180 S1      
317m4566            VIA   -    MD0100PA01X+157957Y+006934X0200Y         S0      
327m4566            C1556 -2          A01X+157946Y+006444X0120Y0150R090 S1      
317m4567            VIA   -    MD0080PA01X+143470Y+091789X0160Y    R180 S0      
327m4567            U25   -R33        A01X+143287Y+091894X0177Y    R180 S1      
317m4567            VIA   -    MD0100PA01X+159057Y+007534X0200Y         S0      
327m4567            C1558 -2          A01X+159046Y+007044X0120Y0150R090 S1      
317m4568            VIA   -    MD0080PA01X+146801Y+092427X0160Y    R180 S0      
327m4568            U25   -U24        A01X+146617Y+092532X0177Y    R180 S1      
317m4568            VIA   -    MD0100PA01X+170190Y+007534X0200Y         S0      
327m4568            C1578 -2          A01X+170180Y+007044X0120Y0150R090 S1      
317m4569            VIA   -    MD0080PA01X+143470Y+096891X0160Y         S0      
327m4569            U25   -AL33       A01X+143287Y+096996X0177Y    R180 S1      
317m4569            VIA   -    MD0100PA01X+159179Y+002648X0200Y         S0      
327m4569            J38   -A48        A01X+159231Y+003276X0150Y0570R180 S1      
317m4570            VIA   -    MD0080PA01X+144581Y+097529X0160Y         S0      
327m4570            U25   -AN30       A01X+144397Y+097634X0177Y    R180 S1      
317m4570            VIA   -    MD0100PA01X+159890Y+001954X0200Y         S0      
327m4570            J38   -A45        A01X+159940Y+003276X0150Y0570R180 S1      
317m4571            VIA   -    MD0080PA01X+144581Y+096254X0160Y         S0      
327m4571            U25   -AJ30       A01X+144397Y+096358X0177Y    R180 S1      
317m4571            VIA   -    MD0100PA01X+162766Y+002648X0200Y         S0      
327m4571            J38   -A40        A01X+162818Y+003276X0150Y0570R180 S1      
317m4572            VIA   -    MD0080PA01X+144581Y+096891X0160Y         S0      
327m4572            U25   -AL30       A01X+144397Y+096996X0177Y    R180 S1      
317m4572            VIA   -    MD0100PA01X+163476Y+001954X0200Y         S0      
327m4572            J38   -A37        A01X+163526Y+003276X0150Y0570R180 S1      
317m4573            VIA   -    MD0080PA01X+145691Y+097529X0160Y         S0      
327m4573            U25   -AN27       A01X+145507Y+097634X0177Y    R180 S1      
317m4573            VIA   -    MD0100PA01X+164183Y+002648X0200Y         S0      
327m4573            J38   -A34        A01X+164235Y+003276X0150Y0570R180 S1      
317m4574            VIA   -    MD0080PA01X+145691Y+096254X0160Y         S0      
327m4574            U25   -AJ27       A01X+145507Y+096358X0177Y    R180 S1      
317m4574            VIA   -    MD0100PA01X+164894Y+001954X0200Y         S0      
327m4574            J38   -A31        A01X+164944Y+003276X0150Y0570R180 S1      
317m4575            VIA   -    MD0080PA01X+145691Y+096891X0160Y         S0      
327m4575            U25   -AL27       A01X+145507Y+096996X0177Y    R180 S1      
317m4575            VIA   -    MD0100PA01X+167179Y+002648X0200Y         S0      
327m4575            J38   -A27        A01X+167231Y+003276X0150Y0570R180 S1      
317m4576            VIA   -    MD0080PA01X+146801Y+097529X0160Y         S0      
327m4576            U25   -AN24       A01X+146617Y+097634X0177Y    R180 S1      
317m4576            VIA   -    MD0100PA01X+167890Y+001954X0200Y         S0      
327m4576            J38   -A24        A01X+167940Y+003276X0150Y0570R180 S1      
317m4577            VIA   -    MD0080PA01X+146801Y+096254X0160Y         S0      
327m4577            U25   -AJ24       A01X+146617Y+096358X0177Y    R180 S1      
317m4577            VIA   -    MD0100PA01X+168597Y+002648X0200Y         S0      
327m4577            J38   -A21        A01X+168648Y+003276X0150Y0570R180 S1      
317m4578            VIA   -    MD0080PA01X+142545Y+097848X0160Y         S0      
327m4578            U25   -AP36       A01X+142361Y+097953X0177Y    R180 S1      
317m4578            VIA   -    MD0100PA01X+154927Y+002648X0200Y         S0      
327m4578            J38   -A66        A01X+154979Y+003276X0150Y0570R180 S1      
317m4579            VIA   -    MD0080PA01X+142545Y+097210X0160Y         S0      
327m4579            U25   -AM36       A01X+142361Y+097315X0177Y    R180 S1      
317m4579            VIA   -    MD0100PA01X+155638Y+001954X0200Y         S0      
327m4579            J38   -A63        A01X+155688Y+003276X0150Y0570R180 S1      
317m4580            VIA   -    MD0080PA01X+142545Y+095935X0160Y         S0      
327m4580            U25   -AH36       A01X+142361Y+096039X0177Y    R180 S1      
317m4580            VIA   -    MD0100PA01X+156345Y+002648X0200Y         S0      
327m4580            J38   -A60        A01X+156396Y+003276X0150Y0570R180 S1      
317m4581            VIA   -    MD0080PA01X+142545Y+096572X0160Y         S0      
327m4581            U25   -AK36       A01X+142361Y+096677X0177Y    R180 S1      
317m4581            VIA   -    MD0100PA01X+157055Y+001954X0200Y         S0      
327m4581            J38   -A57        A01X+157105Y+003276X0150Y0570R180 S1      
317m4582            VIA   -    MD0080PA01X+143470Y+097529X0160Y         S0      
327m4582            U25   -AN33       A01X+143287Y+097634X0177Y    R180 S1      
317m4582            VIA   -    MD0100PA01X+157762Y+002648X0200Y         S0      
327m4582            J38   -A54        A01X+157814Y+003276X0150Y0570R180 S1      
317m4583            VIA   -    MD0080PA01X+143470Y+096254X0160Y         S0      
327m4583            U25   -AJ33       A01X+143287Y+096358X0177Y    R180 S1      
317m4583            VIA   -    MD0100PA01X+158472Y+001954X0200Y         S0      
327m4583            J38   -A51        A01X+158522Y+003276X0150Y0570R180 S1      
317m4584            VIA   -    MD0080PA01X+146801Y+096891X0160Y         S0      
327m4584            U25   -AL24       A01X+146617Y+096996X0177Y    R180 S1      
317m4584            VIA   -    MD0100PA01X+169307Y+001954X0200Y         S0      
327m4584            J38   -A18        A01X+169357Y+003276X0150Y0570R180 S1      
317m4585            VIA   -    MD0080PA01X+143840Y+096891X0160Y         S0      
327m4585            U25   -AL32       A01X+143657Y+096996X0177Y    R180 S1      
317m4585            VIA   -    MD0100PA01X+159519Y+002648X0200Y         S0      
327m4585            J38   -A47        A01X+159467Y+003276X0150Y0570R180 S1      
317m4586            VIA   -    MD0080PA01X+144951Y+097529X0160Y         S0      
327m4586            U25   -AN29       A01X+144767Y+097634X0177Y    R180 S1      
317m4586            VIA   -    MD0100PA01X+160230Y+001954X0200Y         S0      
327m4586            J38   -A44        A01X+160176Y+003276X0150Y0570R180 S1      
317m4587            VIA   -    MD0080PA01X+144951Y+096254X0160Y         S0      
327m4587            U25   -AJ29       A01X+144767Y+096358X0177Y    R180 S1      
317m4587            VIA   -    MD0100PA01X+163106Y+002648X0200Y         S0      
327m4587            J38   -A39        A01X+163054Y+003276X0150Y0570R180 S1      
317m4588            VIA   -    MD0080PA01X+144951Y+096891X0160Y         S0      
327m4588            U25   -AL29       A01X+144767Y+096996X0177Y    R180 S1      
317m4588            VIA   -    MD0100PA01X+163816Y+001954X0200Y         S0      
327m4588            J38   -A36        A01X+163762Y+003276X0150Y0570R180 S1      
317m4589            VIA   -    MD0080PA01X+146061Y+097529X0160Y         S0      
327m4589            U25   -AN26       A01X+145877Y+097634X0177Y    R180 S1      
317m4589            VIA   -    MD0100PA01X+164523Y+002648X0200Y         S0      
327m4589            J38   -A33        A01X+164471Y+003276X0150Y0570R180 S1      
317m4590            VIA   -    MD0080PA01X+146061Y+096254X0160Y         S0      
327m4590            U25   -AJ26       A01X+145877Y+096358X0177Y    R180 S1      
317m4590            VIA   -    MD0100PA01X+165234Y+001954X0200Y         S0      
327m4590            J38   -A30        A01X+165180Y+003276X0150Y0570R180 S1      
317m4591            VIA   -    MD0080PA01X+146061Y+096891X0160Y         S0      
327m4591            U25   -AL26       A01X+145877Y+096996X0177Y    R180 S1      
317m4591            VIA   -    MD0100PA01X+167519Y+002648X0200Y         S0      
327m4591            J38   -A26        A01X+167467Y+003276X0150Y0570R180 S1      
317m4592            VIA   -    MD0080PA01X+147171Y+097529X0160Y         S0      
327m4592            U25   -AN23       A01X+146987Y+097634X0177Y    R180 S1      
317m4592            VIA   -    MD0100PA01X+168230Y+001954X0200Y         S0      
327m4592            J38   -A23        A01X+168176Y+003276X0150Y0570R180 S1      
317m4593            VIA   -    MD0080PA01X+147171Y+096254X0160Y         S0      
327m4593            U25   -AJ23       A01X+146987Y+096358X0177Y    R180 S1      
317m4593            VIA   -    MD0100PA01X+168937Y+002648X0200Y         S0      
327m4593            J38   -A20        A01X+168885Y+003276X0150Y0570R180 S1      
317m4594            VIA   -    MD0080PA01X+142915Y+097848X0160Y         S0      
327m4594            U25   -AP35       A01X+142732Y+097953X0177Y    R180 S1      
317m4594            VIA   -    MD0100PA01X+155267Y+002648X0200Y         S0      
327m4594            J38   -A65        A01X+155215Y+003276X0150Y0570R180 S1      
317m4595            VIA   -    MD0080PA01X+142915Y+097210X0160Y         S0      
327m4595            U25   -AM35       A01X+142732Y+097315X0177Y    R180 S1      
317m4595            VIA   -    MD0100PA01X+155978Y+001954X0200Y         S0      
327m4595            J38   -A62        A01X+155924Y+003276X0150Y0570R180 S1      
317m4596            VIA   -    MD0080PA01X+142915Y+095935X0160Y         S0      
327m4596            U25   -AH35       A01X+142732Y+096039X0177Y    R180 S1      
317m4596            VIA   -    MD0100PA01X+156685Y+002648X0200Y         S0      
327m4596            J38   -A59        A01X+156633Y+003276X0150Y0570R180 S1      
317m4597            VIA   -    MD0080PA01X+142915Y+096572X0160Y         S0      
327m4597            U25   -AK35       A01X+142732Y+096677X0177Y    R180 S1      
317m4597            VIA   -    MD0100PA01X+157395Y+001954X0200Y         S0      
327m4597            J38   -A56        A01X+157341Y+003276X0150Y0570R180 S1      
317m4598            VIA   -    MD0080PA01X+143840Y+097529X0160Y         S0      
327m4598            U25   -AN32       A01X+143657Y+097634X0177Y    R180 S1      
317m4598            VIA   -    MD0100PA01X+158102Y+002648X0200Y         S0      
327m4598            J38   -A53        A01X+158050Y+003276X0150Y0570R180 S1      
317m4599            VIA   -    MD0080PA01X+143840Y+096254X0160Y         S0      
327m4599            U25   -AJ32       A01X+143657Y+096358X0177Y    R180 S1      
317m4599            VIA   -    MD0100PA01X+158812Y+001954X0200Y         S0      
327m4599            J38   -A50        A01X+158759Y+003276X0150Y0570R180 S1      
317m4600            VIA   -    MD0080PA01X+147171Y+096891X0160Y         S0      
327m4600            U25   -AL23       A01X+146987Y+096996X0177Y    R180 S1      
317m4600            VIA   -    MD0100PA01X+169647Y+001954X0200Y         S0      
327m4600            J38   -A17        A01X+169593Y+003276X0150Y0570R180 S1      
317m4601            VIA   -    MD0080PA01X+150430Y+155270X0160Y         S0      
317m4601            VIA   -    MD0080PA01X+146179Y+113329X0160Y         S0      
327m4601            U25   -CW26       A01X+145995Y+113224X0177Y    R180 S1      
327m4601            U6013 -BP26       A01X+150225Y+155270X0150Y         S1      
317m4602            VIA   -    MD0080PA01X+149957Y+155270X0160Y         S0      
317m4602            VIA   -    MD0080PA01X+145069Y+113967X0160Y         S0      
327m4602            U25   -DA29       A01X+144885Y+113862X0177Y    R180 S1      
327m4602            U6013 -CA26       A01X+149752Y+155270X0150Y         S1      
317m4603            VIA   -    MD0080PA01X+151374Y+155270X0160Y         S0      
317m4603            VIA   -    MD0080PA01X+146179Y+113967X0160Y         S0      
327m4603            U25   -DA26       A01X+145995Y+113862X0177Y    R180 S1      
327m4603            U6013 -AY26       A01X+151170Y+155270X0150Y         S1      
317m4604            VIA   -    MD0080PA01X+150902Y+155270X0160Y         S0      
317m4604            VIA   -    MD0080PA01X+146179Y+114605X0160Y         S0      
327m4604            U25   -DC26       A01X+145995Y+114500X0177Y    R180 S1      
327m4604            U6013 -BG26       A01X+150697Y+155270X0150Y         S1      
317m4605            VIA   -    MD0080PA01X+150272Y+154997X0160Y         S0      
317m4605            VIA   -    MD0080PA01X+145809Y+113329X0160Y         S0      
327m4605            U25   -CW27       A01X+145625Y+113224X0177Y    R180 S1      
327m4605            U6013 -BT29       A01X+150067Y+154997X0150Y         S1      
317m4606            VIA   -    MD0080PA01X+149800Y+154997X0160Y         S0      
317m4606            VIA   -    MD0080PA01X+144699Y+113967X0160Y         S0      
327m4606            U25   -DA30       A01X+144515Y+113862X0177Y    R180 S1      
327m4606            U6013 -CC29       A01X+149595Y+154997X0150Y         S1      
317m4607            VIA   -    MD0080PA01X+151217Y+154997X0160Y         S0      
317m4607            VIA   -    MD0080PA01X+145809Y+113967X0160Y         S0      
327m4607            U25   -DA27       A01X+145625Y+113862X0177Y    R180 S1      
327m4607            U6013 -BB29       A01X+151012Y+154997X0150Y         S1      
317m4608            VIA   -    MD0080PA01X+150745Y+154997X0160Y         S0      
317m4608            VIA   -    MD0080PA01X+145809Y+114605X0160Y         S0      
327m4608            U25   -DC27       A01X+145625Y+114500X0177Y    R180 S1      
327m4608            U6013 -BJ29       A01X+150540Y+154997X0150Y         S1      
327P3V_BAT_R        R364  -1          A01X+058639Y+009325X0198Y0197R270 S1      
317P3V_BAT_R        VIA   -    M      A01X+058639Y+009595X0200Y         S2      
017P3V_BAT_R        VIA   -    M      A18X+058639Y+009595X0260Y         S2      
017P3V_BAT_R              -    MD0100PA00X+058639Y+009595                       
327P3V_BAT_R        R1775 -2          A01X+120533Y+013387X0198Y0197     S1      
317P3V_BAT_R        VIA   -    MD0100PA00X+120843Y+013387X0200Y    R180 S0      
327P3V_BAT_R        U166  -2          A01X+121153Y+013387X0240Y0320R270 S1      
317P3V_BAT_R        VIA   -    MD0100PA00X+085420Y+014306X0200Y         S0      
317P3V_BAT          BT2   -1    D0440PA00X+115638Y+013387X0640Y0640R270 S3      
327P3V_BAT          R1775 -1          A01X+120218Y+013387X0198Y0197     S1      
327P3V_BAT          VIA   -    M      A01X+119738Y+013387X0300Y    R270 S1      
317P3V3_RTC_AUX     VIA   -    M      A01X+127598Y+008511X0200Y    R270 S2      
017P3V3_RTC_AUX     VIA   -    M      A18X+127598Y+008511X0260Y    R270 S2      
017P3V3_RTC_AUX           -    MD0100PA00X+127598Y+008511                       
327P3V3_RTC_AUX     R5052 -2          A01X+127598Y+008754X0198Y0197R270 S1      
317P3V3_RTC_AUX     VIA   -    MD0100PA00X+119059Y+009969X0200Y         S0      
327P3V3_RTC_AUX     R5051 -1          A01X+118816Y+009969X0198Y0197R180 S1      
327P3V3_RTC_AUX     U166  -3          A01X+121783Y+013131X0240Y0320R270 S1      
317P3V3_RTC_AUX     VIA   -    MD0100PA00X+122093Y+013131X0200Y         S0      
317P3V3_OCP_VCC_2   VIA   -    M      A01X+036574Y+022187X0200Y    R180 S2      
017P3V3_OCP_VCC_2   VIA   -    M      A18X+036574Y+022187X0260Y    R180 S2      
017P3V3_OCP_VCC_2         -    MD0100PA00X+036574Y+022187                       
327P3V3_OCP_VCC_2   PR3782-2          A01X+036889Y+021536X0198Y0197     S1      
327P3V3_OCP_VCC_2   PU200 -A2         A01X+036398Y+022670X0090Y    R180 S1      
327P3V3_OCP_VCC_2   C39   -1   M      A01X+036574Y+021936X0198Y0197     S1      
327P3V3_OCP_VCC_1   PR3798-2          A01X+171495Y+042034X0198Y0197R180 S1      
327P3V3_OCP_VCC_1   PC2086-1   M      A01X+171041Y+042037X0198Y0197R090 S1      
317P3V3_OCP_VCC_1   VIA   -    M      A01X+170757Y+042037X0200Y         S2      
017P3V3_OCP_VCC_1   VIA   -    M      A18X+170757Y+042037X0260Y         S2      
017P3V3_OCP_VCC_1         -    MD0100PA00X+170757Y+042037                       
327P3V3_OCP_VCC_1   PU202 -A2         A01X+170307Y+041861X0090Y    R270 S1      
327m4609            R3633 -2   M      A01X+032922Y+023938X1150Y1380R090 S1      
327m4609            U263  -11         A01X+029176Y+015579X0090Y0240R270 S1      
327m4609            C8009 -1   M      A01X+031358Y+024100X0198Y0197R180 S1      
327m4609            R8095 -1          A01X+030250Y+025042X0198Y0197R090 S1      
327m4609            PU200 -B6         A01X+035611Y+022867X0090Y    R180 S1      
327m4609            PU200 -C6         A01X+035611Y+023064X0090Y    R180 S1      
327m4609            PU200 -D6         A01X+035611Y+023261X0090Y    R180 S1      
327m4609            PU207 -6_7        A01X+036659Y+028439X0295Y0354R180 S1      
327m4609            PC2137-1          A01X+037141Y+027200X0198Y0197R090 S1      
327m4609            PC2173-1          A01X+036641Y+027497X0400Y0500     S1      
327m4609            PC2142-1          A01X+035262Y+026431X0400Y0500R270 S1      
327m4609            PD109 -C          A01X+038544Y+025606X0670Y0990     S1      
327m4609            VIA   -           A01X+033303Y+025532X0300Y    R270 S1      
327m4609            PU200 -A4         A01X+036004Y+022670X0090Y    R180 S1      
327m4609            PU200 -B4         A01X+036004Y+022867X0090Y    R180 S1      
327m4609            PU200 -C4         A01X+036004Y+023064X0090Y    R180 S1      
327m4609            PU200 -D4         A01X+036004Y+023261X0090Y    R180 S1      
327m4609            R3570 -1          A01X+031741Y+023185X0198Y0197R180 S1      
317m4609            VIA   -    MD0100PA00X+032010Y+023181X0200Y         S0      
317m4609            VIA   -    MD0100PA00X+029647Y+015871X0200Y         S0      
327m4609            C2017 -1   M      A01X+029648Y+015620X0198Y0197     S1      
317m4609            VIA   -    MD0100PA00X+034811Y+022042X0200Y         S0      
327m4609            PR4523-1          A01X+035236Y+021141X0198Y0197     S1      
327m4609            PC2149-1   M      A01X+035234Y+021532X0198Y0197     S1      
327m4609            U8002 -3   M      A01X+031350Y+024747X0260Y0380R180 S1      
327P3V3_OCP_V3_2    R3633 -1          A01X+032922Y+022087X1150Y1380R090 S1      
327P3V3_OCP_V3_2    C1861 -1   M      A01X+059526Y+015749X0198Y0197R090 S1      
327P3V3_OCP_V3_2    U235  -8          A01X+058942Y+015749X0240Y0460R090 S1      
317P3V3_OCP_V3_2    VIA   -    MD0100PA00X+059855Y+015907X0200Y    R090 S0      
317P3V3_OCP_V3_2    VIA   -    MD0100PA00X+060585Y+015214X0200Y    R090 S0      
327P3V3_OCP_V3_2    R3519 -1          A01X+060334Y+015364X0198Y0197R180 S1      
327P3V3_OCP_V3_2    R3183 -1   M      A01X+040537Y+015228X0198Y0197R180 S1      
317P3V3_OCP_V3_2    VIA   -    MD0100PA00X+040860Y+015228X0200Y         S0      
327P3V3_OCP_V3_2    R3182 -1          A01X+040537Y+015703X0198Y0197R180 S1      
327P3V3_OCP_V3_2    R3571 -1          A01X+031741Y+022785X0198Y0197R180 S1      
317P3V3_OCP_V3_2    VIA   -    MD0100PA00X+031747Y+022522X0200Y         S0      
317P3V3_OCP_V3_2    VIA   -    MD0100PA00X+031997Y+022817X0200Y         S0      
317P3V3_OCP_V3_2    VIA   -    MD0100PA00X+031747Y+022226X0200Y         S0      
327P3V3_OCP_V3_2    R3520 -1          A01X+060334Y+014964X0198Y0197R180 S1      
317P3V3_OCP_V3_2    VIA   -    MD0100PA00X+060585Y+014964X0200Y    R090 S0      
327P3V3_OCP_V3_2    R3173 -2          A18X+030002Y+004279X0198Y0197R090 S2      
317P3V3_OCP_V3_2    VIA   -    MD0100PA00X+029872Y+004002X0200Y         S0      
327P3V3_OCP_V3_2    R3174 -2          A18X+029872Y+003742X0198Y0197R180 S2      
317P3V3_OCP_V3_2    VIA   -    MD0100PA00X+029072Y+004002X0200Y         S0      
327P3V3_OCP_V3_2    R3176 -2          A18X+029072Y+004279X0198Y0197R090 S2      
317P3V3_OCP_V3_2    VIA   -    MD0100PA00X+028272Y+004002X0200Y         S0      
327P3V3_OCP_V3_2    R3162 -1          A18X+028272Y+004279X0198Y0197R270 S2      
317P3V3_OCP_V3_2    VIA   -    M      A01X+026642Y+003912X0200Y         S2      
017P3V3_OCP_V3_2    VIA   -    M      A18X+026642Y+003912X0260Y         S2      
017P3V3_OCP_V3_2          -    MD0100PA00X+026642Y+003912                       
327P3V3_OCP_V3_2    R3166 -1          A18X+029752Y+001516X0198Y0197R270 S2      
317P3V3_OCP_V3_2    VIA   -    MD0100PA00X+030023Y+001482X0200Y         S0      
317P3V3_OCP_V3_2    VIA   -    MD0100PA00X+023570Y+003976X0200Y         S0      
317P3V3_OCP_V3_2    VIA   -    MD0100PA00X+023806Y+003716X0200Y         S0      
327P3V3_OCP_V3_2    C1838 -1          A18X+025022Y+003694X0198Y0197R090 S2      
327P3V3_OCP_V3_2    C1835 -1          A18X+025412Y+003694X0198Y0197R090 S2      
317P3V3_OCP_V3_2    VIA   -    MD0100PA00X+025405Y+003942X0200Y         S0      
317P3V3_OCP_V3_2    VIA   -    MD0100PA00X+025022Y+003936X0200Y         S0      
327P3V3_OCP_V3_2    C1837 -1          A18X+024622Y+003694X0198Y0197R090 S2      
327P3V3_OCP_V3_2    C1836 -1          A18X+024222Y+003694X0198Y0197R090 S2      
327P3V3_OCP_V3_2    J35   -B11        A01X+023570Y+004437X0150Y0570R180 S1      
317P3V3_OCP_V3_2    VIA   -    MD0100PA00X+024622Y+003936X0200Y         S0      
317P3V3_OCP_V3_2    VIA   -    MD0100PA00X+024222Y+003936X0200Y         S0      
327m4610            R3807 -1          A18X+037337Y+023945X0198Y0197     S2      
317m4610            VIA   -    M      A01X+024549Y+015970X0200Y         S2      
017m4610            VIA   -    M      A18X+024549Y+015970X0260Y         S2      
017m4610                  -    MD0100PA00X+024549Y+015970                       
327m4610            Q119  -3          A01X+024226Y+015504X0170Y0200R090 S1      
327P3V3_OCP_UV_2    R3807 -2          A18X+037022Y+023945X0198Y0197     S2      
327P3V3_OCP_UV_2    PU200 -D2         A01X+036398Y+023261X0090Y    R180 S1      
317P3V3_OCP_UV_2    VIA   -    M      A01X+036556Y+023890X0200Y    R090 S2      
017P3V3_OCP_UV_2    VIA   -    M      A18X+036556Y+023890X0260Y    R090 S2      
017P3V3_OCP_UV_2          -    MD0100PA00X+036556Y+023890                       
327P3V3_OCP_UV_2    PR3795-2          A01X+037398Y+023962X0198Y0197R180 S1      
327P3V3_OCP_UV_2    PR3829-1   M      A01X+037006Y+023956X0198Y0197R090 S1      
327m4611            Q124  -3          A01X+180256Y+015928X0170Y0200R090 S1      
327m4611            R3785 -1          A18X+169056Y+043019X0198Y0197R090 S2      
317m4611            VIA   -    M      A01X+169245Y+043677X0200Y         S2      
017m4611            VIA   -    M      A18X+169245Y+043677X0260Y         S2      
017m4611                  -    MD0100PA00X+169245Y+043677                       
317m4611            VIA   -    MD0100PA00X+180256Y+015656X0200Y         S0      
327P3V3_OCP_UV_1    R3785 -2          A18X+169056Y+042704X0198Y0197R090 S2      
327P3V3_OCP_UV_1    PR3789-2          A01X+169015Y+042861X0198Y0197R270 S1      
327P3V3_OCP_UV_1    PR3790-1   M      A01X+169021Y+042469X0198Y0197R180 S1      
317P3V3_OCP_UV_1    VIA   -    M      A01X+169021Y+042186X0200Y    R180 S2      
017P3V3_OCP_UV_1    VIA   -    M      A18X+169021Y+042186X0260Y    R180 S2      
017P3V3_OCP_UV_1          -    MD0100PA00X+169021Y+042186                       
327P3V3_OCP_UV_1    PU202 -D2         A01X+169716Y+041861X0090Y    R270 S1      
327P3V3_OCP_SFF_R   R3645 -2          A01X+168692Y+038652X1150Y1380R180 S1      
327P3V3_OCP_SFF_R   C8008 -1   M      A01X+163858Y+038150X0198Y0197R180 S1      
327P3V3_OCP_SFF_R   R8092 -1          A01X+162900Y+038592X0198Y0197R090 S1      
327P3V3_OCP_SFF_R   PC2081-1          A01X+167985Y+042817X0400Y0500R270 S1      
327P3V3_OCP_SFF_R   PC2091-1          A01X+167387Y+042807X0198Y0197R090 S1      
327P3V3_OCP_SFF_R   PU202 -A4         A01X+170307Y+041468X0090Y    R270 S1      
327P3V3_OCP_SFF_R   PU202 -B4         A01X+170110Y+041468X0090Y    R270 S1      
327P3V3_OCP_SFF_R   PU202 -B6         A01X+170110Y+041074X0090Y    R270 S1      
327P3V3_OCP_SFF_R   PU202 -C4         A01X+169913Y+041468X0090Y    R270 S1      
327P3V3_OCP_SFF_R   PU202 -C6         A01X+169913Y+041074X0090Y    R270 S1      
327P3V3_OCP_SFF_R   PU202 -D4         A01X+169716Y+041468X0090Y    R270 S1      
327P3V3_OCP_SFF_R   PU202 -D6         A01X+169716Y+041074X0090Y    R270 S1      
327P3V3_OCP_SFF_R   VIA   -           A01X+168002Y+042013X0300Y         S1      
327P3V3_OCP_SFF_R   PC2163-1          A01X+166757Y+041433X0400Y0500R270 S1      
327P3V3_OCP_SFF_R   PU205 -6_7        A01X+165709Y+041420X0295Y0354R270 S1      
327P3V3_OCP_SFF_R   PD103 -C          A01X+167175Y+038560X0670Y0990R090 S1      
327P3V3_OCP_SFF_R   R3602 -1          A01X+170172Y+036977X0198Y0197     S1      
317P3V3_OCP_SFF_R   VIA   -    MD0100PA00X+169822Y+036965X0200Y         S0      
327P3V3_OCP_SFF_R   C2024 -1   M      A01X+172250Y+036879X0198Y0197R090 S1      
327P3V3_OCP_SFF_R   U266  -11         A01X+172948Y+036940X0090Y0240R090 S1      
317P3V3_OCP_SFF_R   VIA   -    MD0100PA00X+171920Y+037116X0200Y         S0      
327P3V3_OCP_SFF_R   PR4525-1          A01X+171893Y+040696X0198Y0197R090 S1      
327P3V3_OCP_SFF_R   PC2144-1   M      A01X+171504Y+040697X0198Y0197R090 S1      
327P3V3_OCP_SFF_R   U8001 -3   M      A01X+163850Y+038697X0260Y0380R180 S1      
327P3V3_OCP_SFF     R3645 -1          A01X+170542Y+038652X1150Y1380R180 S1      
317P3V3_OCP_SFF     VIA   -    MD0100PA00X+171372Y+038465X0200Y         S0      
317P3V3_OCP_SFF     VIA   -    MD0100PA00X+171372Y+038815X0200Y         S0      
317P3V3_OCP_SFF     VIA   -    MD0100PA00X+171722Y+038815X0200Y         S0      
317P3V3_OCP_SFF     VIA   -    MD0100PA00X+171722Y+038465X0200Y         S0      
317P3V3_OCP_SFF     VIA   -    MD0100PA00X+171372Y+038115X0200Y         S0      
317P3V3_OCP_SFF     VIA   -    MD0100PA00X+171722Y+038115X0200Y         S0      
327P3V3_OCP_SFF     VIA   -           A01X+171710Y+037796X0300Y         S1      
317P3V3_OCP_SFF     VIA   -    MD0100PA00X+171372Y+039165X0200Y         S0      
317P3V3_OCP_SFF     VIA   -    MD0100PA00X+171722Y+039165X0200Y         S0      
327P3V3_OCP_SFF     R3603 -1          A01X+170172Y+037377X0198Y0197     S1      
327P3V3_OCP_SFF     R3501 -1          A01X+162548Y+029474X0198Y0197R180 S1      
317P3V3_OCP_SFF     VIA   -    MD0100PA00X+162791Y+029474X0200Y    R090 S0      
327P3V3_OCP_SFF     C1862 -1   M      A01X+161740Y+030360X0198Y0197R090 S1      
327P3V3_OCP_SFF     U236  -8          A01X+161166Y+030360X0240Y0460R090 S1      
317P3V3_OCP_SFF     VIA   -    MD0100PA00X+161991Y+030360X0200Y    R090 S0      
327P3V3_OCP_SFF     R3500 -1          A01X+162548Y+029874X0198Y0197R180 S1      
317P3V3_OCP_SFF     VIA   -    MD0100PA00X+162791Y+029874X0200Y    R090 S0      
317P3V3_OCP_SFF     VIA   -    MD0100PA00X+178739Y+015183X0200Y    R270 S0      
327P3V3_OCP_SFF     R45   -1   M      A01X+178982Y+015183X0198Y0197     S1      
327P3V3_OCP_SFF     R1824 -1          A01X+178982Y+014683X0198Y0197     S1      
317P3V3_OCP_SFF     VIA   -    MD0100PA00X+172163Y+014731X0200Y         S0      
327P3V3_OCP_SFF     R8420 -2          A18X+178199Y+004018X0198Y0197R090 S2      
327P3V3_OCP_SFF     R33   -1          A18X+177376Y+003448X0198Y0197R090 S2      
317P3V3_OCP_SFF     VIA   -    MD0100PA00X+177772Y+003779X0200Y         S0      
327P3V3_OCP_SFF     R8421 -2   M      A18X+177775Y+004029X0198Y0197R090 S2      
327P3V3_OCP_SFF     C1238 -1          A18X+171319Y+004765X0198Y0197R180 S2      
327P3V3_OCP_SFF     C1237 -1          A18X+171319Y+005165X0198Y0197R180 S2      
327P3V3_OCP_SFF     C1240 -1          A18X+171319Y+003965X0198Y0197R180 S2      
327P3V3_OCP_SFF     C1239 -1          A18X+171319Y+004365X0198Y0197R180 S2      
317P3V3_OCP_SFF     VIA   -    MD0100PA00X+171011Y+003977X0200Y         S0      
327P3V3_OCP_SFF     J38   -B11 M      A01X+171011Y+004437X0150Y0570R180 S1      
317P3V3_OCP_SFF     VIA   -    MD0100PA00X+171011Y+004898X0200Y         S0      
317P3V3_OCP_SFF     VIA   -    MD0100PA00X+176896Y+003756X0200Y         S0      
327P3V3_OCP_SFF     R31   -1          A18X+176606Y+004003X0198Y0197R270 S2      
327P3V3_OCP_SFF     R8423 -2   M      A18X+176990Y+004013X0198Y0197R090 S2      
317m4612            VIA   -           A01X+037712Y+022223X0200Y         S2      
017m4612            VIA   -           A18X+037712Y+022223X0260Y         S2      
017m4612                  -     D0100PA00X+037712Y+022223                       
327m4612            PU200 -A1         A01X+036595Y+022670X0090Y    R180 S1      
327m4612            PR3824-1   M      A01X+037347Y+022514X0198Y0197     S1      
317m4613            VIA   -           A01X+170754Y+043174X0200Y    R090 S2      
017m4613            VIA   -           A18X+170754Y+043174X0260Y    R090 S2      
017m4613                  -     D0100PA00X+170754Y+043174                       
327m4613            PU202 -A1         A01X+170307Y+042058X0090Y    R270 S1      
327m4613            PR5481-1   M      A01X+170462Y+042810X0198Y0197R090 S1      
317P3V3_OCP_REG_2   VIA   -    M      A01X+037035Y+023546X0200Y    R090 S2      
017P3V3_OCP_REG_2   VIA   -    M      A18X+037035Y+023546X0260Y    R090 S2      
017P3V3_OCP_REG_2         -    MD0100PA00X+037035Y+023546                       
327P3V3_OCP_REG_2   PC2147-2          A01X+037395Y+023546X0198Y0197R180 S1      
327P3V3_OCP_REG_2   PU200 -D1         A01X+036595Y+023261X0090Y    R180 S1      
327P3V3_OCP_REG_1   PU202 -D1         A01X+169716Y+042058X0090Y    R270 S1      
317P3V3_OCP_REG_1   VIA   -    M      A01X+169546Y+042229X0200Y         S2      
017P3V3_OCP_REG_1   VIA   -    M      A18X+169546Y+042229X0260Y         S2      
017P3V3_OCP_REG_1         -    MD0100PA00X+169546Y+042229                       
327P3V3_OCP_REG_1   PC2093-2          A01X+169431Y+042858X0198Y0197R270 S1      
327m4614            R3832 -1          A01X+034670Y+023713X0198Y0197R270 S1      
317m4614            VIA   -    M      A01X+035200Y+023564X0200Y    R270 S2      
017m4614            VIA   -    M      A18X+035200Y+023564X0260Y    R270 S2      
017m4614                  -    MD0100PA00X+035200Y+023564                       
327m4614            PU200 -D7         A01X+035414Y+023261X0090Y    R180 S1      
327m4615            PU202 -D7         A01X+169716Y+040877X0090Y    R270 S1      
317m4615            VIA   -    M      A01X+169716Y+040660X0200Y         S2      
017m4615            VIA   -    M      A18X+169716Y+040660X0260Y         S2      
017m4615                  -    MD0100PA00X+169716Y+040660                       
327m4615            R3794 -1          A01X+168850Y+040464X0198Y0197R270 S1      
327P3V3_OCP_OV_2    VIA   -    M      A01X+036516Y+024337X0300Y    R270 S1      
327P3V3_OCP_OV_2    PU200 -D3         A01X+036201Y+023261X0090Y    R180 S1      
327P3V3_OCP_OV_2    PR3812-1          A01X+037398Y+024362X0198Y0197     S1      
327P3V3_OCP_OV_2    PR3829-2   M      A01X+037006Y+024271X0198Y0197R090 S1      
327P3V3_OCP_OV_1    PU202 -D3         A01X+169716Y+041664X0090Y    R270 S1      
327P3V3_OCP_OV_1    PR3791-1          A01X+168615Y+042861X0198Y0197R090 S1      
317P3V3_OCP_OV_1    VIA   -    M      A01X+169405Y+041664X0200Y         S2      
017P3V3_OCP_OV_1    VIA   -    M      A18X+169405Y+041664X0260Y         S2      
017P3V3_OCP_OV_1          -    MD0100PA00X+169405Y+041664                       
327P3V3_OCP_OV_1    PR3790-2   M      A01X+168706Y+042469X0198Y0197R180 S1      
327m4616            PC2168-1          A01X+035263Y+028372X0198Y0197R090 S1      
327m4616            PR3855-1   M      A01X+035261Y+027990X0198Y0197R270 S1      
327m4616            VIA   -    M      A01X+035734Y+028142X0300Y    R270 S1      
327m4616            PU207 -5          A01X+036265Y+028390X0100Y0280R270 S1      
327m4617            PC2157-1          A01X+165961Y+040028X0198Y0197R270 S1      
327m4617            PR3844-1   M      A01X+166361Y+040028X0198Y0197R270 S1      
327m4617            VIA   -    M      A01X+166161Y+040520X0300Y         S1      
327m4617            PU205 -5          A01X+165758Y+041026X0100Y0280     S1      
327m4618            PR3856-2          A01X+035583Y+029182X0198Y0197R270 S1      
327m4618            VIA   -    M      A01X+035739Y+028687X0300Y    R270 S1      
327m4618            PU207 -4          A01X+036265Y+028587X0100Y0280R270 S1      
327m4619            PR3846-2          A01X+165261Y+040028X0198Y0197R090 S1      
327m4619            VIA   -    M      A01X+165461Y+040500X0300Y         S1      
327m4619            PU205 -4          A01X+165561Y+041026X0100Y0280     S1      
327m4620            PU207 -8          A01X+037052Y+028390X0100Y0280R270 S1      
327m4620            VIA   -    M      A01X+037609Y+028027X0300Y    R270 S1      
327m4620            PC1322-1          A01X+038101Y+028037X0198Y0197     S1      
327m4621            PC2089-1   M      A01X+171043Y+041074X0198Y0197R270 S1      
327m4621            PU202 -A6         A01X+170307Y+041074X0090Y    R270 S1      
317m4621            VIA   -    M      A01X+170778Y+041074X0200Y         S2      
017m4621            VIA   -    M      A18X+170778Y+041074X0260Y         S2      
017m4621                  -    MD0100PA00X+170778Y+041074                       
327m4621            PC2144-2   M      A01X+171504Y+041012X0198Y0197R090 S1      
327m4621            PR4525-2          A01X+171893Y+041011X0198Y0197R090 S1      
317m4622            VIA   -    M      A01X+035591Y+022385X0200Y    R180 S2      
017m4622            VIA   -    M      A18X+035591Y+022385X0260Y    R180 S2      
017m4622                  -    MD0100PA00X+035591Y+022385                       
327m4622            PR4523-2          A01X+035551Y+021141X0198Y0197     S1      
327m4622            PC2149-2   M      A01X+035549Y+021532X0198Y0197     S1      
327m4622            PU200 -A6         A01X+035611Y+022670X0090Y    R180 S1      
327m4622            PC2151-1   M      A01X+035551Y+021934X0198Y0197R180 S1      
327m4623            PC2162-1          A01X+166111Y+042863X0198Y0197R090 S1      
327m4623            VIA   -    M      A01X+166121Y+042370X0300Y         S1      
327m4623            PU205 -8          A01X+165758Y+041814X0100Y0280     S1      
317m4624            VIA   -    M      A01X+035200Y+023064X0200Y    R270 S2      
017m4624            VIA   -    M      A18X+035200Y+023064X0260Y    R270 S2      
017m4624                  -    MD0100PA00X+035200Y+023064                       
327m4624            R3833 -2          A01X+034629Y+022507X0198Y0197     S1      
327m4624            PU200 -C7         A01X+035414Y+023064X0090Y    R180 S1      
327m4625            PU202 -C7         A01X+169913Y+040877X0090Y    R270 S1      
327m4625            R3796 -2          A01X+170296Y+040148X0198Y0197     S1      
317m4625            VIA   -    M      A01X+170296Y+040424X0200Y         S2      
017m4625            VIA   -    M      A18X+170296Y+040424X0260Y         S2      
017m4625                  -    MD0100PA00X+170296Y+040424                       
327m4626            R1520 -2          A01X+022509Y+015654X0198Y0197R090 S1      
327m4626            R1182 -2   M      A01X+022952Y+015513X0198Y0197R090 S1      
327m4626            VIA   -    M      A01X+023740Y+016396X0300Y         S1      
327m4626            R4060 -2   M      A01X+023360Y+015515X0198Y0197R090 S1      
327m4626            R4066 -1   M      A01X+023360Y+015907X0198Y0197R180 S1      
327m4626            Q119  -2          A01X+024226Y+015760X0170Y0200R090 S1      
317P3V3_OCP_EN_2    VIA   -    MD0100PA00X+038991Y+028034X0200Y         S0      
327P3V3_OCP_EN_2    VIA   -    M      A01X+037609Y+028787X0300Y    R270 S1      
327P3V3_OCP_EN_2    R3631 -2   M      A01X+038101Y+028737X0198Y0197R180 S1      
327P3V3_OCP_EN_2    PU207 -9          A01X+037052Y+028587X0100Y0280R270 S1      
327P3V3_OCP_EN_2    R1196 -2          A18X+024722Y+011174X0198Y0197     S2      
317P3V3_OCP_EN_2    VIA   -    MD0100PA00X+023433Y+010329X0200Y         S0      
327P3V3_OCP_EN_2    R1521 -2          A01X+022228Y+014471X0198Y0197R180 S1      
327m4627            R1487 -2          A01X+165004Y+042847X0198Y0197R270 S1      
327m4627            R1137 -2          A01X+165754Y+042847X0198Y0197R270 S1      
327m4627            R3845 -2   M      A01X+165379Y+042847X0198Y0197R270 S1      
327m4627            PU205 -9          A01X+165561Y+041814X0100Y0280     S1      
327m4627            VIA   -    M      A01X+165361Y+042370X0300Y         S1      
327m4628            R1136 -2   M      A01X+178413Y+016597X0198Y0197R090 S1      
327m4628            VIA   -    M      A01X+179776Y+016183X0300Y    R270 S1      
327m4628            Q124  -2          A01X+180256Y+016183X0170Y0200R090 S1      
327m4628            R5487 -2   M      A01X+179296Y+016583X0198Y0197     S1      
327m4628            R4069 -1   M      A01X+179296Y+016183X0198Y0197R180 S1      
327m4628            R1486 -2          A01X+178413Y+015888X0198Y0197R090 S1      
327m4629            VIA   -    M      A01X+068340Y+044583X0300Y    R090 S1      
327m4629            U18   -B9         A01X+070048Y+044509X0160Y    R090 S1      
327m4629            R23   -1          A01X+067558Y+044236X0198Y0197R180 S1      
327m4630            PC1321-1          A01X+038101Y+029437X0198Y0197     S1      
327m4630            VIA   -    M      A01X+037609Y+029547X0300Y    R270 S1      
327m4630            PU207 -10         A01X+037052Y+028784X0100Y0280R270 S1      
327m4631            PC2161-1          A01X+164651Y+042847X0198Y0197R090 S1      
327m4631            PU205 -10         A01X+165364Y+041814X0100Y0280     S1      
327m4631            VIA   -    M      A01X+164601Y+042370X0300Y         S1      
327P3V3_OCP_CB_2    PR3822-1          A01X+037347Y+022864X0198Y0197     S1      
317P3V3_OCP_CB_2    VIA   -    M      A01X+037033Y+022895X0200Y    R180 S2      
017P3V3_OCP_CB_2    VIA   -    M      A18X+037033Y+022895X0260Y    R180 S2      
017P3V3_OCP_CB_2          -    MD0100PA00X+037033Y+022895                       
327P3V3_OCP_CB_2    PU200 -B1         A01X+036595Y+022867X0090Y    R180 S1      
327P3V3_OCP_CB_1    PR3780-1          A01X+170112Y+042810X0198Y0197R090 S1      
317P3V3_OCP_CB_1    VIA   -    M      A01X+170112Y+042380X0200Y         S2      
017P3V3_OCP_CB_1    VIA   -    M      A18X+170112Y+042380X0260Y         S2      
017P3V3_OCP_CB_1          -    MD0100PA00X+170112Y+042380                       
327P3V3_OCP_CB_1    PU202 -B1         A01X+170110Y+042058X0090Y    R270 S1      
327m4632            R4067 -2          A01X+025476Y+015988X0198Y0197R090 S1      
327m4632            VIA   -    M      A01X+025950Y+016266X0300Y         S1      
327m4632            Q119  -6   M      A01X+024974Y+016016X0170Y0200R090 S1      
327m4632            Q119  -5          A01X+024974Y+015760X0170Y0200R090 S1      
327m4633            Q124  -5          A01X+181004Y+016183X0170Y0200R090 S1      
327m4633            Q124  -6   M      A01X+181004Y+016439X0170Y0200R090 S1      
327m4633            VIA   -    M      A01X+181490Y+016695X0300Y    R270 S1      
327m4633            R4070 -2          A01X+181970Y+016695X0198Y0197R090 S1      
327P3V3_M2_0        R3634 -1          A01X+064932Y+021936X1150Y1380R090 S1      
327P3V3_M2_0        C1920 -1          A01X+065161Y+020689X0280Y0320R180 S1      
327P3V3_M2_0        C1921 -1          A01X+064618Y+020690X0280Y0320R180 S1      
327P3V3_M2_0        J59   -14         A01X+066755Y+020886X0110Y0630R270 S1      
327P3V3_M2_0        J59   -12         A01X+066755Y+021083X0110Y0630R270 S1      
327P3V3_M2_0        R3295 -1          A01X+059024Y+040429X0198Y0197     S1      
317P3V3_M2_0        VIA   -    M      A01X+058771Y+040429X0200Y    R270 S2      
017P3V3_M2_0        VIA   -    M      A18X+058771Y+040429X0260Y    R270 S2      
017P3V3_M2_0              -    MD0100PA00X+058771Y+040429                       
327P3V3_M2_0        J59   -70         A01X+066755Y+015374X0110Y0630R270 S1      
327P3V3_M2_0        J59   -72         A01X+066755Y+015177X0110Y0630R270 S1      
327P3V3_M2_0        J59   -74         A01X+066755Y+014980X0110Y0630R270 S1      
317P3V3_M2_0        VIA   -    MD0100PA00X+066565Y+014769X0200Y         S0      
317P3V3_M2_0        VIA   -    MD0100PA00X+066288Y+014691X0200Y         S0      
317P3V3_M2_0        VIA   -    MD0100PA00X+066288Y+014991X0200Y         S0      
317P3V3_M2_0        VIA   -    MD0100PA00X+064008Y+022711X0200Y         S0      
327P3V3_M2_0        C9922 -1          A18X+066687Y+019727X0280Y0320R270 S2      
327P3V3_M2_0        C1925 -1          A18X+066640Y+020236X0198Y0197R180 S2      
327P3V3_M2_0        C1924 -1          A18X+066640Y+020636X0198Y0197R180 S2      
327P3V3_M2_0        C1923 -1          A18X+066640Y+021036X0198Y0197R180 S2      
327P3V3_M2_0        J59   -2          A01X+066755Y+022067X0110Y0630R270 S1      
327P3V3_M2_0        J59   -4          A01X+066755Y+021870X0110Y0630R270 S1      
327P3V3_M2_0        R3575 -1          A01X+063768Y+022698X0198Y0197R180 S1      
327P3V3_M2_0        J59   -16         A01X+066755Y+020689X0110Y0630R270 S1      
327P3V3_M2_0        J59   -18         A01X+066755Y+020492X0110Y0630R270 S1      
317P3V3_M2_0        VIA   -    MD0100PA00X+066278Y+021036X0200Y         S0      
317P3V3_M2_0        VIA   -    MD0100PA00X+066278Y+020536X0200Y         S0      
317P3V3_M2_0        VIA   -    MD0100PA00X+066278Y+020786X0200Y         S0      
317P3V3_M2_0        VIA   -    MD0100PA00X+065988Y+021076X0200Y         S0      
317P3V3_M2_0        VIA   -    MD0100PA00X+065988Y+020576X0200Y         S0      
317P3V3_M2_0        VIA   -    MD0100PA00X+065988Y+020826X0200Y         S0      
317P3V3_E1S_VCC_0   VIA   -    M      A01X+086662Y+028680X0200Y         S2      
017P3V3_E1S_VCC_0   VIA   -    M      A18X+086662Y+028680X0260Y         S2      
017P3V3_E1S_VCC_0         -    MD0100PA00X+086662Y+028680                       
327P3V3_E1S_VCC_0   PR3967-2          A01X+086757Y+029381X0198Y0197R270 S1      
327P3V3_E1S_VCC_0   PU295 -A2         A01X+086938Y+028197X0090Y         S1      
327P3V3_E1S_VCC_0   PC2210-1   M      A01X+086762Y+028931X0198Y0197R180 S1      
327m4634            Q126  -3          A01X+099769Y+026888X0170Y0200R090 S1      
327m4634            R3959 -1          A18X+086253Y+026481X0198Y0197R270 S2      
317m4634            VIA   -    M      A01X+086770Y+026754X0200Y         S2      
017m4634            VIA   -    M      A18X+086770Y+026754X0260Y         S2      
017m4634                  -    MD0100PA00X+086770Y+026754                       
317m4634            VIA   -    MD0100PA00X+097827Y+026493X0200Y         S0      
327P3V3_E1S_UV_0    PU295 -D2         A01X+086938Y+027606X0090Y         S1      
327P3V3_E1S_UV_0    PR3963-2          A01X+085938Y+026906X0198Y0197     S1      
327P3V3_E1S_UV_0    PR3964-1   M      A01X+086329Y+026911X0198Y0197R270 S1      
317P3V3_E1S_UV_0    VIA   -    M      A01X+086810Y+027310X0200Y         S2      
017P3V3_E1S_UV_0    VIA   -    M      A18X+086810Y+027310X0260Y         S2      
017P3V3_E1S_UV_0          -    MD0100PA00X+086810Y+027310                       
327P3V3_E1S_UV_0    R3959 -2          A18X+086253Y+026796X0198Y0197R270 S2      
317m4635            VIA   -           A01X+085624Y+028645X0200Y    R180 S2      
017m4635            VIA   -           A18X+085624Y+028645X0260Y    R180 S2      
017m4635                  -     D0100PA00X+085624Y+028645                       
327m4635            PU295 -A1         A01X+086741Y+028197X0090Y         S1      
327m4635            PR3971-1   M      A01X+085989Y+028353X0198Y0197R180 S1      
327P3V3_E1S_REG_0   PU295 -D1         A01X+086741Y+027606X0090Y         S1      
317P3V3_E1S_REG_0   VIA   -    M      A01X+086310Y+027310X0200Y         S2      
017P3V3_E1S_REG_0   VIA   -    M      A18X+086310Y+027310X0260Y         S2      
017P3V3_E1S_REG_0         -    MD0100PA00X+086310Y+027310                       
327P3V3_E1S_REG_0   PC2212-2          A01X+085941Y+027322X0198Y0197     S1      
327m4636            R3973 -1          A01X+088385Y+026741X0198Y0197     S1      
317m4636            VIA   -    M      A01X+088135Y+026741X0200Y         S2      
017m4636            VIA   -    M      A18X+088135Y+026741X0260Y         S2      
017m4636                  -    MD0100PA00X+088135Y+026741                       
327m4636            PU295 -D7         A01X+087922Y+027606X0090Y         S1      
327P3V3_E1S_OV_0    PU295 -D3         A01X+087134Y+027606X0090Y         S1      
327P3V3_E1S_OV_0    PR3965-1          A01X+085938Y+026506X0198Y0197R180 S1      
327P3V3_E1S_OV_0    PR3964-2   M      A01X+086329Y+026596X0198Y0197R270 S1      
327P3V3_E1S_OV_0    VIA   -    M      A01X+086852Y+026365X0300Y    R270 S1      
327m4637            PR3945-1   M      A01X+075984Y+026532X0198Y0197R180 S1      
327m4637            PC2197-1          A01X+075984Y+026932X0198Y0197R180 S1      
327m4637            PU293 -5          A01X+076983Y+027135X0100Y0280R270 S1      
327m4637            VIA   -    M      A01X+076477Y+026732X0300Y    R270 S1      
327m4638            PR3947-2          A01X+075984Y+027632X0198Y0197     S1      
327m4638            VIA   -    M      A01X+076396Y+027278X0300Y    R270 S1      
327m4638            PU293 -4          A01X+076983Y+027332X0100Y0280R270 S1      
327m4639            PC2203-1          A01X+078819Y+026782X0198Y0197     S1      
327m4639            VIA   -    M      A01X+078327Y+026772X0300Y    R270 S1      
327m4639            PU293 -8          A01X+077770Y+027135X0100Y0280R270 S1      
317m4640            VIA   -    M      A01X+087745Y+028482X0200Y         S2      
017m4640            VIA   -    M      A18X+087745Y+028482X0260Y         S2      
017m4640                  -    MD0100PA00X+087745Y+028482                       
327m4640            PR4527-2          A01X+087789Y+029736X0198Y0197R180 S1      
327m4640            PC2213-2   M      A01X+087787Y+029335X0198Y0197R180 S1      
327m4640            PU295 -A6         A01X+087725Y+028197X0090Y         S1      
327m4640            PC2216-1   M      A01X+087784Y+028944X0198Y0197     S1      
317m4641            VIA   -    M      A01X+088576Y+028436X0200Y    R270 S2      
017m4641            VIA   -    M      A18X+088576Y+028436X0260Y    R270 S2      
017m4641                  -    MD0100PA00X+088576Y+028436                       
327m4641            R3977 -2          A01X+088650Y+028186X0198Y0197R090 S1      
327m4641            PU295 -C7         A01X+087922Y+027803X0090Y         S1      
327m4642            R3946 -2          A01X+078819Y+027482X0198Y0197R180 S1      
327m4642            VIA   -    M      A01X+078327Y+027532X0300Y    R270 S1      
327m4642            PU293 -9          A01X+077770Y+027332X0100Y0280R270 S1      
327m4643            PC2201-1          A01X+078819Y+028182X0198Y0197     S1      
327m4643            VIA   -    M      A01X+078327Y+028292X0300Y    R270 S1      
327m4643            PU293 -10         A01X+077770Y+027529X0100Y0280R270 S1      
317P3V3_E1S_CB_0    VIA   -    M      A01X+086323Y+028000X0200Y         S2      
017P3V3_E1S_CB_0    VIA   -    M      A18X+086323Y+028000X0260Y         S2      
017P3V3_E1S_CB_0          -    MD0100PA00X+086323Y+028000                       
327P3V3_E1S_CB_0    PU295 -B1         A01X+086741Y+028000X0090Y         S1      
327P3V3_E1S_CB_0    PR3969-1          A01X+085989Y+028003X0198Y0197R180 S1      
327m4644            R648  -2          A18X+078958Y+047534X0198Y0197     S2      
317m4644            VIA   -    M      A01X+078388Y+047534X0200Y    R180 S2      
017m4644            VIA   -    M      A18X+078388Y+047534X0260Y    R180 S2      
017m4644                  -    MD0100PA00X+078388Y+047534                       
327m4644            U18   -V12        A01X+075087Y+045454X0160Y    R090 S1      
317m4644            VIA   -    MD0100PA00X+075241Y+045607X0180Y    R090 S0      
327P3V3_E1S_0_R     R3767 -2          A01X+088218Y+023518X1150Y1380R090 S1      
327P3V3_E1S_0_R     C8010 -1   M      A01X+088108Y+030150X0198Y0197R180 S1      
327P3V3_E1S_0_R     R8098 -1          A01X+087150Y+031642X0198Y0197R090 S1      
327P3V3_E1S_0_R     PC2204-1          A01X+077346Y+026029X0400Y0500R090 S1      
327P3V3_E1S_0_R     PU293 -6_7        A01X+077377Y+027185X0295Y0354R180 S1      
327P3V3_E1S_0_R     PU295 -B6         A01X+087725Y+028000X0090Y         S1      
327P3V3_E1S_0_R     PU295 -C6         A01X+087725Y+027803X0090Y         S1      
327P3V3_E1S_0_R     PU295 -D6         A01X+087725Y+027606X0090Y         S1      
327P3V3_E1S_0_R     PR4527-1   M      A01X+088104Y+029736X0198Y0197R180 S1      
327P3V3_E1S_0_R     PC2213-1   M      A01X+088102Y+029335X0198Y0197R180 S1      
327P3V3_E1S_0_R     U276  -11         A01X+085299Y+021538X0090Y0240R270 S1      
327P3V3_E1S_0_R     C2069 -1          A18X+085270Y+021636X0198Y0197     S2      
327P3V3_E1S_0_R     R3758 -1          A01X+086847Y+022776X0198Y0197R180 S1      
317P3V3_E1S_0_R     VIA   -    MD0100PA00X+085593Y+021538X0200Y         S0      
327P3V3_E1S_0_R     PU295 -A4         A01X+087331Y+028197X0090Y         S1      
327P3V3_E1S_0_R     PU295 -B4         A01X+087331Y+028000X0090Y         S1      
327P3V3_E1S_0_R     PU295 -C4         A01X+087331Y+027803X0090Y         S1      
327P3V3_E1S_0_R     PU295 -D4         A01X+087331Y+027606X0090Y         S1      
327P3V3_E1S_0_R     PD113 -C          A01X+084635Y+025677X0670Y0990     S1      
327P3V3_E1S_0_R     PC2220-1          A01X+086258Y+023407X0400Y0500     S1      
327P3V3_E1S_0_R     PC2218-1          A01X+086117Y+024044X0198Y0197R180 S1      
317P3V3_E1S_0_R     VIA   -    M      A01X+086753Y+023179X0200Y         S2      
017P3V3_E1S_0_R     VIA   -    M      A18X+086753Y+023179X0260Y         S2      
017P3V3_E1S_0_R           -    MD0100PA00X+086753Y+023179                       
327P3V3_E1S_0_R     U8003 -3   M      A01X+088100Y+031097X0260Y0380R180 S1      
327m4645            Q126  -5          A01X+100517Y+027144X0170Y0200R090 S1      
327m4645            R4072 -2          A01X+101483Y+027400X0198Y0197R090 S1      
327m4645            VIA   -    M      A01X+101003Y+027400X0300Y         S1      
327m4645            Q126  -6   M      A01X+100517Y+027400X0170Y0200R090 S1      
327P3V3_E1S_0       R3767 -1          A01X+088218Y+021668X1150Y1380R090 S1      
327P3V3_E1S_0       R2317 -1          A01X+094452Y+018505X0198Y0197R180 S1      
317P3V3_E1S_0       VIA   -    MD0100PA00X+094452Y+018209X0200Y         S0      
327P3V3_E1S_0       C1283 -1          A18X+093317Y+018939X0198Y0197     S2      
327P3V3_E1S_0       C1282 -1          A18X+093337Y+019339X0198Y0197     S2      
327P3V3_E1S_0       C508  -1   M      A01X+092547Y+026722X0198Y0197R270 S1      
327P3V3_E1S_0       U44   -5          A01X+093135Y+026722X0140Y0490R270 S1      
317P3V3_E1S_0       VIA   -    MD0100PA00X+092234Y+026388X0200Y    R270 S0      
317P3V3_E1S_0       VIA   -    MD0100PA00X+093577Y+019142X0200Y         S0      
317P3V3_E1S_0       VIA   -    MD0100PA00X+093927Y+019142X0200Y         S0      
327P3V3_E1S_0       J90   -B11        A01X+093150Y+019120X0150Y0500R090 S1      
327P3V3_E1S_0       R10287-1          A01X+088115Y+018745X0198Y0197     S1      
317P3V3_E1S_0       VIA   -    MD0100PA00X+087822Y+018745X0200Y         S0      
327P3V3_E1S_0       R3530 -1          A01X+087430Y+017136X0198Y0197R180 S1      
327P3V3_E1S_0       R3532 -1          A01X+087430Y+017686X0198Y0197R180 S1      
327P3V3_E1S_0       R3760 -1          A01X+086847Y+022376X0198Y0197R180 S1      
317P3V3_E1S_0       VIA   -    MD0100PA00X+089662Y+020966X0200Y         S0      
317P3V3_E1S_0       VIA   -    MD0100PA00X+089412Y+020966X0200Y         S0      
317P3V3_E1S_0       VIA   -    MD0100PA00X+089412Y+020716X0200Y         S0      
317P3V3_E1S_0       VIA   -    MD0100PA00X+089662Y+020716X0200Y         S0      
317P3V3_E1S_0       VIA   -    MD0100PA00X+088893Y+020932X0200Y         S0      
317P3V3_E1S_0       VIA   -    MD0100PA00X+089162Y+020966X0200Y         S0      
317P3V3_E1S_0       VIA   -    MD0100PA00X+088893Y+020682X0200Y         S0      
317P3V3_E1S_0       VIA   -    MD0100PA00X+089162Y+020716X0200Y         S0      
327P3V3_E1S_0       VIA   -           A01X+086990Y+020956X0300Y    R090 S1      
327P3V3_E1S_0       R1673 -1          A01X+088114Y+018317X0198Y0197     S1      
317P3V3_E1S_0       VIA   -    MD0100PA00X+087833Y+018317X0200Y         S0      
317P3V3_E1S_0       VIA   -    MD0100PA00X+087670Y+017136X0200Y    R180 S0      
317P3V3_E1S_0       VIA   -    MD0100PA00X+087670Y+017686X0200Y    R180 S0      
327P3V3_E1S_0       C1998 -1   M      A01X+087114Y+016636X0198Y0197     S1      
317P3V3_E1S_0       VIA   -    MD0100PA00X+087114Y+016386X0200Y    R180 S0      
327P3V3_E1S_0       U279  -1          A01X+085969Y+016806X0240Y0460R270 S1      
317P3V3_AUX_VOS     VIA   -    M      A01X+178492Y+018605X0200Y    R270 S2      
017P3V3_AUX_VOS     VIA   -    M      A18X+178492Y+018605X0260Y    R270 S2      
017P3V3_AUX_VOS           -    MD0100PA00X+178492Y+018605                       
327P3V3_AUX_VOS     PU9   -28         A01X+178794Y+019219X0110Y0230R270 S1      
327P3V3_AUX_VOS     PR836 -1          A01X+178408Y+018246X0198Y0197R180 S1      
327P3V3_AUX_VDRV    PU9   -5          A01X+180650Y+020007X0110Y0240R270 S1      
327P3V3_AUX_VDRV    PC581 -1   M      A01X+181183Y+020260X0280Y0320     S1      
317P3V3_AUX_VDRV    VIA   -           A01X+181619Y+020888X0200Y    R270 S2      
017P3V3_AUX_VDRV    VIA   -           A18X+181619Y+020888X0260Y    R270 S2      
017P3V3_AUX_VDRV          -     D0100PA00X+181619Y+020888                       
327P3V3_AUX_VDRV    PR8389-1   M      A01X+181631Y+020510X0198Y0197R270 S1      
317P3V3_AUX_VCC     VIA   -    M      A01X+181127Y+019810X0200Y    R270 S2      
017P3V3_AUX_VCC     VIA   -    M      A18X+181127Y+019810X0260Y    R270 S2      
017P3V3_AUX_VCC           -    MD0100PA00X+181127Y+019810                       
327P3V3_AUX_VCC     PU9   -4          A01X+180650Y+019810X0110Y0240R270 S1      
327P3V3_AUX_VCC     PC591 -1   M      A01X+181767Y+019760X0280Y0320R180 S1      
327P3V3_AUX_VCC     PR8389-2          A01X+181631Y+020195X0198Y0197R270 S1      
327P3V3_AUX_SS      VIA   -           A01X+178505Y+017758X0300Y    R180 S1      
327P3V3_AUX_SS      PU9   -29         A01X+179036Y+018968X0110Y0230R180 S1      
327P3V3_AUX_SS      PR833 -1   M      A01X+178981Y+018372X0198Y0197R270 S1      
327P3V3_AUX_MODE    VIA   -           A18X+180960Y+018078X0260Y    R180 S2      
317P3V3_AUX_MODE    VIA   -    MD0100PA00X+180257Y+018691X0200Y    R180 S0      
327P3V3_AUX_MODE    PR832 -1          A01X+180411Y+018372X0198Y0197R270 S1      
327P3V3_AUX_MODE    PU9   -36         A01X+180414Y+018968X0110Y0230R180 S1      
327P3V3_AUX_ILIM    PR834 -1          A01X+180771Y+018372X0198Y0197R270 S1      
327P3V3_AUX_ILIM    PU9   -1          A01X+180655Y+019219X0110Y0230R270 S1      
317P3V3_AUX_ILIM    VIA   -    M      A01X+180647Y+018687X0200Y    R090 S2      
017P3V3_AUX_ILIM    VIA   -    M      A18X+180647Y+018687X0260Y    R090 S2      
017P3V3_AUX_ILIM          -    MD0100PA00X+180647Y+018687                       
327P3V3_AUX_FB      PR831 -1   M      A01X+179701Y+018372X0198Y0197R270 S1      
327P3V3_AUX_FB      PR830 -1          A01X+180051Y+018372X0198Y0197R270 S1      
327P3V3_AUX_FB      PU9   -30         A01X+179232Y+018973X0110Y0240R180 S1      
327P3V3_AUX_FB      PC569 -1   M      A01X+179344Y+018372X0198Y0197R270 S1      
327P3V3_AUX_EN      R1571 -2   M      A01X+178165Y+019080X0198Y0197     S1      
317P3V3_AUX_EN      VIA   -    M      A01X+178532Y+019307X0200Y    R270 S2      
017P3V3_AUX_EN      VIA   -    M      A18X+178532Y+019307X0260Y    R270 S2      
017P3V3_AUX_EN            -    MD0100PA00X+178532Y+019307                       
327P3V3_AUX_EN      PU9   -27         A01X+178799Y+019416X0110Y0240R270 S1      
327P3V3_AUX_EN      PC1870-1          A01X+178165Y+018691X0198Y0197R180 S1      
327P3V3_AUX_EN      R3117 -2          A18X+179799Y+018259X0198Y0197R270 S2      
327P3V3_AUX_EN      R3118 -1   M      A18X+179164Y+018782X0198Y0197R270 S2      
317P3V3_AUX         VIA   -    MD0100PA00X+007178Y+016519X0200Y         S0      
327P3V3_AUX         R1322 -1          A01X+007418Y+016519X0198Y0197     S1      
327P3V3_AUX         C1106 -1   M      A01X+010168Y+015369X0198Y0197     S1      
317P3V3_AUX         VIA   -    MD0100PA00X+010168Y+015119X0200Y         S0      
327P3V3_AUX         U56   -9          A01X+009697Y+015384X0090Y0240R270 S1      
317P3V3_AUX         VIA   -    MD0100PA00X+007973Y+014519X0200Y         S0      
327P3V3_AUX         R1328 -1          A01X+007733Y+014519X0198Y0197R180 S1      
317P3V3_AUX         VIA   -    MD0100PA00X+016667Y+050290X0200Y         S0      
317P3V3_AUX         VIA   -    MD0100PA00X+016676Y+050688X0200Y         S0      
327P3V3_AUX         R1481 -1          A01X+017407Y+050480X0850Y1150R270 S1      
317P3V3_AUX         VIA   -    MD0100PA00X+017212Y+041235X0200Y         S0      
327P3V3_AUX         R1052 -1          A01X+017452Y+041235X0198Y0197     S1      
327P3V3_AUX         R1239 -1          A18X+084934Y+129598X0198Y0197R180 S2      
317P3V3_AUX         VIA   -    MD0100PA00X+084690Y+129598X0200Y         S0      
327P3V3_AUX         R1241 -1          A18X+084938Y+129147X0198Y0197R180 S2      
317P3V3_AUX         VIA   -    MD0100PA00X+084693Y+129147X0200Y         S0      
327P3V3_AUX         R513  -1          A18X+061635Y+126299X0198Y0197     S2      
317P3V3_AUX         VIA   -    MD0100PA00X+061604Y+136717X0200Y         S0      
327P3V3_AUX         R8146 -1          A01X+061928Y+136717X0198Y0197     S1      
317P3V3_AUX         VIA   -    MD0100PA00X+061662Y+138623X0200Y    R090 S0      
327P3V3_AUX         R8380 -1          A01X+061920Y+138673X0198Y0197     S1      
317P3V3_AUX         VIA   -    MD0100PA00X+065188Y+139107X0200Y    R180 S0      
327P3V3_AUX         PR393 -2          A01X+065188Y+138846X0198Y0197R090 S1      
327P3V3_AUX         PR394 -2          A01X+070166Y+139514X0198Y0197R090 S1      
317P3V3_AUX         VIA   -    MD0100PA00X+070169Y+139954X0200Y    R180 S0      
317P3V3_AUX         VIA   -    MD0100PA00X+083234Y+127463X0200Y         S0      
317P3V3_AUX         VIA   -    MD0100PA00X+083227Y+127730X0200Y         S0      
327P3V3_AUX         L25   -1          A18X+083576Y+127662X0280Y0320R270 S2      
317P3V3_AUX         VIA   -    MD0100PA00X+063509Y+127710X0200Y         S0      
327P3V3_AUX         C1067 -1   M      A01X+045075Y+157320X0120Y0150R270 S1      
327P3V3_AUX         R4125 -1          A18X+064652Y+163682X0198Y0197     S2      
317P3V3_AUX         VIA   -    MD0100PA00X+137980Y+173312X0200Y    R270 S0      
327P3V3_AUX         R4547 -1          A01X+138223Y+173312X0198Y0197     S1      
317P3V3_AUX         VIA   -    MD0100PA00X+139004Y+171204X0200Y    R090 S0      
327P3V3_AUX         C8    -1   M      A01X+138762Y+171204X0198Y0197R180 S1      
327P3V3_AUX         U316  -5          A01X+138762Y+171644X0160Y0200R180 S1      
317P3V3_AUX         VIA   -    MD0100PA00X+138204Y+170404X0200Y    R270 S0      
327P3V3_AUX         R4549 -1          A01X+138447Y+170404X0198Y0197     S1      
317P3V3_AUX         VIA   -    MD0100PA00X+139175Y+169775X0200Y    R180 S0      
327P3V3_AUX         R4560 -1          A01X+139175Y+169524X0198Y0197R180 S1      
327P3V3_AUX         R4198 -1          A01X+144907Y+168430X0198Y0197R270 S1      
317P3V3_AUX         VIA   -    MD0100PA00X+144907Y+168672X0200Y         S0      
317P3V3_AUX         VIA   -    MD0100PA00X+144508Y+168668X0200Y         S0      
327P3V3_AUX         R4206 -1          A01X+144508Y+168425X0198Y0197R270 S1      
317P3V3_AUX         VIA   -    MD0100PA00X+138192Y+167688X0200Y    R180 S0      
327P3V3_AUX         R4562 -1          A01X+138192Y+167439X0198Y0197     S1      
317P3V3_AUX         VIA   -    MD0100PA00X+139207Y+167688X0200Y    R180 S0      
327P3V3_AUX         R4561 -1          A01X+139207Y+167439X0198Y0197R180 S1      
327P3V3_AUX         C10   -1   M      A01X+082759Y+049791X0198Y0197     S1      
327P3V3_AUX         U75   -5          A01X+082903Y+049161X0140Y0490R090 S1      
317P3V3_AUX         VIA   -    MD0100PA00X+082826Y+050103X0200Y         S0      
327P3V3_AUX         R496  -1          A01X+080958Y+050800X0198Y0197R180 S1      
327P3V3_AUX         R6061 -2          A01X+080969Y+049534X0198Y0197     S1      
317P3V3_AUX         VIA   -    MD0100PA00X+081311Y+049534X0200Y         S0      
327P3V3_AUX         R1527 -2          A01X+077823Y+049134X0198Y0197     S1      
317P3V3_AUX         VIA   -    MD0100PA00X+078709Y+049068X0200Y    R180 S0      
327P3V3_AUX         U18   -W16        A01X+075402Y+046714X0160Y    R090 S1      
317P3V3_AUX         VIA   -    MD0100PA00X+075556Y+046867X0180Y    R090 S0      
327P3V3_AUX         U18   -C16        A01X+070363Y+046714X0160Y    R090 S1      
317P3V3_AUX         VIA   -    MD0100PA00X+070210Y+046867X0180Y    R090 S0      
327P3V3_AUX         U18   -W11        A01X+075402Y+045139X0160Y    R090 S1      
317P3V3_AUX         VIA   -    MD0100PA00X+075556Y+044985X0180Y    R090 S0      
327P3V3_AUX         U18   -C12        A01X+070363Y+045454X0160Y    R090 S1      
317P3V3_AUX         VIA   -    MD0100PA00X+070210Y+045607X0180Y    R090 S0      
327P3V3_AUX         U18   -W7         A01X+075402Y+043879X0160Y    R090 S1      
317P3V3_AUX         VIA   -    MD0100PA00X+075556Y+043726X0180Y    R090 S0      
327P3V3_AUX         U18   -R10        A01X+074143Y+044824X0160Y    R090 S1      
327P3V3_AUX         U18   -R9         A01X+074143Y+044509X0160Y    R090 S1      
327P3V3_AUX         C356  -1   M      A18X+074454Y+044828X0164Y0164     S2      
327P3V3_AUX         U18   -R11        A01X+074143Y+045139X0160Y    R090 S1      
327P3V3_AUX         U18   -R12        A01X+074143Y+045454X0160Y    R090 S1      
327P3V3_AUX         U18   -R13        A01X+074143Y+045769X0160Y    R090 S1      
327P3V3_AUX         U18   -R14        A01X+074143Y+046084X0160Y    R090 S1      
327P3V3_AUX         C360  -1   M      A18X+074454Y+045765X0164Y0164     S2      
327P3V3_AUX         C361  -1   M      A18X+074454Y+045284X0164Y0164     S2      
317P3V3_AUX         VIA   -    MD0100PA00X+074296Y+044670X0180Y    R090 S0      
317P3V3_AUX         VIA   -    MD0100PA00X+074296Y+044356X0180Y    R090 S0      
317P3V3_AUX         VIA   -    MD0100PA00X+074296Y+044985X0180Y    R090 S0      
317P3V3_AUX         VIA   -    MD0100PA00X+074296Y+045607X0180Y    R090 S0      
317P3V3_AUX         VIA   -    MD0100PA00X+074296Y+046237X0180Y    R090 S0      
317P3V3_AUX         VIA   -    MD0100PA00X+074296Y+045922X0180Y    R090 S0      
327P3V3_AUX         C1175 -1          A18X+073509Y+044198X0164Y0164R180 S2      
327P3V3_AUX         U18   -P8         A01X+073828Y+044194X0160Y    R090 S1      
327P3V3_AUX         U18   -N8         A01X+073513Y+044194X0160Y    R090 S1      
327P3V3_AUX         U18   -M8         A01X+073198Y+044194X0160Y    R090 S1      
317P3V3_AUX         VIA   -    MD0100PA00X+073981Y+044040X0180Y    R090 S0      
317P3V3_AUX         VIA   -    MD0100PA00X+073666Y+044040X0180Y    R090 S0      
317P3V3_AUX         VIA   -    MD0100PA00X+073351Y+044040X0180Y    R090 S0      
327P3V3_AUX         U18   -L11        A01X+072883Y+045139X0160Y    R090 S1      
327P3V3_AUX         U18   -K12        A01X+072568Y+045454X0160Y    R090 S1      
327P3V3_AUX         U18   -K13        A01X+072568Y+045769X0160Y    R090 S1      
327P3V3_AUX         U18   -L12        A01X+072883Y+045454X0160Y    R090 S1      
327P3V3_AUX         C1174 -1   M      A18X+072572Y+045765X0164Y0164R270 S2      
327P3V3_AUX         C1176 -1   M      A18X+072572Y+045284X0164Y0164     S2      
327P3V3_AUX         C1173 -1   M      A18X+073015Y+045765X0164Y0164R270 S2      
327P3V3_AUX         U18   -N10        A01X+073513Y+044824X0160Y    R090 S1      
327P3V3_AUX         C358  -1   M      A18X+073509Y+044828X0164Y0164R090 S2      
327P3V3_AUX         U18   -K10        A01X+072568Y+044824X0160Y    R090 S1      
327P3V3_AUX         C359  -1   M      A18X+072572Y+044828X0164Y0164R090 S2      
327P3V3_AUX         C362  -1   M      A18X+073015Y+044828X0164Y0164R090 S2      
327P3V3_AUX         U18   -N11        A01X+073513Y+045139X0160Y    R090 S1      
327P3V3_AUX         U18   -M11        A01X+073198Y+045139X0160Y    R090 S1      
327P3V3_AUX         C1171 -1   M      A18X+073509Y+045284X0164Y0164R180 S2      
327P3V3_AUX         U18   -N13        A01X+073513Y+045769X0160Y    R090 S1      
327P3V3_AUX         U18   -N12        A01X+073513Y+045454X0160Y    R090 S1      
327P3V3_AUX         U18   -M12        A01X+073198Y+045454X0160Y    R090 S1      
327P3V3_AUX         U18   -K11        A01X+072568Y+045139X0160Y    R090 S1      
317P3V3_AUX         VIA   -    MD0100PA00X+072414Y+044985X0180Y    R090 S0      
317P3V3_AUX         VIA   -    MD0100PA00X+072729Y+044985X0180Y    R090 S0      
317P3V3_AUX         VIA   -    MD0100PA00X+072414Y+045607X0180Y    R090 S0      
317P3V3_AUX         VIA   -    MD0100PA00X+072414Y+045922X0180Y    R090 S0      
317P3V3_AUX         VIA   -    MD0100PA00X+072729Y+045607X0180Y    R090 S0      
317P3V3_AUX         VIA   -    MD0100PA00X+073666Y+044670X0180Y    R090 S0      
317P3V3_AUX         VIA   -    MD0100PA00X+072414Y+044670X0180Y    R090 S0      
317P3V3_AUX         VIA   -    MD0100PA00X+073666Y+044985X0180Y    R090 S0      
317P3V3_AUX         VIA   -    MD0100PA00X+073351Y+044985X0180Y    R090 S0      
317P3V3_AUX         VIA   -    MD0100PA00X+073351Y+045607X0180Y    R090 S0      
317P3V3_AUX         VIA   -    MD0100PA00X+073666Y+045607X0180Y    R090 S0      
317P3V3_AUX         VIA   -    MD0100PA00X+073666Y+045922X0180Y    R090 S0      
327P3V3_AUX         R1189 -2          A18X+073015Y+044042X0198Y0197R270 S2      
327P3V3_AUX         U18   -L8         A01X+072883Y+044194X0160Y    R090 S1      
317P3V3_AUX         VIA   -    MD0100PA00X+072729Y+044040X0180Y    R090 S0      
327P3V3_AUX         U18   -H11        A01X+071938Y+045139X0160Y    R090 S1      
327P3V3_AUX         U18   -H12        A01X+071938Y+045454X0160Y    R090 S1      
327P3V3_AUX         C355  -1   M      A18X+071627Y+045284X0164Y0164R180 S2      
327P3V3_AUX         U18   -G13        A01X+071623Y+045769X0160Y    R090 S1      
327P3V3_AUX         U18   -H14        A01X+071938Y+046084X0160Y    R090 S1      
327P3V3_AUX         C1172 -1   M      A18X+071627Y+045765X0164Y0164R180 S2      
327P3V3_AUX         U18   -G10        A01X+071623Y+044824X0160Y    R090 S1      
327P3V3_AUX         U18   -H9         A01X+071938Y+044509X0160Y    R090 S1      
327P3V3_AUX         C357  -1   M      A18X+071627Y+044828X0164Y0164R180 S2      
317P3V3_AUX         VIA   -    MD0100PA00X+071784Y+044985X0180Y    R090 S0      
317P3V3_AUX         VIA   -    MD0100PA00X+071784Y+045607X0180Y    R090 S0      
317P3V3_AUX         VIA   -    MD0100PA00X+071784Y+046237X0180Y    R090 S0      
317P3V3_AUX         VIA   -    MD0100PA00X+071469Y+045922X0180Y    R090 S0      
317P3V3_AUX         VIA   -    MD0100PA00X+071469Y+044670X0180Y    R090 S0      
317P3V3_AUX         VIA   -    MD0100PA00X+071784Y+044356X0180Y    R090 S0      
327P3V3_AUX         U18   -C7         A01X+070363Y+043879X0160Y    R090 S1      
317P3V3_AUX         VIA   -    MD0100PA00X+070210Y+043726X0180Y    R090 S0      
317P3V3_AUX         VIA   -    MD0100PA00X+073351Y+042466X0180Y    R090 S0      
327P3V3_AUX         U18   -M3         A01X+073198Y+042619X0160Y    R090 S1      
327P3V3_AUX         R1188 -2   M      A01X+072750Y+039329X0198Y0197R270 S1      
327P3V3_AUX         R1190 -2          A01X+073150Y+039329X0198Y0197R270 S1      
317P3V3_AUX         VIA   -    MD0100PA00X+072750Y+039086X0200Y    R090 S0      
327P3V3_AUX         R1186 -2          A18X+072750Y+039329X0198Y0197R090 S2      
327P3V3_AUX         R6023 -1   M      A18X+067950Y+038794X0198Y0197R090 S2      
327P3V3_AUX         R6021 -1   M      A18X+067550Y+038794X0198Y0197R090 S2      
327P3V3_AUX         R6017 -1          A18X+068350Y+038794X0198Y0197R090 S2      
327P3V3_AUX         R6016 -1          A18X+068350Y+039329X0198Y0197R270 S2      
327P3V3_AUX         R6019 -1   M      A18X+067550Y+039329X0198Y0197R270 S2      
327P3V3_AUX         R6020 -1   M      A18X+067950Y+039329X0198Y0197R270 S2      
317P3V3_AUX         VIA   -    MD0100PA00X+067150Y+039086X0200Y         S0      
327P3V3_AUX         C1058 -1   M      A01X+064950Y+037642X0198Y0197R090 S1      
327P3V3_AUX         U30   -5          A01X+065526Y+038032X0220Y0530     S1      
317P3V3_AUX         VIA   -    MD0100PA00X+064950Y+037350X0200Y         S0      
327P3V3_AUX         R1009 -1          A01X+065174Y+030709X0198Y0197R180 S1      
317P3V3_AUX         VIA   -    MD0100PA00X+064217Y+031128X0200Y         S0      
327P3V3_AUX         R994  -1          A01X+062670Y+030288X0198Y0197R270 S1      
317P3V3_AUX         VIA   -    MD0100PA00X+062647Y+030534X0200Y         S0      
317P3V3_AUX         VIA   -    MD0100PA00X+047915Y+031550X0200Y    R270 S0      
327P3V3_AUX         R6245 -1          A18X+047664Y+031550X0198Y0197R090 S2      
317P3V3_AUX         VIA   -    M      A01X+048382Y+028589X0200Y    R270 S2      
017P3V3_AUX         VIA   -    M      A18X+048382Y+028589X0260Y    R270 S2      
017P3V3_AUX               -    MD0100PA00X+048382Y+028589                       
327P3V3_AUX         R6244 -1          A01X+048711Y+028515X0198Y0197R090 S1      
327P3V3_AUX         PR3951-2          A01X+100540Y+022150X0198Y0197R090 S1      
327P3V3_AUX         R3948 -1          A01X+100140Y+022150X0198Y0197R270 S1      
317P3V3_AUX         VIA   -    MD0100PA00X+100120Y+022390X0200Y    R270 S0      
327P3V3_AUX         L15   -2          A01X+130088Y+015750X0280Y0320R270 S1      
327P3V3_AUX         L16   -1          A01X+119011Y+018285X0280Y0320R270 S1      
327P3V3_AUX         U263  -9          A01X+029176Y+015185X0090Y0240R270 S1      
327P3V3_AUX         OSC1  -4          A01X+084174Y+010595X0480Y0590R090 S1      
327P3V3_AUX         U272  -8          A01X+038482Y+165502X0240Y0520     S1      
327P3V3_AUX         U6001 -56         A01X+051612Y+013001X0070Y0520R180 S1      
327P3V3_AUX         U6001 -28         A01X+051927Y+016033X0070Y0520R180 S1      
327P3V3_AUX         U6001 -61         A01X+052399Y+013001X0070Y0520R180 S1      
327P3V3_AUX         U6001 -66         A01X+053187Y+013001X0070Y0520R180 S1      
327P3V3_AUX         U6003 -8          A01X+045099Y+026377X0350Y0500R270 S1      
317P3V3_AUX         VIA   -    MD0100PA00X+075816Y+149079X0200Y    R090 S0      
327P3V3_AUX         PJ38  -12         A01X+076291Y+149079X0240Y0650R090 S1      
317P3V3_AUX         VIA   -    MD0100PA00X+090703Y+145723X0200Y         S0      
317P3V3_AUX         VIA   -    MD0100PA00X+027842Y+023092X0200Y         S0      
327P3V3_AUX         U37   -5          A01X+027850Y+022556X0400Y0150     S1      
327P3V3_AUX         C1062 -1   M      A01X+027550Y+023092X0198Y0197R090 S1      
327P3V3_AUX         R4092 -1          A01X+026698Y+014289X0198Y0197     S1      
317P3V3_AUX         VIA   -    MD0100PA00X+026697Y+014011X0200Y         S0      
317P3V3_AUX         VIA   -    MD0100PA00X+024482Y+011555X0200Y         S0      
317P3V3_AUX         VIA   -    MD0100PA00X+024482Y+011155X0200Y         S0      
327P3V3_AUX         PR3851-2          A01X+024722Y+011574X0198Y0197R180 S1      
327P3V3_AUX         R3848 -1          A01X+024722Y+011174X0198Y0197     S1      
317P3V3_AUX         VIA   -    MD0100PA00X+073808Y+171808X0200Y    R180 S0      
317P3V3_AUX         VIA   -    MD0100PA00X+074102Y+171820X0200Y    R180 S0      
317P3V3_AUX         VIA   -    MD0100PA00X+073811Y+172116X0200Y    R180 S0      
317P3V3_AUX         VIA   -    MD0100PA00X+074116Y+172115X0200Y    R180 S0      
317P3V3_AUX         VIA   -    MD0100PA00X+074103Y+172690X0200Y    R180 S0      
317P3V3_AUX         VIA   -    MD0100PA00X+073803Y+172690X0200Y    R180 S0      
317P3V3_AUX         VIA   -    MD0100PA00X+074103Y+172390X0200Y    R180 S0      
317P3V3_AUX         VIA   -    MD0100PA00X+073803Y+172390X0200Y    R180 S0      
317P3V3_AUX         VIA   -    MD0100PA00X+108097Y+169132X0200Y         S0      
317P3V3_AUX         VIA   -    MD0100PA00X+107802Y+169121X0200Y         S0      
317P3V3_AUX         VIA   -    MD0100PA00X+108093Y+168824X0200Y         S0      
317P3V3_AUX         VIA   -    MD0100PA00X+107788Y+168825X0200Y         S0      
317P3V3_AUX         VIA   -    MD0100PA00X+107801Y+168250X0200Y         S0      
317P3V3_AUX         VIA   -    MD0100PA00X+108101Y+168250X0200Y         S0      
317P3V3_AUX         VIA   -    MD0100PA00X+107801Y+168550X0200Y         S0      
317P3V3_AUX         VIA   -    MD0100PA00X+108101Y+168550X0200Y         S0      
317P3V3_AUX         VIA   -    MD0100PA00X+075484Y+167807X0200Y    R090 S0      
327P3V3_AUX         R2794 -1          A01X+075219Y+167807X0198Y0197R270 S1      
317P3V3_AUX         VIA   -    MD0100PA00X+075219Y+168299X0200Y    R090 S0      
327P3V3_AUX         R2950 -1          A01X+075219Y+168542X0198Y0197R090 S1      
317P3V3_AUX         VIA   -    MD0100PA00X+075803Y+166858X0200Y    R270 S0      
327P3V3_AUX         R2946 -1          A01X+075803Y+166616X0198Y0197R270 S1      
317P3V3_AUX         VIA   -    MD0100PA00X+074508Y+166568X0200Y         S0      
327P3V3_AUX         R8107 -1          A18X+074508Y+166300X0198Y0197     S2      
317P3V3_AUX         VIA   -    MD0100PA00X+071377Y+165493X0200Y         S0      
327P3V3_AUX         R9020 -1          A18X+071377Y+165739X0198Y0197R270 S2      
327P3V3_AUX         R9008 -1          A01X+070569Y+165052X0198Y0197R270 S1      
327P3V3_AUX         R9006 -1   M      A01X+067772Y+164390X0198Y0197     S1      
327P3V3_AUX         R9009 -1          A01X+067772Y+163970X0198Y0197     S1      
317P3V3_AUX         VIA   -    MD0100PA00X+067491Y+164448X0200Y         S0      
317P3V3_AUX         VIA   -    MD0100PA00X+066006Y+164889X0200Y         S0      
327P3V3_AUX         R4128 -1          A18X+066054Y+164552X0198Y0197     S2      
317P3V3_AUX         VIA   -    MD0100PA00X+067941Y+165325X0200Y         S0      
327P3V3_AUX         R2807 -1          A18X+067682Y+165042X0198Y0197R180 S2      
327P3V3_AUX         C1751 -1   M      A18X+068608Y+165450X0198Y0197     S2      
317P3V3_AUX         VIA   -    MD0100PA00X+068608Y+165708X0200Y         S0      
327P3V3_AUX         U192  -8          A18X+069319Y+165109X0140Y0560R090 S2      
327P3V3_AUX         R6239 -1          A18X+068940Y+165833X0198Y0197R180 S2      
317P3V3_AUX         VIA   -    MD0100PA00X+067355Y+166955X0200Y         S0      
327P3V3_AUX         U41   -10         A18X+066648Y+166975X0130Y0250R270 S2      
327P3V3_AUX         C1066 -1   M      A18X+067096Y+166955X0120Y0150R090 S2      
317P3V3_AUX         VIA   -    MD0100PA00X+070310Y+166555X0200Y         S0      
327P3V3_AUX         C1713 -1          A01X+070662Y+166615X0198Y0197R270 S1      
327P3V3_AUX         U181  -24         A01X+071127Y+166636X0240Y0540     S1      
327P3V3_AUX         R6236 -1          A18X+067550Y+168474X0198Y0197R180 S2      
317P3V3_AUX         VIA   -    MD0100PA00X+067550Y+168725X0200Y         S0      
317P3V3_AUX         VIA   -    MD0100PA00X+069156Y+168205X0200Y    R090 S0      
327P3V3_AUX         R2695 -1          A01X+069676Y+167847X0198Y0197     S1      
327P3V3_AUX         R4129 -1          A18X+064326Y+171784X0198Y0197R090 S2      
327P3V3_AUX         R3429 -1          A01X+064182Y+172214X0198Y0197     S1      
327P3V3_AUX         R3438 -1          A01X+064182Y+171714X0198Y0197     S1      
317P3V3_AUX         VIA   -    MD0100PA00X+064086Y+171968X0200Y         S0      
327P3V3_AUX         R2920 -1          A01X+064182Y+172800X0198Y0197     S1      
317P3V3_AUX         VIA   -    MD0100PA00X+064182Y+173052X0200Y         S0      
327P3V3_AUX         R2830 -1          A01X+064182Y+173300X0198Y0197     S1      
327P3V3_AUX         U175  -8          A01X+063888Y+170973X0140Y0560     S1      
317P3V3_AUX         VIA   -    MD0100PA00X+063521Y+171840X0200Y         S0      
327P3V3_AUX         C1707 -1   M      A01X+063779Y+171840X0198Y0197R090 S1      
317P3V3_AUX         VIA   -    MD0100PA00X+064069Y+170355X0200Y         S0      
327P3V3_AUX         R4130 -1   M      A18X+064326Y+170384X0198Y0197R090 S2      
327P3V3_AUX         R4121 -1          A18X+064326Y+170770X0198Y0197R270 S2      
327P3V3_AUX         R4123 -1          A18X+064726Y+169370X0198Y0197R270 S2      
317P3V3_AUX         VIA   -    MD0100PA00X+064946Y+169118X0200Y         S0      
327P3V3_AUX         R2667 -1          A01X+065680Y+169122X0198Y0197R090 S1      
317P3V3_AUX         VIA   -    MD0100PA00X+065849Y+168896X0200Y         S0      
327P3V3_AUX         R8111 -1          A18X+069239Y+168474X0198Y0197     S2      
317P3V3_AUX         VIA   -    MD0100PA00X+069239Y+168759X0200Y         S0      
327P3V3_AUX         R3433 -1          A01X+067311Y+171902X0198Y0197R090 S1      
317P3V3_AUX         VIA   -    MD0100PA00X+067311Y+171660X0200Y    R090 S0      
327P3V3_AUX         R4127 -1          A18X+067138Y+170016X0198Y0197     S2      
317P3V3_AUX         VIA   -    MD0100PA00X+067180Y+170454X0200Y         S0      
327P3V3_AUX         R2835 -1          A01X+067311Y+172969X0198Y0197R090 S1      
317P3V3_AUX         VIA   -    MD0100PA00X+067311Y+172726X0200Y         S0      
327P3V3_AUX         R2669 -1          A01X+066558Y+171208X0198Y0197R180 S1      
327P3V3_AUX         R4126 -1          A18X+066806Y+171753X0198Y0197R090 S2      
317P3V3_AUX         VIA   -    MD0100PA00X+066806Y+172009X0200Y         S0      
317P3V3_AUX         VIA   -    MD0100PA00X+064763Y+164152X0200Y         S0      
327P3V3_AUX         R4119 -1          A18X+065039Y+164152X0198Y0197R180 S2      
317P3V3_AUX         VIA   -    MD0100PA00X+064024Y+163995X0200Y         S0      
327P3V3_AUX         U43   -10         A18X+063033Y+164041X0130Y0250R180 S2      
327P3V3_AUX         C1068 -1   M      A18X+063070Y+163595X0120Y0150     S2      
327P3V3_AUX         R2820 -1          A18X+071332Y+162736X0198Y0197R090 S2      
327P3V3_AUX         R2911 -1          A18X+071332Y+163471X0198Y0197R270 S2      
317P3V3_AUX         VIA   -    MD0100PA00X+071130Y+163253X0200Y         S0      
327P3V3_AUX         U195  -5          A18X+069836Y+163164X0160Y0200R270 S2      
317P3V3_AUX         VIA   -    MD0100PA00X+070268Y+163372X0200Y         S0      
327P3V3_AUX         C1769 -1   M      A18X+070268Y+163104X0198Y0197R180 S2      
317P3V3_AUX         VIA   -    MD0100PA00X+069345Y+162873X0200Y         S0      
327P3V3_AUX         R2693 -1          A01X+069980Y+162762X0198Y0197R090 S1      
327P3V3_AUX         R2923 -1   M      A01X+069603Y+162770X0198Y0197R090 S1      
327P3V3_AUX         R2909 -1          A18X+067739Y+163704X0198Y0197R180 S2      
327P3V3_AUX         R2815 -1   M      A18X+067739Y+163304X0198Y0197R180 S2      
317P3V3_AUX         VIA   -    MD0100PA00X+067396Y+163304X0200Y         S0      
317P3V3_AUX         VIA   -    MD0100PA00X+075152Y+165601X0200Y    R180 S0      
327P3V3_AUX         U278  -5          A01X+075403Y+165101X0220Y0320     S1      
327P3V3_AUX         C1775 -1   M      A01X+075403Y+165601X0198Y0197R090 S1      
327P3V3_AUX         R2805 -1          A18X+072867Y+164800X0198Y0197     S2      
317P3V3_AUX         VIA   -    MD0100PA00X+073112Y+164800X0200Y         S0      
317P3V3_AUX         VIA   -    MD0100PA00X+075526Y+162821X0200Y    R270 S0      
327P3V3_AUX         R2940 -1          A01X+075777Y+162821X0198Y0197R090 S1      
327P3V3_AUX         R2921 -1          A01X+071915Y+163066X0198Y0197R270 S1      
317P3V3_AUX         VIA   -    MD0100PA00X+072210Y+162625X0200Y         S0      
317P3V3_AUX         VIA   -    MD0100PA00X+071780Y+160734X0200Y         S0      
327P3V3_AUX         R3925 -2          A01X+071711Y+160260X0198Y0197R090 S1      
317P3V3_AUX         VIA   -    MD0100PA00X+178234Y+145319X0200Y    R180 S0      
317P3V3_AUX         VIA   -    MD0100PA00X+178541Y+145338X0200Y    R180 S0      
317P3V3_AUX         VIA   -    MD0100PA00X+178253Y+145623X0200Y    R180 S0      
317P3V3_AUX         VIA   -    MD0100PA00X+178563Y+145633X0200Y    R180 S0      
317P3V3_AUX         VIA   -    MD0100PA00X+086306Y+094144X0200Y    R180 S0      
317P3V3_AUX         VIA   -    MD0100PA00X+086600Y+094155X0200Y    R180 S0      
317P3V3_AUX         VIA   -    MD0100PA00X+086309Y+094452X0200Y    R180 S0      
317P3V3_AUX         VIA   -    MD0100PA00X+086614Y+094451X0200Y    R180 S0      
317P3V3_AUX         VIA   -    MD0100PA00X+086601Y+095026X0200Y    R180 S0      
317P3V3_AUX         VIA   -    MD0100PA00X+086301Y+095026X0200Y    R180 S0      
317P3V3_AUX         VIA   -    MD0100PA00X+086601Y+094726X0200Y    R180 S0      
317P3V3_AUX         VIA   -    MD0100PA00X+086301Y+094726X0200Y    R180 S0      
317P3V3_AUX         VIA   -    MD0100PA00X+082400Y+093032X0200Y    R180 S0      
317P3V3_AUX         VIA   -    MD0100PA00X+082695Y+093043X0200Y    R180 S0      
317P3V3_AUX         VIA   -    MD0100PA00X+082404Y+093339X0200Y    R180 S0      
317P3V3_AUX         VIA   -    MD0100PA00X+082709Y+093339X0200Y    R180 S0      
317P3V3_AUX         VIA   -    MD0100PA00X+082696Y+093914X0200Y    R180 S0      
317P3V3_AUX         VIA   -    MD0100PA00X+082396Y+093914X0200Y    R180 S0      
317P3V3_AUX         VIA   -    MD0100PA00X+082696Y+093614X0200Y    R180 S0      
317P3V3_AUX         VIA   -    MD0100PA00X+082396Y+093614X0200Y    R180 S0      
327P3V3_AUX         R1341 -1          A01X+107787Y+046700X0198Y0197R180 S1      
327P3V3_AUX         R9000 -1          A18X+095180Y+165514X0198Y0197R270 S2      
317P3V3_AUX         VIA   -    MD0100PA00X+094920Y+165514X0200Y         S0      
317P3V3_AUX         VIA   -    MD0100PA00X+111692Y+151264X0200Y    R180 S0      
317P3V3_AUX         VIA   -    MD0100PA00X+111991Y+151264X0200Y    R180 S0      
317P3V3_AUX         VIA   -    MD0100PA00X+111991Y+150694X0200Y    R180 S0      
317P3V3_AUX         VIA   -    MD0100PA00X+111692Y+151564X0200Y    R180 S0      
317P3V3_AUX         VIA   -    MD0100PA00X+111991Y+151564X0200Y    R180 S0      
317P3V3_AUX         VIA   -    MD0100PA00X+111991Y+150989X0200Y    R180 S0      
317P3V3_AUX         VIA   -    MD0100PA00X+111692Y+150990X0200Y    R180 S0      
317P3V3_AUX         VIA   -    MD0100PA00X+111692Y+150682X0200Y    R180 S0      
327P3V3_AUX         PR443 -2          A01X+106636Y+138562X0198Y0197R090 S1      
317P3V3_AUX         VIA   -    MD0100PA00X+108100Y+142546X0200Y         S0      
327P3V3_AUX         R200  -1          A18X+096350Y+085742X0198Y0197R270 S2      
317P3V3_AUX         VIA   -    MD0100PA00X+096350Y+085472X0200Y         S0      
317P3V3_AUX         VIA   -    MD0100PA00X+094950Y+087050X0200Y         S0      
327P3V3_AUX         U5    -1          A18X+093579Y+088692X0240Y0460     S2      
317P3V3_AUX         VIA   -    MD0100PA00X+092960Y+087900X0200Y         S0      
327P3V3_AUX         R201  -1          A18X+090384Y+089978X0198Y0197R090 S2      
317P3V3_AUX         VIA   -    MD0100PA00X+090700Y+089978X0200Y    R180 S0      
327P3V3_AUX         C2    -1   M      A18X+091738Y+088188X0198Y0197R270 S2      
327P3V3_AUX         U2    -8          A18X+091221Y+088668X0240Y0460R180 S2      
317P3V3_AUX         VIA   -    MD0100PA00X+092090Y+088188X0200Y         S0      
327P3V3_AUX         C23   -1   M      A18X+092960Y+088235X0198Y0197R270 S2      
327P3V3_AUX         U96   -8          A18X+095487Y+086994X0240Y0460     S2      
327P3V3_AUX         C611  -1   M      A18X+094950Y+087342X0198Y0197R270 S2      
317P3V3_AUX         VIA   -    MD0100PA00X+094850Y+093700X0200Y         S0      
327P3V3_AUX         U6    -10         A18X+094295Y+093398X0130Y0250R270 S2      
327P3V3_AUX         C25   -1   M      A18X+094850Y+093408X0198Y0197R090 S2      
327P3V3_AUX         C11   -1   M      A18X+091676Y+098678X0198Y0197R270 S2      
327P3V3_AUX         U4    -10         A18X+091676Y+098178X0130Y0250     S2      
317P3V3_AUX         VIA   -    MD0100PA00X+091927Y+098678X0200Y    R090 S0      
327P3V3_AUX         R644  -1          A18X+088963Y+114506X0198Y0197R180 S2      
317P3V3_AUX         VIA   -    MD0100PA00X+089200Y+114971X0200Y         S0      
327P3V3_AUX         PR6521-1          A18X+090549Y+113832X0198Y0197R270 S2      
317P3V3_AUX         VIA   -    MD0100PA00X+090238Y+113756X0200Y         S0      
317P3V3_AUX         VIA   -    MD0100PA00X+093323Y+114506X0200Y         S0      
327P3V3_AUX         R6505 -1          A18X+093666Y+114506X0198Y0197R180 S2      
327P3V3_AUX         PR6501-1          A18X+095251Y+113832X0198Y0197R270 S2      
317P3V3_AUX         VIA   -    MD0100PA00X+094941Y+113756X0200Y         S0      
317P3V3_AUX         VIA   -    MD0100PA00X+094673Y+129072X0200Y         S0      
327P3V3_AUX         L24   -2          A18X+095010Y+129200X0280Y0320R090 S2      
317P3V3_AUX         VIA   -    MD0100PA00X+094673Y+129322X0200Y         S0      
327P3V3_AUX         PQ10  -S          A01X+116016Y+144126X0320Y0360R270 S1      
317P3V3_AUX         VIA   -    MD0100PA00X+116016Y+144563X0200Y         S0      
327P3V3_AUX         PR55  -1          A01X+116335Y+145423X0198Y0197R180 S1      
317P3V3_AUX         VIA   -    MD0100PA00X+116635Y+145423X0200Y         S0      
327P3V3_AUX         R8056 -1          A01X+118802Y+142850X0198Y0197     S1      
317P3V3_AUX         VIA   -    MD0100PA00X+118490Y+142850X0200Y         S0      
327P3V3_AUX         R8065 -1          A18X+119692Y+141450X0198Y0197R180 S2      
317P3V3_AUX         VIA   -    MD0100PA00X+119400Y+141450X0200Y         S0      
327P3V3_AUX         R6230 -1          A01X+110875Y+152880X0198Y0197R090 S1      
317P3V3_AUX         VIA   -    MD0100PA00X+110670Y+152659X0200Y         S0      
317P3V3_AUX         VIA   -    MD0100PA00X+111462Y+152632X0200Y    R090 S0      
327P3V3_AUX         R6231 -1          A01X+111462Y+152880X0198Y0197R090 S1      
327P3V3_AUX         R355  -1          A01X+110956Y+154451X0198Y0197R090 S1      
317P3V3_AUX         VIA   -    MD0100PA00X+111389Y+154345X0200Y    R270 S0      
317P3V3_AUX         VIA   -    MD0100PA00X+113503Y+155611X0200Y         S0      
327P3V3_AUX         U48   -10         A01X+114193Y+155603X0130Y0250R090 S1      
327P3V3_AUX         C1072 -1   M      A01X+113732Y+155611X0120Y0150R270 S1      
317P3V3_AUX         VIA   -    MD0100PA00X+113376Y+156895X0200Y    R090 S0      
327P3V3_AUX         U143  -1          A01X+112674Y+156524X0170Y0590R180 S1      
327P3V3_AUX         C1787 -1   M      A01X+113126Y+156895X0198Y0197R090 S1      
327P3V3_AUX         R354  -1          A01X+111503Y+159633X0198Y0197R270 S1      
317P3V3_AUX         VIA   -    MD0100PA00X+111503Y+159879X0200Y         S0      
327P3V3_AUX         R4139 -1          A01X+120512Y+167306X0198Y0197     S1      
317P3V3_AUX         VIA   -    MD0100PA00X+120270Y+167306X0200Y    R270 S0      
327P3V3_AUX         R4137 -1          A01X+118978Y+167305X0198Y0197     S1      
317P3V3_AUX         VIA   -    MD0100PA00X+119062Y+167064X0200Y    R270 S0      
327P3V3_AUX         R2670 -1          A18X+112600Y+167542X0198Y0197R270 S2      
317P3V3_AUX         VIA   -    MD0100PA00X+112600Y+167242X0200Y         S0      
327P3V3_AUX         U176  -8          A01X+114647Y+168241X0140Y0560R270 S1      
327P3V3_AUX         C1708 -1          A18X+113954Y+168252X0198Y0197     S2      
317P3V3_AUX         VIA   -    MD0100PA00X+114203Y+168241X0200Y         S0      
327P3V3_AUX         R2668 -1          A18X+115200Y+167592X0198Y0197R270 S2      
317P3V3_AUX         VIA   -    MD0100PA00X+115450Y+167700X0200Y         S0      
317P3V3_AUX         VIA   -    MD0100PA00X+117573Y+168673X0200Y         S0      
327P3V3_AUX         U49   -10         A18X+117545Y+167767X0130Y0250     S2      
327P3V3_AUX         C1073 -1   M      A18X+117573Y+168213X0120Y0150R180 S2      
327P3V3_AUX         C69   -1   M      A01X+109549Y+169918X0198Y0197R270 S1      
327P3V3_AUX         U308  -5          A01X+109549Y+170376X0170Y0240R180 S1      
317P3V3_AUX         VIA   -    MD0100PA00X+109298Y+169918X0200Y    R180 S0      
327P3V3_AUX         R4264 -1          A01X+110264Y+169603X0198Y0197R180 S1      
317P3V3_AUX         VIA   -    MD0100PA00X+110515Y+169603X0200Y         S0      
317P3V3_AUX         VIA   -    MD0100PA00X+119448Y+169994X0200Y         S0      
327P3V3_AUX         R4140 -1          A01X+118946Y+169785X0198Y0197     S1      
317P3V3_AUX         VIA   -    MD0100PA00X+118946Y+170033X0200Y    R180 S0      
327P3V3_AUX         R4131 -1          A01X+119961Y+169385X0198Y0197R180 S1      
317P3V3_AUX         VIA   -    MD0100PA00X+119961Y+169137X0200Y         S0      
327P3V3_AUX         R4142 -1          A01X+120480Y+169786X0198Y0197     S1      
317P3V3_AUX         VIA   -    MD0100PA00X+120480Y+170034X0200Y    R180 S0      
317P3V3_AUX         VIA   -    MD0100PA00X+121495Y+169138X0200Y         S0      
327P3V3_AUX         R4135 -1          A01X+121495Y+169386X0198Y0197R180 S1      
317P3V3_AUX         VIA   -    MD0100PA00X+110100Y+171584X0200Y    R090 S0      
327P3V3_AUX         R4554 -1          A01X+109851Y+171584X0198Y0197R090 S1      
317P3V3_AUX         VIA   -    MD0100PA00X+111936Y+171373X0200Y         S0      
327P3V3_AUX         R4553 -1          A01X+111936Y+171616X0198Y0197R090 S1      
327P3V3_AUX         R3464 -1          A01X+121025Y+170686X0198Y0197R090 S1      
317P3V3_AUX         VIA   -    MD0100PA00X+120777Y+170686X0200Y    R270 S0      
327P3V3_AUX         R3437 -1          A01X+121425Y+171701X0198Y0197R270 S1      
317P3V3_AUX         VIA   -    MD0100PA00X+121674Y+171701X0200Y    R090 S0      
317P3V3_AUX         VIA   -    MD0100PA00X+110100Y+172599X0200Y    R090 S0      
327P3V3_AUX         R4551 -1          A01X+109851Y+172599X0198Y0197R270 S1      
327P3V3_AUX         R3435 -1          A01X+118941Y+171509X0198Y0197R270 S1      
317P3V3_AUX         VIA   -    MD0100PA00X+118941Y+171752X0200Y    R180 S0      
317P3V3_AUX         VIA   -    MD0100PA00X+120777Y+172086X0200Y    R270 S0      
327P3V3_AUX         R4133 -1          A01X+121025Y+172086X0198Y0197R090 S1      
317P3V3_AUX         VIA   -    MD0100PA00X+121674Y+173101X0200Y    R090 S0      
327P3V3_AUX         R4141 -1          A01X+121425Y+173101X0198Y0197R270 S1      
317P3V3_AUX         VIA   -    MD0100PA00X+120564Y+173277X0200Y    R090 S0      
327P3V3_AUX         R4138 -1          A01X+120305Y+173180X0198Y0197R180 S1      
317P3V3_AUX         VIA   -    MD0100PA00X+111250Y+167111X0200Y    R270 S0      
317P3V3_AUX         VIA   -    MD0100PA00X+110900Y+167111X0200Y    R270 S0      
317P3V3_AUX         VIA   -    MD0100PA00X+109650Y+163900X0200Y         S0      
327P3V3_AUX         R4491 -1          A01X+111250Y+166858X0198Y0197R270 S1      
327P3V3_AUX         R4476 -1          A01X+110900Y+166858X0198Y0197R270 S1      
327P3V3_AUX         R4489 -1          A01X+109892Y+163900X0198Y0197     S1      
327P3V3_AUX         L19   -1          A01X+111000Y+169674X0440Y0540R090 S1      
317P3V3_AUX         VIA   -    MD0100PA00X+111439Y+169594X0200Y         S0      
317P3V3_AUX         VIA   -    MD0100PA00X+111441Y+169886X0200Y         S0      
327P3V3_AUX         PR76  -2          A01X+125300Y+143708X0198Y0197R090 S1      
317P3V3_AUX         VIA   -    MD0100PA00X+125660Y+143450X0200Y         S0      
327P3V3_AUX         L20   -1          A01X+110889Y+162009X0440Y0540R270 S1      
317P3V3_AUX         VIA   -    MD0100PA00X+110981Y+161592X0200Y         S0      
317P3V3_AUX         VIA   -    MD0100PA00X+110718Y+161592X0200Y         S0      
327P3V3_AUX         J1    -3          A01X+121011Y+076352X0205Y0590R090 S1      
327P3V3_AUX         C88   -1          A18X+121158Y+076376X0198Y0197     S2      
317P3V3_AUX         VIA   -    MD0100PA00X+121461Y+076352X0190Y         S0      
317P3V3_AUX         VIA   -    MD0100PA00X+126246Y+079881X0200Y    R180 S0      
327P3V3_AUX         R396  -1          A18X+127318Y+080125X0198Y0197R270 S2      
327P3V3_AUX         R387  -1          A18X+126418Y+080125X0198Y0197R270 S2      
317P3V3_AUX         VIA   -    MD0100PA00X+125645Y+079883X0200Y    R180 S0      
327P3V3_AUX         R390  -1          A18X+125318Y+080125X0198Y0197R270 S2      
327P3V3_AUX         R388  -1   M      A18X+125718Y+080125X0198Y0197R270 S2      
327P3V3_AUX         J15   -3          A01X+118041Y+076352X0205Y0590R090 S1      
327P3V3_AUX         C92   -1          A18X+117901Y+076376X0198Y0197     S2      
317P3V3_AUX         VIA   -    MD0100PA00X+118491Y+076352X0190Y         S0      
327P3V3_AUX         J17   -3          A01X+115071Y+076352X0205Y0590R090 S1      
327P3V3_AUX         C96   -1          A18X+114931Y+076376X0198Y0197     S2      
317P3V3_AUX         VIA   -    MD0100PA00X+115521Y+076352X0190Y         S0      
327P3V3_AUX         J19   -3          A01X+112101Y+076352X0205Y0590R090 S1      
327P3V3_AUX         C100  -1          A18X+111961Y+076376X0198Y0197     S2      
317P3V3_AUX         VIA   -    MD0100PA00X+112551Y+076352X0190Y         S0      
327P3V3_AUX         J21   -3          A01X+109131Y+076352X0205Y0590R090 S1      
327P3V3_AUX         C104  -1          A18X+108991Y+076376X0198Y0197     S2      
317P3V3_AUX         VIA   -    MD0100PA00X+109581Y+076352X0190Y         S0      
327P3V3_AUX         J23   -3          A01X+106161Y+076352X0205Y0590R090 S1      
327P3V3_AUX         C108  -1          A18X+106021Y+076376X0198Y0197     S2      
317P3V3_AUX         VIA   -    MD0100PA00X+106611Y+076352X0190Y         S0      
317P3V3_AUX         VIA   -    MD0100PA00X+107267Y+042879X0200Y         S0      
327P3V3_AUX         R6070 -1          A01X+107553Y+042754X0198Y0197R270 S1      
327P3V3_AUX         R499  -1          A01X+070406Y+057751X0198Y0197R090 S1      
317P3V3_AUX         VIA   -    MD0100PA00X+070406Y+057508X0200Y         S0      
327P3V3_AUX         R590  -1          A01X+069900Y+057751X0198Y0197R090 S1      
317P3V3_AUX         VIA   -    MD0100PA00X+069900Y+057508X0200Y         S0      
327P3V3_AUX         C1097 -1   M      A01X+156644Y+029732X0198Y0197     S1      
327P3V3_AUX         U55   -9          A01X+156173Y+029746X0090Y0240R270 S1      
327P3V3_AUX         R1327 -1          A01X+154209Y+028882X0198Y0197R180 S1      
327P3V3_AUX         R1320 -1          A01X+153894Y+030882X0198Y0197     S1      
327P3V3_AUX         C1096 -1   M      A01X+129013Y+040362X0198Y0197     S1      
327P3V3_AUX         U52   -9          A01X+128541Y+040377X0090Y0240R270 S1      
327P3V3_AUX         R1326 -1          A01X+126577Y+039512X0198Y0197R180 S1      
327P3V3_AUX         R1317 -1          A01X+126263Y+041512X0198Y0197     S1      
317P3V3_AUX         VIA   -    MD0100PA00X+156644Y+029482X0200Y         S0      
317P3V3_AUX         VIA   -    MD0100PA00X+154449Y+028882X0200Y         S0      
317P3V3_AUX         VIA   -    MD0100PA00X+153654Y+030882X0200Y         S0      
317P3V3_AUX         VIA   -    MD0100PA00X+129013Y+040112X0200Y         S0      
317P3V3_AUX         VIA   -    MD0100PA00X+126817Y+039512X0200Y         S0      
317P3V3_AUX         VIA   -    MD0100PA00X+126023Y+041513X0200Y         S0      
327P3V3_AUX         PR253 -2          A01X+014903Y+145219X0198Y0197R090 S1      
317P3V3_AUX         VIA   -    MD0100PA00X+014834Y+145467X0200Y         S0      
317P3V3_AUX         VIA   -    MD0100PA00X+010196Y+144866X0200Y         S0      
327P3V3_AUX         R8233 -1          A18X+009900Y+144708X0198Y0197R090 S2      
317P3V3_AUX         VIA   -    MD0100PA00X+007906Y+143400X0200Y         S0      
327P3V3_AUX         PR232 -1   M      A01X+007658Y+143400X0198Y0197R180 S1      
327P3V3_AUX         PQ12  -S          A01X+008074Y+143956X0320Y0360     S1      
327P3V3_AUX         R8242 -1          A18X+009592Y+142600X0198Y0197R180 S2      
317P3V3_AUX         VIA   -    MD0100PA00X+009300Y+142600X0200Y         S0      
327P3V3_AUX         R6211 -1          A01X+108336Y+047210X0198Y0197     S1      
327P3V3_AUX         R1316 -1          A01X+107787Y+047150X0198Y0197R180 S1      
317P3V3_AUX         VIA   -    MD0100PA00X+108057Y+047150X0200Y         S0      
317P3V3_AUX         VIA   -    MD0100PA00X+108064Y+046700X0200Y         S0      
327P3V3_AUX         R3731 -1          A01X+106572Y+045796X0198Y0197     S1      
317P3V3_AUX         VIA   -    MD0100PA00X+169502Y+146562X0200Y         S0      
317P3V3_AUX         VIA   -    MD0100PA00X+162528Y+143338X0200Y    R090 S0      
317P3V3_AUX         VIA   -    MD0100PA00X+164109Y+139612X0200Y    R180 S0      
317P3V3_AUX         VIA   -    MD0100PA00X+167015Y+144431X0200Y    R180 S0      
327P3V3_AUX         PR130 -2          A01X+167015Y+144172X0198Y0197R090 S1      
327P3V3_AUX         PR413 -2          A01X+164516Y+139440X0198Y0197R090 S1      
317P3V3_AUX         VIA   -    MD0100PA00X+162717Y+142045X0200Y    R180 S0      
327P3V3_AUX         R8458 -1          A01X+162967Y+142045X0198Y0197     S1      
327P3V3_AUX         R117  -1          A01X+162959Y+144002X0198Y0197     S1      
317P3V3_AUX         VIA   -    MD0100PA00X+156397Y+136320X0200Y         S0      
317P3V3_AUX         VIA   -    MD0100PA00X+155469Y+126969X0200Y    R180 S0      
327P3V3_AUX         R389  -1          A01X+155025Y+127019X0198Y0197R180 S1      
327P3V3_AUX         R8465 -1          A01X+130407Y+053730X0198Y0197     S1      
327P3V3_AUX         PR477 -1          A18X+130409Y+053730X0198Y0197R180 S2      
317P3V3_AUX         VIA   -    MD0100PA00X+130164Y+053730X0200Y    R180 S0      
327P3V3_AUX         PR6551-1          A01X+172620Y+159917X0198Y0197R270 S1      
317P3V3_AUX         VIA   -    MD0100PA00X+171287Y+158662X0200Y         S0      
327P3V3_AUX         R2344 -1          A01X+157007Y+053122X0198Y0197     S1      
317P3V3_AUX         VIA   -    MD0100PA00X+157007Y+053410X0200Y    R180 S0      
327P3V3_AUX         R1338 -1          A01X+059658Y+044950X0198Y0197R180 S1      
317P3V3_AUX         VIA   -    MD0100PA00X+059850Y+045142X0200Y         S0      
327P3V3_AUX         R1128 -1          A01X+061950Y+043892X0198Y0197R090 S1      
317P3V3_AUX         VIA   -    MD0100PA00X+062217Y+043892X0200Y         S0      
327P3V3_AUX         R1131 -1          A01X+061858Y+041800X0198Y0197R180 S1      
317P3V3_AUX         VIA   -    MD0100PA00X+061800Y+041555X0200Y         S0      
317P3V3_AUX         VIA   -    MD0100PA00X+059988Y+041200X0200Y         S0      
317P3V3_AUX         VIA   -    MD0100PA00X+080246Y+038776X0200Y         S0      
327P3V3_AUX         R1133 -1          A01X+080549Y+038102X0198Y0197     S1      
317P3V3_AUX         VIA   -    MD0100PA00X+080266Y+038102X0200Y         S0      
317P3V3_AUX         VIA   -    MD0100PA00X+083858Y+047755X0200Y         S0      
327P3V3_AUX         R9032 -1          A01X+083592Y+039300X0198Y0197     S1      
317P3V3_AUX         VIA   -    MD0100PA00X+083310Y+039300X0200Y         S0      
327P3V3_AUX         R1145 -1          A01X+085158Y+038100X0198Y0197R180 S1      
317P3V3_AUX         VIA   -    MD0100PA00X+085455Y+038100X0200Y         S0      
317P3V3_AUX         VIA   -    MD0100PA00X+085892Y+039854X0200Y         S0      
327P3V3_AUX         R1144 -1          A01X+065242Y+039000X0198Y0197     S1      
317P3V3_AUX         VIA   -    MD0100PA00X+065242Y+038592X0200Y         S0      
327P3V3_AUX         R9024 -1          A01X+065008Y+041850X0198Y0197R180 S1      
327P3V3_AUX         R9026 -1          A01X+063108Y+042700X0198Y0197R180 S1      
327P3V3_AUX         R9027 -1   M      A01X+065008Y+042250X0198Y0197R180 S1      
327P3V3_AUX         R9043 -1          A01X+175038Y+171023X0198Y0197R090 S1      
327P3V3_AUX         R9044 -1          A01X+172463Y+170512X0198Y0197R090 S1      
327P3V3_AUX         R1167 -1          A01X+040458Y+030400X0198Y0197R180 S1      
327P3V3_AUX         R1149 -1          A01X+019392Y+014900X0198Y0197     S1      
327P3V3_AUX         R1165 -1          A01X+019442Y+015650X0198Y0197     S1      
327P3V3_AUX         R1171 -1          A01X+034200Y+028058X0198Y0197R270 S1      
327P3V3_AUX         R577  -1          A01X+182587Y+043168X0198Y0197R180 S1      
327P3V3_AUX         R1192 -1          A01X+006980Y+026822X0198Y0197R180 S1      
327P3V3_AUX         C1065 -1   M      A01X+021792Y+015650X0198Y0197     S1      
327P3V3_AUX         C1061 -1   M      A01X+039142Y+031150X0198Y0197     S1      
327P3V3_AUX         C1063 -1   M      A01X+033892Y+028500X0198Y0197     S1      
317P3V3_AUX         VIA   -    MD0100PA00X+041000Y+030400X0200Y         S0      
317P3V3_AUX         VIA   -    MD0100PA00X+039505Y+031812X0200Y         S0      
317P3V3_AUX         VIA   -    MD0100PA00X+007246Y+026822X0200Y         S0      
317P3V3_AUX         VIA   -    MD0100PA00X+019126Y+014777X0200Y         S0      
317P3V3_AUX         VIA   -    MD0100PA00X+019361Y+015395X0200Y         S0      
317P3V3_AUX         VIA   -    MD0100PA00X+022105Y+015317X0200Y         S0      
317P3V3_AUX         VIA   -    MD0100PA00X+033600Y+028400X0200Y         S0      
317P3V3_AUX         VIA   -    MD0100PA00X+034403Y+028261X0200Y         S0      
317P3V3_AUX         VIA   -    MD0100PA00X+166112Y+169075X0200Y         S0      
317P3V3_AUX         VIA   -    MD0100PA00X+054985Y+040630X0200Y         S0      
317P3V3_AUX         VIA   -    MD0100PA00X+182848Y+043168X0200Y         S0      
317P3V3_AUX         VIA   -    MD0100PA00X+088499Y+019883X0200Y         S0      
327P3V3_AUX         R3771 -1          A18X+092835Y+019761X0198Y0197R180 S2      
327P3V3_AUX         R134  -2          A01X+083698Y+043955X0198Y0197R180 S1      
317P3V3_AUX         VIA   -    MD0100PA00X+063108Y+042989X0200Y         S0      
317P3V3_AUX         VIA   -    MD0100PA00X+065425Y+042250X0200Y         S0      
317P3V3_AUX         VIA   -    M      A01X+174712Y+171082X0200Y         S2      
017P3V3_AUX         VIA   -    M      A18X+174712Y+171082X0260Y         S2      
017P3V3_AUX               -    MD0100PA00X+174712Y+171082                       
317P3V3_AUX         VIA   -    MD0100PA00X+175038Y+170747X0200Y         S0      
327P3V3_AUX         C8013 -1   M      A18X+079150Y+054458X0198Y0197R090 S2      
327P3V3_AUX         R8037 -1          A01X+083008Y+040950X0198Y0197R180 S1      
327P3V3_AUX         R8082 -1          A01X+078942Y+040750X0198Y0197     S1      
327P3V3_AUX         R8038 -1          A01X+081558Y+039250X0198Y0197R180 S1      
327P3V3_AUX         R8085 -1          A01X+079842Y+039250X0198Y0197     S1      
327P3V3_AUX         R8039 -1   M      A01X+056992Y+047550X0198Y0197     S1      
327P3V3_AUX         R8088 -1   M      A01X+057692Y+047950X0198Y0197     S1      
327P3V3_AUX         R8040 -1          A01X+077192Y+036400X0198Y0197     S1      
327P3V3_AUX         R8091 -1          A01X+077892Y+037100X0198Y0197     S1      
327P3V3_AUX         R8017 -1          A01X+169300Y+023158X0198Y0197R270 S1      
327P3V3_AUX         R8019 -1          A01X+166200Y+021792X0198Y0197R090 S1      
327P3V3_AUX         R552  -1          A01X+063424Y+051061X0198Y0197R270 S1      
327P3V3_AUX         R492  -1          A01X+065600Y+052108X0198Y0197R270 S1      
327P3V3_AUX         R8103 -1          A18X+078100Y+056642X0198Y0197R270 S2      
327P3V3_AUX         R8106 -1          A18X+078550Y+052942X0198Y0197R270 S2      
327P3V3_AUX         R8113 -1          A01X+050150Y+041942X0198Y0197R090 S1      
327P3V3_AUX         R8119 -1          A01X+059063Y+045424X0198Y0197     S1      
327P3V3_AUX         R8120 -1          A01X+055042Y+045100X0198Y0197     S1      
327P3V3_AUX         R8125 -1          A01X+056992Y+047150X0198Y0197     S1      
327P3V3_AUX         R8029 -2          A01X+076100Y+021558X0198Y0197R090 S1      
327P3V3_AUX         R8028 -1   M      A01X+075763Y+022820X0198Y0197R180 S1      
327P3V3_AUX         R652  -1          A01X+177104Y+165746X0198Y0197R180 S1      
327P3V3_AUX         PR6817-1          A01X+172689Y+165896X0198Y0197     S1      
327P3V3_AUX         PR6805-1   M      A01X+172689Y+166796X0198Y0197     S1      
327P3V3_AUX         PR6803-1   M      A01X+172689Y+166346X0198Y0197     S1      
327P3V3_AUX         PR6615-1          A18X+172743Y+167238X0198Y0197R270 S2      
327P3V3_AUX         R655  -1   M      A01X+172689Y+167246X0198Y0197     S1      
327P3V3_AUX         R643  -1          A18X+172685Y+168146X0198Y0197R180 S2      
327P3V3_AUX         PR6608-2          A01X+177104Y+168996X0198Y0197     S1      
327P3V3_AUX         R649  -1          A01X+173546Y+169204X0198Y0197R270 S1      
327P3V3_AUX         R4166 -1          A18X+171023Y+172642X0198Y0197R090 S2      
317P3V3_AUX         VIA   -    MD0100PA00X+171023Y+172965X0200Y         S0      
327P3V3_AUX         R4169 -1          A18X+168538Y+172674X0198Y0197R090 S2      
317P3V3_AUX         VIA   -    MD0100PA00X+168538Y+172956X0200Y         S0      
327P3V3_AUX         R4162 -1          A18X+168938Y+171659X0198Y0197R270 S2      
317P3V3_AUX         VIA   -    MD0100PA00X+173546Y+169446X0200Y    R270 S0      
317P3V3_AUX         VIA   -    MD0100PA00X+177104Y+169296X0200Y    R270 S0      
317P3V3_AUX         VIA   -    MD0100PA00X+177393Y+165496X0200Y    R270 S0      
317P3V3_AUX         VIA   -    MD0100PA00X+177393Y+165746X0200Y    R270 S0      
317P3V3_AUX         VIA   -    MD0100PA00X+172426Y+167246X0200Y    R270 S0      
327P3V3_AUX         U6005 -9          A01X+169203Y+169176X0090Y0240     S1      
327P3V3_AUX         C6087 -1   M      A01X+169195Y+169642X0198Y0197     S1      
317P3V3_AUX         VIA   -    MD0100PA00X+169195Y+169895X0200Y    R090 S0      
327P3V3_AUX         R6247 -1          A01X+169242Y+166616X0198Y0197R090 S1      
317P3V3_AUX         VIA   -    MD0100PA00X+169242Y+166374X0200Y    R270 S0      
317P3V3_AUX         VIA   -    MD0100PA00X+160499Y+053634X0200Y    R180 S0      
327P3V3_AUX         R2346 -1          A01X+160187Y+053634X0198Y0197R180 S1      
327P3V3_AUX         J24   -3          A01X+023397Y+076352X0205Y0590R090 S1      
327P3V3_AUX         C136  -1          A18X+023544Y+076377X0198Y0197     S2      
317P3V3_AUX         VIA   -    MD0100PA00X+027205Y+080111X0200Y    R180 S0      
327P3V3_AUX         R512  -1          A18X+026897Y+079961X0198Y0197R270 S2      
327P3V3_AUX         R517  -1          A18X+027470Y+080189X0198Y0197R180 S2      
317P3V3_AUX         VIA   -    MD0100PA00X+024637Y+077239X0200Y    R180 S0      
327P3V3_AUX         R514  -1   M      A18X+024890Y+077239X0198Y0197R180 S2      
327P3V3_AUX         R516  -1          A18X+024890Y+077639X0198Y0197R180 S2      
317P3V3_AUX         VIA   -    MD0100PA00X+023847Y+076352X0190Y         S0      
327P3V3_AUX         J26   -3          A01X+020427Y+076352X0205Y0590R090 S1      
327P3V3_AUX         C140  -1          A18X+020284Y+076377X0198Y0197     S2      
317P3V3_AUX         VIA   -    MD0100PA00X+020877Y+076352X0190Y         S0      
327P3V3_AUX         J28   -3          A01X+017457Y+076352X0205Y0590R090 S1      
327P3V3_AUX         C144  -1          A18X+017314Y+076367X0198Y0197     S2      
317P3V3_AUX         VIA   -    MD0100PA00X+017907Y+076352X0190Y         S0      
327P3V3_AUX         J30   -3          A01X+014487Y+076352X0205Y0590R090 S1      
327P3V3_AUX         C148  -1          A18X+014347Y+076370X0198Y0197     S2      
317P3V3_AUX         VIA   -    MD0100PA00X+014937Y+076352X0190Y         S0      
327P3V3_AUX         J32   -3          A01X+011517Y+076352X0205Y0590R090 S1      
327P3V3_AUX         C152  -1          A18X+011364Y+076377X0198Y0197     S2      
317P3V3_AUX         VIA   -    MD0100PA00X+011967Y+076352X0190Y         S0      
327P3V3_AUX         J33   -3          A01X+008546Y+076352X0205Y0590R090 S1      
327P3V3_AUX         C156  -1          A18X+008393Y+076377X0198Y0197     S2      
317P3V3_AUX         VIA   -    MD0100PA00X+008996Y+076352X0190Y         S0      
317P3V3_AUX         VIA   -    MD0100PA00X+015282Y+066550X0200Y         S0      
327P3V3_AUX         U107  -10         A01X+015270Y+067378X0130Y0250R180 S1      
327P3V3_AUX         C1338 -1   M      A01X+015282Y+066836X0198Y0197R180 S1      
317P3V3_AUX         VIA   -    MD0100PA00X+040366Y+054692X0200Y    R180 S0      
327P3V3_AUX         PR183 -2          A18X+040366Y+054934X0198Y0197R090 S2      
327P3V3_AUX         C1827 -1   M      A18X+076061Y+028663X0198Y0197     S2      
327P3V3_AUX         U223  -14         A18X+076990Y+028682X0140Y0590R090 S2      
317P3V3_AUX         VIA   -    MD0100PA00X+076061Y+028410X0200Y         S0      
327P3V3_AUX         R4160 -1          A01X+172863Y+173042X0198Y0197R270 S1      
317P3V3_AUX         VIA   -    MD0100PA00X+173112Y+173042X0200Y    R090 S0      
327P3V3_AUX         R2828 -1          A01X+165451Y+173391X0198Y0197R270 S1      
317P3V3_AUX         VIA   -    MD0100PA00X+165700Y+173391X0200Y    R090 S0      
327P3V3_AUX         R4165 -1          A01X+174948Y+172058X0198Y0197R090 S1      
317P3V3_AUX         VIA   -    MD0100PA00X+174948Y+171816X0200Y         S0      
327P3V3_AUX         R3470 -1          A01X+172863Y+171526X0198Y0197R270 S1      
317P3V3_AUX         VIA   -    MD0100PA00X+173112Y+171526X0200Y    R090 S0      
327P3V3_AUX         R4168 -1          A01X+172463Y+172026X0198Y0197R090 S1      
317P3V3_AUX         VIA   -    MD0100PA00X+172215Y+172026X0200Y    R270 S0      
327P3V3_AUX         R2832 -1          A01X+168951Y+171876X0198Y0197R270 S1      
317P3V3_AUX         VIA   -    MD0100PA00X+169222Y+171754X0200Y    R090 S0      
327P3V3_AUX         R2834 -1          A01X+167536Y+172368X0198Y0197R090 S1      
317P3V3_AUX         VIA   -    MD0100PA00X+167536Y+172125X0200Y         S0      
327P3V3_AUX         R4158 -1          A01X+165451Y+171876X0198Y0197R270 S1      
317P3V3_AUX         VIA   -    MD0100PA00X+165700Y+171876X0200Y    R090 S0      
327P3V3_AUX         R2919 -1          A01X+165051Y+172376X0198Y0197R090 S1      
317P3V3_AUX         VIA   -    MD0100PA00X+164803Y+172376X0200Y    R270 S0      
317P3V3_AUX         VIA   -    MD0100PA00X+172191Y+170512X0200Y    R270 S0      
327P3V3_AUX         R2836 -1          A01X+171036Y+170893X0198Y0197R090 S1      
317P3V3_AUX         VIA   -    MD0100PA00X+171036Y+170650X0200Y         S0      
327P3V3_AUX         R2933 -1          A01X+168551Y+170861X0198Y0197R090 S1      
317P3V3_AUX         VIA   -    MD0100PA00X+168303Y+170861X0200Y    R270 S0      
327P3V3_AUX         R4164 -1          A01X+167536Y+170893X0198Y0197R090 S1      
317P3V3_AUX         VIA   -    MD0100PA00X+167250Y+170893X0200Y         S0      
327P3V3_AUX         R4167 -1          A01X+165051Y+170861X0198Y0197R090 S1      
317P3V3_AUX         VIA   -    MD0100PA00X+164803Y+170861X0200Y    R270 S0      
317P3V3_AUX         VIA   -    MD0100PA00X+055838Y+048210X0200Y         S0      
327P3V3_AUX         D8005 -2          A01X+058428Y+048600X0260Y0540R270 S1      
317P3V3_AUX         VIA   -    MD0100PA00X+056730Y+048755X0200Y         S0      
317P3V3_AUX         VIA   -    MD0100PA00X+075763Y+023930X0200Y         S0      
317P3V3_AUX         VIA   -    MD0100PA00X+166331Y+021549X0200Y         S0      
317P3V3_AUX         VIA   -    MD0100PA00X+179264Y+076352X0190Y         S0      
327P3V3_AUX         C112  -1          A18X+178674Y+076376X0198Y0197     S2      
327P3V3_AUX         J67   -3          A01X+178814Y+076352X0205Y0590R090 S1      
317P3V3_AUX         VIA   -    MD0100PA00X+176294Y+076352X0190Y         S0      
327P3V3_AUX         J20   -3          A01X+175844Y+076352X0205Y0590R090 S1      
327P3V3_AUX         C132  -1          A18X+175704Y+076376X0198Y0197     S2      
317P3V3_AUX         VIA   -    MD0100PA00X+173324Y+076352X0190Y         S0      
327P3V3_AUX         J68   -3          A01X+172874Y+076352X0205Y0590R090 S1      
327P3V3_AUX         C128  -1          A18X+172734Y+076376X0198Y0197     S2      
317P3V3_AUX         VIA   -    MD0100PA00X+170354Y+076352X0190Y         S0      
327P3V3_AUX         J18   -3          A01X+169904Y+076352X0205Y0590R090 S1      
327P3V3_AUX         C124  -1          A18X+169764Y+076376X0198Y0197     S2      
317P3V3_AUX         VIA   -    MD0100PA00X+167384Y+076352X0190Y         S0      
327P3V3_AUX         J69   -3          A01X+166934Y+076352X0205Y0590R090 S1      
327P3V3_AUX         C120  -1          A18X+166794Y+076376X0198Y0197     S2      
327P3V3_AUX         C116  -1          A18X+163824Y+076376X0198Y0197     S2      
327P3V3_AUX         J16   -3          A01X+163964Y+076352X0205Y0590R090 S1      
317P3V3_AUX         VIA   -    MD0100PA00X+164414Y+076352X0190Y         S0      
317P3V3_AUX         VIA   -    MD0100PA00X+172641Y+065364X0200Y         S0      
327P3V3_AUX         U106  -10         A01X+172633Y+066093X0130Y0250R180 S1      
327P3V3_AUX         C1337 -1   M      A01X+172641Y+065624X0198Y0197R180 S1      
327P3V3_AUX         PR446 -2          A01X+164998Y+061897X0198Y0197R270 S1      
317P3V3_AUX         VIA   -    MD0100PA00X+164716Y+061897X0200Y         S0      
317P3V3_AUX         VIA   -    MD0100PA00X+071170Y+064653X0200Y         S0      
327P3V3_AUX         U108  -10         A01X+071682Y+064867X0130Y0250R090 S1      
327P3V3_AUX         C1339 -1   M      A01X+071170Y+064918X0198Y0197R090 S1      
317P3V3_AUX         VIA   -    MD0100PA00X+070378Y+064180X0200Y         S0      
317P3V3_AUX         VIA   -    MD0100PA00X+058142Y+081308X0200Y    R180 S0      
327P3V3_AUX         R522  -1          A18X+057217Y+080346X0198Y0197R090 S2      
327P3V3_AUX         C43   -1   M      A01X+071184Y+059079X0198Y0197R270 S1      
327P3V3_AUX         U27   -8          A01X+070566Y+058893X0240Y0460     S1      
317P3V3_AUX         VIA   -    MD0100PA00X+071458Y+059079X0200Y         S0      
317P3V3_AUX         VIA   -    MD0100PA00X+118827Y+057181X0200Y         S0      
327P3V3_AUX         U105  -10         A01X+118819Y+057902X0130Y0250R180 S1      
327P3V3_AUX         C1336 -1   M      A01X+118827Y+057432X0198Y0197R180 S1      
317P3V3_AUX         VIA   -    MD0100PA00X+182107Y+056516X0200Y    R180 S0      
317P3V3_AUX         VIA   -    MD0100PA00X+182407Y+056516X0200Y    R180 S0      
317P3V3_AUX         VIA   -    MD0100PA00X+182707Y+056516X0200Y    R180 S0      
317P3V3_AUX         VIA   -    MD0100PA00X+178534Y+145006X0200Y    R180 S0      
317P3V3_AUX         VIA   -    MD0100PA00X+178238Y+145010X0200Y    R180 S0      
317P3V3_AUX         VIA   -    MD0100PA00X+178534Y+144756X0200Y    R180 S0      
317P3V3_AUX         VIA   -    MD0100PA00X+178237Y+144758X0200Y    R180 S0      
327P3V3_AUX         R21   -1          A01X+101292Y+056050X0198Y0197     S1      
317P3V3_AUX         VIA   -    MD0100PA00X+101292Y+055800X0200Y    R180 S0      
327P3V3_AUX         R127  -1          A01X+102142Y+056600X0198Y0197     S1      
317P3V3_AUX         VIA   -    MD0100PA00X+102142Y+056861X0200Y    R180 S0      
317P3V3_AUX         VIA   -    MD0100PA00X+101772Y+054120X0200Y    R270 S0      
327P3V3_AUX         C1105 -1   M      A01X+102020Y+054135X0198Y0197R270 S1      
327P3V3_AUX         U54   -11         A01X+102496Y+054350X0070Y0280R270 S1      
317P3V3_AUX         VIA   -    MD0100PA00X+100453Y+055322X0200Y    R270 S0      
327P3V3_AUX         R128  -1          A01X+100701Y+055322X0198Y0197R270 S1      
317P3V3_AUX         VIA   -    MD0100PA00X+100453Y+054192X0200Y    R270 S0      
327P3V3_AUX         R129  -1          A01X+100701Y+054192X0198Y0197R090 S1      
327P3V3_AUX         L17   -1          A18X+003881Y+054700X0440Y0540     S2      
317P3V3_AUX         VIA   -    MD0100PA00X+003595Y+055160X0200Y    R180 S0      
317P3V3_AUX         VIA   -    MD0100PA00X+003995Y+055160X0200Y    R180 S0      
327P3V3_AUX         R4078 -1          A01X+005330Y+054987X0198Y0197R270 S1      
317P3V3_AUX         VIA   -    MD0100PA00X+005330Y+055236X0200Y    R180 S0      
327P3V3_AUX         R4080 -1          A01X+005836Y+054984X0198Y0197R270 S1      
317P3V3_AUX         VIA   -    MD0100PA00X+005836Y+055236X0200Y    R180 S0      
317P3V3_AUX         VIA   -    MD0100PA00X+078912Y+052942X0200Y         S0      
327P3V3_AUX         U8004 -5   M      A18X+079150Y+054926X0170Y0240R180 S2      
317P3V3_AUX         VIA   -    MD0100PA00X+077200Y+052986X0200Y         S0      
327P3V3_AUX         R6085 -1          A01X+077200Y+052744X0198Y0197R270 S1      
327P3V3_AUX         PR285 -1   M      A18X+144545Y+056132X0198Y0197R180 S2      
327P3V3_AUX         PQ13  -S          A18X+144349Y+056888X0320Y0360     S2      
317P3V3_AUX         VIA   -    MD0100PA00X+144105Y+056054X0200Y         S0      
327P3V3_AUX         R8300 -1          A01X+146668Y+054498X0198Y0197     S1      
327P3V3_AUX         R8298 -1          A01X+146668Y+056098X0198Y0197     S1      
317P3V3_AUX         VIA   -    MD0100PA00X+146426Y+056098X0200Y    R180 S0      
317P3V3_AUX         VIA   -    MD0100PA00X+146365Y+054498X0200Y    R180 S0      
327P3V3_AUX         PR316 -2          A18X+151676Y+053990X0198Y0197R090 S2      
317P3V3_AUX         VIA   -    MD0100PA00X+151676Y+053748X0200Y    R180 S0      
317P3V3_AUX         VIA   -    MD0100PA00X+101331Y+051815X0200Y    R270 S0      
327P3V3_AUX         C1104 -1          A18X+101331Y+052057X0198Y0197R270 S2      
327P3V3_AUX         U53   -15         A01X+100863Y+051715X0140Y0630R090 S1      
327P3V3_AUX         R1655 -1   M      A01X+098848Y+052607X0198Y0197     S1      
327P3V3_AUX         R1547 -1          A01X+098848Y+053107X0198Y0197     S1      
327P3V3_AUX         R20   -1   M      A01X+098848Y+052101X0198Y0197     S1      
317P3V3_AUX         VIA   -    MD0100PA00X+098606Y+051601X0200Y    R270 S0      
327P3V3_AUX         R610  -1   M      A01X+098848Y+051601X0198Y0197     S1      
317P3V3_AUX         VIA   -    MD0100PA00X+065942Y+052108X0200Y         S0      
317P3V3_AUX         VIA   -    MD0100PA00X+063151Y+051061X0200Y         S0      
327P3V3_AUX         R4521 -1          A01X+006444Y+050754X0198Y0197R270 S1      
317P3V3_AUX         VIA   -    MD0100PA00X+006444Y+051067X0200Y         S0      
327P3V3_AUX         R4081 -1          A01X+003124Y+051702X0198Y0197     S1      
317P3V3_AUX         VIA   -    MD0100PA00X+002856Y+051702X0200Y    R270 S0      
327P3V3_AUX         R316  -1          A01X+117278Y+048169X0198Y0197R180 S1      
317P3V3_AUX         VIA   -    MD0100PA00X+117518Y+048169X0200Y    R180 S0      
317P3V3_AUX         VIA   -    MD0100PA00X+114466Y+049232X0200Y         S0      
327P3V3_AUX         C106  -1   M      A01X+114466Y+048982X0198Y0197     S1      
327P3V3_AUX         U36   -24         A01X+114066Y+048339X0120Y0630R270 S1      
317P3V3_AUX         VIA   -    MD0100PA00X+124575Y+047073X0200Y         S0      
327P3V3_AUX         U64   -8          A01X+123834Y+047038X0350Y0500R270 S1      
327P3V3_AUX         C629  -1   M      A01X+124575Y+046815X0198Y0197     S1      
317P3V3_AUX         VIA   -    MD0100PA00X+119577Y+046527X0200Y         S0      
327P3V3_AUX         R717  -1          A01X+119991Y+046527X0198Y0197     S1      
327P3V3_AUX         R721  -1          A01X+119999Y+047038X0198Y0197     S1      
317P3V3_AUX         VIA   -    MD0100PA00X+119577Y+047039X0200Y         S0      
317P3V3_AUX         VIA   -    MD0100PA00X+117518Y+046984X0200Y    R180 S0      
327P3V3_AUX         R3395 -1          A01X+117278Y+046984X0198Y0197R180 S1      
317P3V3_AUX         VIA   -    MD0100PA00X+126523Y+045437X0200Y         S0      
327P3V3_AUX         R26   -1   M      A01X+126202Y+045918X0198Y0197R180 S1      
327P3V3_AUX         R43   -1   M      A01X+126209Y+045437X0198Y0197R180 S1      
317P3V3_AUX         VIA   -    MD0100PA00X+119577Y+046020X0200Y         S0      
327P3V3_AUX         R713  -1          A01X+119985Y+046020X0198Y0197     S1      
327P3V3_AUX         R68   -1          A01X+118835Y+045220X0198Y0197     S1      
317P3V3_AUX         VIA   -    MD0100PA00X+118595Y+045220X0200Y         S0      
327P3V3_AUX         R67   -1          A01X+117278Y+045334X0198Y0197R180 S1      
317P3V3_AUX         VIA   -    MD0100PA00X+117518Y+045334X0200Y    R180 S0      
317P3V3_AUX         VIA   -    MD0100PA00X+117518Y+046434X0200Y    R180 S0      
327P3V3_AUX         R3396 -1          A01X+117278Y+046434X0198Y0197R180 S1      
317P3V3_AUX         VIA   -    MD0100PA00X+117518Y+045884X0200Y    R180 S0      
327P3V3_AUX         R66   -1          A01X+117278Y+045884X0198Y0197R180 S1      
327P3V3_AUX         C1    -1   M      A01X+123688Y+044726X0198Y0197     S1      
317P3V3_AUX         VIA   -    MD0100PA00X+123688Y+044976X0200Y    R270 S0      
327P3V3_AUX         U1    -8          A01X+122565Y+044688X0350Y0500R270 S1      
327P3V3_AUX         R4    -1          A01X+124003Y+043526X0198Y0197R180 S1      
317P3V3_AUX         VIA   -    MD0100PA00X+124243Y+043526X0200Y    R180 S0      
327P3V3_AUX         R52   -1          A01X+118835Y+043620X0198Y0197     S1      
317P3V3_AUX         VIA   -    MD0100PA00X+118595Y+043620X0200Y         S0      
327P3V3_AUX         R60   -1          A01X+118835Y+044420X0198Y0197     S1      
317P3V3_AUX         VIA   -    MD0100PA00X+118595Y+044420X0200Y         S0      
317P3V3_AUX         VIA   -    MD0100PA00X+117518Y+044234X0200Y    R180 S0      
327P3V3_AUX         R2985 -1          A01X+117278Y+044234X0198Y0197R180 S1      
317P3V3_AUX         VIA   -    MD0100PA00X+117518Y+044784X0200Y    R180 S0      
327P3V3_AUX         R2984 -1          A01X+117278Y+044784X0198Y0197R180 S1      
327P3V3_AUX         C5229 -1          A18X+005672Y+043860X0198Y0197R090 S2      
327P3V3_AUX         C5234 -1          A18X+006076Y+043853X0198Y0197R090 S2      
317P3V3_AUX         VIA   -    MD0100PA00X+006354Y+043880X0200Y         S0      
327P3V3_AUX         U5201 -12         A18X+005070Y+043984X0070Y0240R270 S2      
317P3V3_AUX         VIA   -    MD0100PA00X+182587Y+042495X0200Y         S0      
327P3V3_AUX         R1150 -1          A01X+182587Y+042743X0198Y0197R180 S1      
317P3V3_AUX         VIA   -    MD0100PA00X+181572Y+042393X0200Y         S0      
327P3V3_AUX         U211  -5          A01X+180565Y+042133X0170Y0240R270 S1      
327P3V3_AUX         C592  -1   M      A01X+181572Y+042143X0198Y0197     S1      
327P3V3_AUX         R1905 -1          A01X+178472Y+042543X0198Y0197     S1      
317P3V3_AUX         VIA   -    MD0100PA00X+178232Y+042543X0200Y         S0      
327P3V3_AUX         PR3789-1          A01X+169015Y+043176X0198Y0197R270 S1      
317P3V3_AUX         VIA   -    MD0100PA00X+169014Y+043416X0200Y    R270 S0      
327P3V3_AUX         R24   -1          A01X+124003Y+043126X0198Y0197R180 S1      
317P3V3_AUX         VIA   -    MD0100PA00X+124243Y+043126X0200Y    R180 S0      
317P3V3_AUX         VIA   -    MD0100PA00X+181622Y+041043X0200Y         S0      
327P3V3_AUX         C593  -1   M      A01X+181622Y+040793X0198Y0197     S1      
327P3V3_AUX         U8    -5          A01X+180566Y+040806X0170Y0240R270 S1      
327P3V3_AUX         R1907 -1          A01X+178472Y+041893X0198Y0197     S1      
317P3V3_AUX         VIA   -    MD0100PA00X+178232Y+041893X0200Y         S0      
327P3V3_AUX         R1906 -1          A01X+178472Y+041043X0198Y0197     S1      
317P3V3_AUX         VIA   -    MD0100PA00X+178232Y+041043X0200Y         S0      
327P3V3_AUX         PR3798-1          A01X+171810Y+042034X0198Y0197R180 S1      
327P3V3_AUX         PC5328-1          A01X+171810Y+042434X0198Y0197R180 S1      
317P3V3_AUX         VIA   -    MD0100PA00X+170900Y+041336X0200Y    R270 S0      
317P3V3_AUX         VIA   -    MD0100PA00X+170900Y+041586X0200Y    R270 S0      
327P3V3_AUX         PU202 -A3         A01X+170307Y+041664X0090Y    R270 S1      
327P3V3_AUX         PU202 -A5         A01X+170307Y+041271X0090Y    R270 S1      
327P3V3_AUX         PU202 -B3         A01X+170110Y+041664X0090Y    R270 S1      
327P3V3_AUX         PU202 -B5         A01X+170110Y+041271X0090Y    R270 S1      
327P3V3_AUX         PU202 -C3         A01X+169913Y+041664X0090Y    R270 S1      
327P3V3_AUX         PU202 -C5         A01X+169913Y+041271X0090Y    R270 S1      
327P3V3_AUX         PU202 -D5         A01X+169716Y+041271X0090Y    R270 S1      
317P3V3_AUX         VIA   -    MD0100PA00X+170650Y+041336X0200Y    R270 S0      
317P3V3_AUX         VIA   -    MD0100PA00X+170650Y+041586X0200Y    R270 S0      
327P3V3_AUX         PU205 -1_2        A01X+165413Y+041420X0295Y0354R090 S1      
317P3V3_AUX         VIA   -    MD0100PA00X+165002Y+041145X0200Y         S0      
317P3V3_AUX         VIA   -    MD0100PA00X+165002Y+040895X0200Y         S0      
327P3V3_AUX         PC2159-1          A01X+164768Y+041420X0198Y0197R180 S1      
317P3V3_AUX         VIA   -    MD0100PA00X+164731Y+041142X0200Y         S0      
317P3V3_AUX         VIA   -    MD0100PA00X+164731Y+040892X0200Y         S0      
317P3V3_AUX         VIA   -    MD0100PA00X+181699Y+039805X0200Y         S0      
327P3V3_AUX         U66   -5          A01X+181311Y+039041X0170Y0240R270 S1      
327P3V3_AUX         C639  -1   M      A01X+181699Y+039555X0198Y0197     S1      
327P3V3_AUX         R1908 -1          A01X+178472Y+040393X0198Y0197     S1      
317P3V3_AUX         VIA   -    MD0100PA00X+178232Y+040393X0200Y         S0      
327P3V3_AUX         R3783 -1          A01X+169558Y+040148X0198Y0197R180 S1      
317P3V3_AUX         VIA   -    MD0100PA00X+169558Y+040398X0200Y    R270 S0      
327P3V3_AUX         R3796 -1          A01X+169981Y+040148X0198Y0197     S1      
317P3V3_AUX         VIA   -    MD0100PA00X+169981Y+040398X0200Y    R270 S0      
317P3V3_AUX         VIA   -    MD0100PA00X+008752Y+039586X0200Y         S0      
327P3V3_AUX         R3656 -1          A01X+008495Y+039586X0198Y0197R180 S1      
317P3V3_AUX         VIA   -    MD0100PA00X+008752Y+039139X0200Y         S0      
327P3V3_AUX         R3657 -1          A01X+008495Y+039139X0198Y0197R180 S1      
317P3V3_AUX         VIA   -    MD0100PA00X+008752Y+038222X0200Y         S0      
327P3V3_AUX         R3663 -1          A01X+008495Y+038222X0198Y0197R180 S1      
317P3V3_AUX         VIA   -    MD0100PA00X+007768Y+038090X0200Y         S0      
317P3V3_AUX         VIA   -    MD0100PA00X+007768Y+037840X0200Y         S0      
327P3V3_AUX         R3655 -1          A18X+007417Y+038162X0198Y0197R270 S2      
317P3V3_AUX         VIA   -    MD0100PA00X+181716Y+037383X0200Y         S0      
327P3V3_AUX         C1840 -1   M      A01X+181716Y+037133X0198Y0197     S1      
327P3V3_AUX         U224  -5          A01X+181255Y+037117X0170Y0240R270 S1      
327P3V3_AUX         R3658 -1          A01X+006343Y+036334X0198Y0197R090 S1      
317P3V3_AUX         VIA   -    MD0100PA00X+006343Y+036070X0200Y         S0      
327P3V3_AUX         R3659 -1          A01X+005932Y+036334X0198Y0197R090 S1      
317P3V3_AUX         VIA   -    MD0100PA00X+005932Y+036070X0200Y         S0      
327P3V3_AUX         R3660 -1          A01X+005111Y+036334X0198Y0197R090 S1      
317P3V3_AUX         VIA   -    MD0100PA00X+005111Y+036086X0200Y         S0      
317P3V3_AUX         VIA   -    MD0100PA00X+011502Y+032072X0200Y    R180 S0      
327P3V3_AUX         R6182 -1          A01X+011502Y+031821X0198Y0197R270 S1      
327P3V3_AUX         U58   -5          A01X+005474Y+031110X0170Y0240R270 S1      
327P3V3_AUX         C1809 -1   M      A01X+005978Y+031036X0198Y0197     S1      
317P3V3_AUX         VIA   -    MD0100PA00X+005978Y+031287X0200Y    R180 S0      
317P3V3_AUX         VIA   -    MD0100PA00X+003428Y+030780X0200Y    R270 S0      
327P3V3_AUX         R3135 -1          A01X+003679Y+030780X0198Y0197     S1      
327P3V3_AUX         R3133 -1          A01X+003679Y+031292X0198Y0197     S1      
317P3V3_AUX         VIA   -    MD0100PA00X+003428Y+031292X0200Y    R270 S0      
317P3V3_AUX         VIA   -    MD0100PA00X+011502Y+030028X0200Y    R180 S0      
327P3V3_AUX         R6181 -1          A01X+011502Y+029777X0198Y0197R270 S1      
317P3V3_AUX         VIA   -    MD0100PA00X+006629Y+029821X0200Y    R090 S0      
327P3V3_AUX         C1876 -1   M      A01X+006378Y+029821X0198Y0197R090 S1      
327P3V3_AUX         U242  -8          A01X+005867Y+029821X0200Y0340R270 S1      
327P3V3_AUX         C1875 -1   M      A01X+003318Y+029821X0198Y0197R090 S1      
327P3V3_AUX         U241  -8          A01X+002807Y+029821X0200Y0340R270 S1      
317P3V3_AUX         VIA   -    MD0100PA00X+003569Y+029821X0200Y    R090 S0      
327P3V3_AUX         C1810 -1   M      A01X+005978Y+028036X0198Y0197     S1      
327P3V3_AUX         U59   -5          A01X+005478Y+028036X0170Y0240R270 S1      
317P3V3_AUX         VIA   -    MD0100PA00X+005978Y+028287X0200Y    R180 S0      
327P3V3_AUX         R3147 -1          A01X+005978Y+027236X0198Y0197     S1      
317P3V3_AUX         VIA   -    MD0100PA00X+005727Y+027236X0200Y    R270 S0      
327P3V3_AUX         R3134 -1          A01X+003679Y+028292X0198Y0197     S1      
317P3V3_AUX         VIA   -    MD0100PA00X+003428Y+028292X0200Y    R270 S0      
327P3V3_AUX         R3136 -1          A01X+003679Y+027780X0198Y0197     S1      
317P3V3_AUX         VIA   -    MD0100PA00X+003428Y+027780X0200Y    R270 S0      
327P3V3_AUX         U276  -9          A01X+085299Y+021144X0090Y0240R270 S1      
327P3V3_AUX         C2067 -1          A18X+085280Y+020936X0198Y0197     S2      
317P3V3_AUX         VIA   -    MD0100PA00X+085586Y+021242X0200Y         S0      
317P3V3_AUX         VIA   -    MD0100PA00X+118682Y+018193X0200Y         S0      
317P3V3_AUX         VIA   -    MD0100PA00X+118682Y+018543X0200Y         S0      
317P3V3_AUX         VIA   -    MD0100PA00X+180862Y+017087X0200Y    R180 S0      
327P3V3_AUX         PR8073-1          A18X+181105Y+017087X0198Y0197R180 S2      
317P3V3_AUX         VIA   -    MD0100PA00X+082533Y+016686X0200Y    R180 S0      
327P3V3_AUX         R3529 -1          A01X+082814Y+016686X0198Y0197     S1      
327P3V3_AUX         R2488 -1          A01X+182516Y+015183X0198Y0197R180 S1      
317P3V3_AUX         VIA   -    MD0100PA00X+182758Y+015183X0200Y    R090 S0      
327P3V3_AUX         R2907 -1   M      A01X+129918Y+016205X0198Y0197R180 S1      
317P3V3_AUX         VIA   -    MD0100PA00X+130174Y+016206X0200Y         S0      
327P3V3_AUX         R3667 -1          A01X+119213Y+016099X0198Y0197     S1      
317P3V3_AUX         VIA   -    MD0100PA00X+118973Y+016099X0200Y    R180 S0      
327P3V3_AUX         R3669 -1          A01X+119213Y+016499X0198Y0197     S1      
317P3V3_AUX         VIA   -    MD0100PA00X+118973Y+016499X0200Y    R180 S0      
317P3V3_AUX         VIA   -    MD0100PA00X+084874Y+016014X0200Y         S0      
327P3V3_AUX         U279  -8          A01X+084256Y+016806X0240Y0460R270 S1      
327P3V3_AUX         C1997 -1   M      A01X+084874Y+016276X0198Y0197     S1      
317P3V3_AUX         VIA   -    MD0100PA00X+077227Y+015373X0200Y         S0      
327P3V3_AUX         R1857 -1          A01X+077473Y+015373X0198Y0197     S1      
327P3V3_AUX         C36   -1   M      A01X+181500Y+015183X0198Y0197     S1      
327P3V3_AUX         U8082 -5          A01X+181028Y+015183X0170Y0240R270 S1      
317P3V3_AUX         VIA   -    MD0100PA00X+181500Y+014932X0200Y         S0      
317P3V3_AUX         VIA   -    MD0100PA00X+178401Y+013740X0200Y         S0      
327P3V3_AUX         R3797 -1          A01X+179074Y+007806X0198Y0197R270 S1      
317P3V3_AUX         VIA   -    MD0100PA00X+178820Y+007811X0200Y         S0      
327P3V3_AUX         R3799 -1          A01X+179074Y+008229X0198Y0197R090 S1      
317P3V3_AUX         VIA   -    MD0100PA00X+178820Y+008234X0200Y         S0      
327P3V3_AUX         R6042 -1          A01X+165495Y+014676X0198Y0197     S1      
317P3V3_AUX         VIA   -    MD0100PA00X+165252Y+014676X0200Y    R270 S0      
327P3V3_AUX         R3978 -1          A01X+099458Y+015230X0198Y0197R180 S1      
317P3V3_AUX         VIA   -    MD0100PA00X+099426Y+015490X0200Y    R270 S0      
327P3V3_AUX         R3976 -1          A01X+100158Y+015230X0198Y0197R180 S1      
317P3V3_AUX         VIA   -    MD0100PA00X+099958Y+015490X0200Y         S0      
317P3V3_AUX         VIA   -    MD0100PA00X+108742Y+014972X0200Y         S0      
327P3V3_AUX         C2014 -1          A01X+082661Y+014712X0198Y0197R090 S1      
317P3V3_AUX         VIA   -    MD0100PA00X+082912Y+014712X0200Y    R090 S0      
327P3V3_AUX         U265  -9          A01X+082647Y+014241X0090Y0240     S1      
327P3V3_AUX         R1319 -2   M      A18X+071467Y+009471X0198Y0197R270 S2      
327P3V3_AUX         R3062 -2          A18X+071067Y+009471X0198Y0197R270 S2      
327P3V3_AUX         R3241 -2   M      A18X+071867Y+009471X0198Y0197R270 S2      
327P3V3_AUX         R3240 -2   M      A18X+072267Y+009471X0198Y0197R270 S2      
317P3V3_AUX         VIA   -    MD0100PA00X+075122Y+013786X0200Y         S0      
327P3V3_AUX         R4013 -1          A01X+076019Y+010065X0198Y0197R090 S1      
317P3V3_AUX         VIA   -    MD0100PA00X+075769Y+010065X0200Y         S0      
317P3V3_AUX         VIA   -    MD0100PA00X+075769Y+009811X0200Y         S0      
327P3V3_AUX         R4015 -1          A01X+076019Y+009642X0198Y0197R270 S1      
327P3V3_AUX         R1854 -1          A01X+074882Y+013786X0198Y0197R180 S1      
327P3V3_AUX         R1356 -1          A18X+168735Y+013676X0198Y0197R180 S2      
317P3V3_AUX         VIA   -    MD0100PA00X+168492Y+013676X0200Y    R090 S0      
317P3V3_AUX         VIA   -    MD0100PA00X+168492Y+013176X0200Y    R090 S0      
327P3V3_AUX         R1357 -1          A18X+168735Y+013176X0198Y0197R180 S2      
327P3V3_AUX         U320  -5          A01X+149280Y+012708X0180Y0520R090 S1      
327P3V3_AUX         C2344 -1   M      A01X+148382Y+012883X0198Y0197R270 S1      
317P3V3_AUX         VIA   -    MD0100PA00X+148382Y+013240X0200Y         S0      
327P3V3_AUX         C1354 -1   M      A01X+145567Y+012824X0198Y0197     S1      
327P3V3_AUX         U116  -15         A01X+145367Y+013482X0140Y0630R180 S1      
317P3V3_AUX         VIA   -    MD0100PA00X+145567Y+012573X0200Y         S0      
317P3V3_AUX         VIA   -    MD0100PA00X+119976Y+012875X0200Y    R180 S0      
327P3V3_AUX         R5101 -1          A01X+120218Y+012875X0198Y0197     S1      
317P3V3_AUX         VIA   -    MD0100PA00X+020058Y+012550X0200Y         S0      
327P3V3_AUX         U225  -5          A01X+020306Y+012050X0170Y0240     S1      
327P3V3_AUX         C1841 -1   M      A01X+020306Y+012550X0198Y0197R090 S1      
317P3V3_AUX         VIA   -    MD0100PA00X+018493Y+012550X0200Y         S0      
327P3V3_AUX         C1825 -1   M      A01X+019086Y+012550X0198Y0197R090 S1      
327P3V3_AUX         U286  -5          A01X+019086Y+012050X0170Y0240     S1      
327P3V3_AUX         R4532 -1          A01X+172234Y+011287X0198Y0197     S1      
327P3V3_AUX         PR3839-2          A01X+172234Y+011687X0198Y0197R180 S1      
317P3V3_AUX         VIA   -    MD0100PA00X+171991Y+011671X0200Y         S0      
317P3V3_AUX         VIA   -    MD0100PA00X+171991Y+011271X0200Y         S0      
317P3V3_AUX         VIA   -    MD0100PA00X+145455Y+010744X0200Y    R180 S0      
327P3V3_AUX         R822  -1          A01X+145455Y+010987X0198Y0197R090 S1      
327P3V3_AUX         R823  -1          A01X+144855Y+011707X0198Y0197R090 S1      
317P3V3_AUX         VIA   -    MD0100PA00X+144855Y+011464X0200Y         S0      
317P3V3_AUX         VIA   -    MD0100PA00X+144305Y+010744X0200Y    R180 S0      
327P3V3_AUX         R824  -1          A01X+144305Y+010987X0198Y0197R090 S1      
317P3V3_AUX         VIA   -    MD0100PA00X+143905Y+010744X0200Y    R180 S0      
327P3V3_AUX         R825  -1          A01X+143905Y+010987X0198Y0197R090 S1      
317P3V3_AUX         VIA   -    MD0100PA00X+083936Y+011486X0200Y         S0      
327P3V3_AUX         C1274 -1   M      A01X+083462Y+010736X0198Y0197R270 S1      
327P3V3_AUX         R4091 -1          A01X+083936Y+011751X0198Y0197R090 S1      
317P3V3_AUX         VIA   -    MD0100PA00X+082312Y+011522X0200Y    R090 S0      
327P3V3_AUX         R3624 -1   M      A01X+082311Y+011762X0198Y0197R090 S1      
327P3V3_AUX         R3622 -1          A01X+082711Y+011762X0198Y0197R090 S1      
317P3V3_AUX         VIA   -    MD0100PA00X+067774Y+011543X0200Y         S0      
317P3V3_AUX         VIA   -    MD0100PA00X+067756Y+011841X0200Y         S0      
327P3V3_AUX         R3836 -1          A01X+068038Y+011587X0198Y0197     S1      
327P3V3_AUX         PR4007-2          A01X+068038Y+011987X0198Y0197R180 S1      
327P3V3_AUX         R6022 -1          A01X+060233Y+010664X0198Y0197R270 S1      
317P3V3_AUX         VIA   -    MD0100PA00X+060233Y+010906X0200Y         S0      
327P3V3_AUX         R6024 -1          A01X+059051Y+010664X0198Y0197R270 S1      
317P3V3_AUX         VIA   -    MD0100PA00X+059138Y+010916X0200Y         S0      
317P3V3_AUX         VIA   -    MD0100PA00X+079602Y+039592X0200Y         S0      
317P3V3_AUX         VIA   -    MD0100PA00X+081122Y+039597X0200Y         S0      
327P3V3_AUX         D8004 -2          A01X+081122Y+039950X0260Y0540R090 S1      
317P3V3_AUX         VIA   -    MD0100PA00X+081699Y+039534X0200Y         S0      
317P3V3_AUX         VIA   -    MD0100PA00X+055251Y+044649X0200Y         S0      
317P3V3_AUX         VIA   -    MD0100PA00X+049850Y+041942X0200Y         S0      
317P3V3_AUX         VIA   -    MD0100PA00X+169300Y+023400X0200Y         S0      
317P3V3_AUX         VIA   -    MD0100PA00X+077650Y+037100X0200Y         S0      
317P3V3_AUX         VIA   -    MD0100PA00X+076900Y+036400X0200Y         S0      
327P3V3_AUX         D8006 -2          A01X+079872Y+036600X0260Y0540R090 S1      
317P3V3_AUX         VIA   -    MD0100PA00X+080350Y+036600X0200Y         S0      
317P3V3_AUX         VIA   -    MD0100PA00X+083300Y+040950X0200Y         S0      
327P3V3_AUX         D8003 -2          A01X+081022Y+040950X0260Y0540R090 S1      
317P3V3_AUX         VIA   -    MD0100PA00X+080756Y+040380X0200Y         S0      
317P3V3_AUX         VIA   -    MD0100PA00X+078700Y+040750X0200Y         S0      
327P3V3_AUX         U160  -16         A01X+045193Y+024095X0240Y0540R270 S1      
327P3V3_AUX         U212  -16         A01X+052998Y+024363X0240Y0540R270 S1      
327P3V3_AUX         U321  -5          A01X+035732Y+013000X0180Y0520R270 S1      
317P3V3_AUX         VIA   -    MD0100PA00X+066337Y+048430X0200Y         S0      
327P3V3_AUX         R6139 -1          A01X+066124Y+049513X0198Y0197     S1      
327P3V3_AUX         R6138 -1   M      A01X+066138Y+048694X0198Y0197     S1      
317P3V3_AUX         VIA   -    MD0100PA00X+008574Y+139160X0200Y         S0      
327P3V3_AUX         PR341 -2          A01X+009060Y+138586X0198Y0197R090 S1      
317P3V3_AUX         VIA   -    MD0100PA00X+006835Y+131410X0200Y         S0      
317P3V3_AUX         VIA   -    MD0100PA00X+009579Y+127801X0200Y         S0      
327P3V3_AUX         R515  -1          A18X+035870Y+120239X0198Y0197R180 S2      
317P3V3_AUX         VIA   -    MD0100PA00X+033953Y+121860X0200Y         S0      
317P3V3_AUX         VIA   -    MD0100PA00X+003458Y+131524X0200Y         S0      
317P3V3_AUX         VIA   -    MD0100PA00X+003458Y+131274X0200Y         S0      
317P3V3_AUX         VIA   -    MD0100PA00X+003458Y+131024X0200Y         S0      
317P3V3_AUX         VIA   -    MD0100PA00X+003458Y+130774X0200Y         S0      
317P3V3_AUX         VIA   -    MD0100PA00X+039505Y+012118X0200Y         S0      
327P3V3_AUX         R757  -2          A18X+082342Y+047616X0198Y0197R180 S2      
317P3V3_AUX         VIA   -    MD0100PA00X+082691Y+047599X0200Y         S0      
327P3V3_AUX         U18   -V3         A01X+075087Y+042619X0160Y    R090 S1      
317P3V3_AUX         VIA   -    MD0100PA00X+075241Y+042466X0180Y    R090 S0      
327P3V3_AUX         R135  -2          A01X+083698Y+045558X0198Y0197R180 S1      
317P3V3_AUX         VIA   -    MD0100PA00X+053807Y+059265X0200Y         S0      
327P3V3_AUX         PR336 -2          A01X+053950Y+059534X0198Y0197R270 S1      
317P3V3_AUX         VIA   -    MD0100PA00X+045872Y+052448X0200Y         S0      
317P3V3_AUX         VIA   -    MD0100PA00X+056615Y+032450X0200Y    R270 S0      
327P3V3_AUX         R6242 -1          A18X+056615Y+032199X0198Y0197     S2      
317P3V3_AUX         VIA   -    M      A01X+057082Y+029489X0200Y    R270 S2      
017P3V3_AUX         VIA   -    M      A18X+057082Y+029489X0260Y    R270 S2      
017P3V3_AUX               -    MD0100PA00X+057082Y+029489                       
327P3V3_AUX         R6243 -1          A01X+057411Y+029415X0198Y0197R090 S1      
327P3V3_AUX         L6000 -1          A18X+056096Y+013179X0440Y0540R180 S2      
327P3V3_AUX         PC1600-1          A18X+179980Y+026243X0400Y0500R270 S2      
327P3V3_AUX         PC1869-1          A18X+180730Y+026061X0198Y0197R090 S2      
327P3V3_AUX         PC1599-1          A18X+179178Y+026243X0400Y0500R270 S2      
327P3V3_AUX         PC1868-1          A18X+178330Y+026243X0400Y0500R270 S2      
317P3V3_AUX         VIA   -    MD0100PA00X+083425Y+045558X0200Y         S0      
317P3V3_AUX         VIA   -    MD0100PA00X+083411Y+043928X0200Y         S0      
327P3V3_AUX         R6277 -1          A01X+049307Y+016762X0198Y0197R180 S1      
317P3V3_AUX         VIA   -    MD0100PA00X+049550Y+016139X0200Y         S0      
317P3V3_AUX         VIA   -    MD0100PA00X+058348Y+013306X0200Y    R090 S0      
317P3V3_AUX         VIA   -    MD0100PA00X+058348Y+013053X0200Y    R090 S0      
317P3V3_AUX         VIA   -    MD0100PA00X+058048Y+013053X0200Y    R090 S0      
317P3V3_AUX         VIA   -    MD0100PA00X+058048Y+013306X0200Y    R090 S0      
327P3V3_AUX         C6048 -1          A18X+052702Y+013321X0198Y0197R180 S2      
327P3V3_AUX         C6053 -1          A18X+052702Y+012921X0198Y0197R180 S2      
327P3V3_AUX         C6051 -1          A18X+051909Y+012213X0198Y0197R270 S2      
327P3V3_AUX         C6047 -1          A18X+053888Y+012391X0198Y0197R270 S2      
327P3V3_AUX         C6052 -1          A18X+053488Y+012391X0198Y0197R270 S2      
327P3V3_AUX         C6046 -1          A18X+054375Y+012362X0280Y0320     S2      
327P3V3_AUX         C6050 -1          A18X+051909Y+012913X0198Y0197R270 S2      
327P3V3_AUX         C6049 -1          A18X+052309Y+012913X0198Y0197R270 S2      
327P3V3_AUX         C6040 -1          A18X+051762Y+016302X0198Y0197R090 S2      
327P3V3_AUX         C6041 -1          A18X+051362Y+016302X0198Y0197R090 S2      
327P3V3_AUX         PQ11  -S          A01X+042601Y+053270X0320Y0360     S1      
317P3V3_AUX         VIA   -    MD0100PA00X+042601Y+052489X0200Y         S0      
327P3V3_AUX         PR152 -1          A01X+041277Y+053106X0198Y0197R090 S1      
317P3V3_AUX         VIA   -    MD0100PA00X+041277Y+052482X0200Y         S0      
317P3V3_AUX         VIA   -    MD0100PA00X+014698Y+053100X0200Y    R090 S0      
327P3V3_AUX         R3322 -1          A01X+014457Y+053100X0198Y0197R180 S1      
317P3V3_AUX         VIA   -    MD0100PA00X+028939Y+049896X0200Y         S0      
317P3V3_AUX         VIA   -    MD0100PA00X+042978Y+046632X0200Y         S0      
327P3V3_AUX         R1492 -1          A01X+042978Y+046874X0198Y0197R090 S1      
317P3V3_AUX         VIA   -    MD0100PA00X+041598Y+046639X0200Y         S0      
327P3V3_AUX         R1449 -1          A01X+041598Y+046882X0198Y0197R090 S1      
317P3V3_AUX         VIA   -    MD0100PA00X+040218Y+046647X0200Y         S0      
327P3V3_AUX         R1450 -1          A01X+040218Y+046889X0198Y0197R090 S1      
327P3V3_AUX         R6226 -1          A18X+044171Y+024259X0198Y0197R270 S2      
317P3V3_AUX         VIA   -    MD0100PA00X+044431Y+024337X0200Y    R225 S0      
327P3V3_AUX         R6329 -1          A01X+039505Y+012360X0198Y0197R090 S1      
327P3V3_AUX         C1503 -1   M      A01X+057786Y+021777X0198Y0197R270 S1      
327P3V3_AUX         U147  -7          A01X+057667Y+022274X0070Y0320R180 S1      
317P3V3_AUX         VIA   -    MD0100PA00X+058034Y+021777X0200Y    R180 S0      
327P3V3_AUX         R1622 -1          A01X+057116Y+023582X0198Y0197     S1      
317P3V3_AUX         VIA   -    MD0100PA00X+056874Y+023582X0200Y         S0      
317P3V3_AUX         VIA   -    MD0100PA00X+058282Y+022870X0200Y    R180 S0      
327P3V3_AUX         U147  -10         A01X+057948Y+022707X0070Y0310R270 S1      
327P3V3_AUX         R6315 -1          A01X+041530Y+021765X0198Y0197R270 S1      
317P3V3_AUX         VIA   -    MD0100PA00X+044784Y+027597X0200Y    R180 S0      
317P3V3_AUX         VIA   -    MD0100PA00X+045542Y+024410X0200Y    R180 S0      
327P3V3_AUX         R6227 -1          A18X+045171Y+024159X0198Y0197R270 S2      
327P3V3_AUX         R6222 -1          A01X+041514Y+026616X0198Y0197     S1      
317P3V3_AUX         VIA   -    MD0100PA00X+041272Y+026616X0200Y    R270 S0      
317P3V3_AUX         VIA   -    MD0100PA00X+041272Y+025116X0200Y    R270 S0      
327P3V3_AUX         R6220 -1          A01X+041514Y+025016X0198Y0197     S1      
317P3V3_AUX         VIA   -    MD0100PA00X+041272Y+025816X0200Y    R270 S0      
327P3V3_AUX         R6218 -1          A01X+041514Y+025816X0198Y0197     S1      
317P3V3_AUX         VIA   -    MD0100PA00X+055020Y+019026X0200Y    R090 S0      
327P3V3_AUX         R6207 -1          A01X+055020Y+018783X0198Y0197R270 S1      
317P3V3_AUX         VIA   -    MD0100PA00X+054720Y+019026X0200Y         S0      
327P3V3_AUX         R6206 -1          A01X+054477Y+019026X0198Y0197R180 S1      
317P3V3_AUX         VIA   -    MD0100PA00X+054720Y+019926X0200Y         S0      
327P3V3_AUX         R6215 -1          A01X+054477Y+019926X0198Y0197R180 S1      
327P3V3_AUX         R6205 -1          A01X+049766Y+018552X0198Y0197     S1      
327P3V3_AUX         R6204 -1          A01X+050593Y+018552X0198Y0197     S1      
317P3V3_AUX         VIA   -    MD0100PA00X+050351Y+018552X0200Y         S0      
317P3V3_AUX         VIA   -    MD0100PA00X+049523Y+018552X0200Y         S0      
317P3V3_AUX         VIA   -    MD0100PA00X+049523Y+019352X0200Y    R180 S0      
327P3V3_AUX         R6213 -1          A01X+049766Y+019352X0198Y0197     S1      
317P3V3_AUX         VIA   -    MD0100PA00X+048668Y+019352X0200Y    R180 S0      
327P3V3_AUX         R4452 -1          A01X+048911Y+019352X0198Y0197     S1      
317P3V3_AUX         VIA   -    MD0100PA00X+043800Y+017070X0200Y         S0      
317P3V3_AUX         VIA   -    MD0100PA00X+040314Y+014830X0200Y         S0      
327P3V3_AUX         R6327 -1          A01X+040557Y+014830X0198Y0197     S1      
317P3V3_AUX         VIA   -    MD0100PA00X+046200Y+016640X0200Y    R090 S0      
327P3V3_AUX         R6282 -1          A01X+046200Y+016370X0198Y0197R270 S1      
317P3V3_AUX         VIA   -    MD0100PA00X+045000Y+016640X0200Y    R090 S0      
327P3V3_AUX         R6289 -1          A01X+045000Y+016370X0198Y0197R270 S1      
317P3V3_AUX         VIA   -    MD0100PA00X+045400Y+016640X0200Y    R090 S0      
327P3V3_AUX         R6283 -1          A01X+045400Y+016370X0198Y0197R270 S1      
317P3V3_AUX         VIA   -    MD0100PA00X+044600Y+016640X0200Y    R090 S0      
327P3V3_AUX         R6287 -1          A01X+044600Y+016370X0198Y0197R270 S1      
317P3V3_AUX         VIA   -    MD0100PA00X+043800Y+016640X0200Y    R090 S0      
327P3V3_AUX         R6294 -1          A01X+043800Y+016370X0198Y0197R270 S1      
317P3V3_AUX         VIA   -    MD0100PA00X+043400Y+016640X0200Y    R090 S0      
327P3V3_AUX         R6292 -1          A01X+043400Y+016370X0198Y0197R270 S1      
327P3V3_AUX         R6297 -1          A01X+046857Y+020662X0198Y0197R180 S1      
317P3V3_AUX         VIA   -    MD0100PA00X+046857Y+021310X0200Y    R090 S0      
327P3V3_AUX         R6298 -1   M      A01X+046857Y+021062X0198Y0197R180 S1      
317P3V3_AUX         VIA   -    MD0100PA00X+042482Y+021765X0200Y    R180 S0      
327P3V3_AUX         R6312 -1   M      A01X+042730Y+021765X0198Y0197R270 S1      
317P3V3_AUX         VIA   -    MD0100PA00X+044730Y+022005X0200Y    R090 S0      
327P3V3_AUX         R6303 -1          A01X+044730Y+021765X0198Y0197R270 S1      
317P3V3_AUX         VIA   -    MD0100PA00X+044330Y+022005X0200Y    R090 S0      
327P3V3_AUX         R6301 -1          A01X+044330Y+021765X0198Y0197R270 S1      
317P3V3_AUX         VIA   -    MD0100PA00X+041161Y+022314X0200Y    R090 S0      
327P3V3_AUX         R6320 -1          A01X+040730Y+021765X0198Y0197R270 S1      
327P3V3_AUX         R6212 -1          A01X+109295Y+047943X0198Y0197R270 S1      
327P3V3_AUX         R6246 -2          A18X+121409Y+026106X0198Y0197R090 S2      
317P3V3_AUX         VIA   -    MD0100PA00X+051377Y+012122X0200Y         S0      
317P3V3_AUX         VIA   -    MD0100PA00X+053057Y+012591X0200Y         S0      
317P3V3_AUX         VIA   -    MD0100PA00X+052499Y+012591X0200Y         S0      
317P3V3_AUX         VIA   -    MD0100PA00X+051927Y+016743X0200Y    R180 S0      
317P3V3_AUX         VIA   -    MD0100PA00X+109545Y+047943X0200Y         S0      
317P3V3_AUX         VIA   -    MD0100PA00X+121409Y+025863X0200Y         S0      
317P3V3_AUX         VIA   -    MD0100PA00X+060787Y+025756X0200Y    R090 S0      
317P3V3_AUX         J57   -1   MD0460PA00X+060902Y+027427X0660Y0660R180 S3      
327P3V3_AUX         R3097 -2          A18X+136609Y+026106X0198Y0197R090 S2      
327P3V3_AUX         R3095 -2          A18X+135009Y+026106X0198Y0197R090 S2      
327P3V3_AUX         R3099 -2          A18X+135809Y+026106X0198Y0197R090 S2      
327P3V3_AUX         R3096 -2          A18X+134209Y+026106X0198Y0197R090 S2      
327P3V3_AUX         R3093 -2          A18X+132609Y+026106X0198Y0197R090 S2      
327P3V3_AUX         R3094 -2          A18X+133409Y+026106X0198Y0197R090 S2      
327P3V3_AUX         R3090 -2          A18X+131009Y+026106X0198Y0197R090 S2      
327P3V3_AUX         R3091 -2          A18X+131809Y+026106X0198Y0197R090 S2      
327P3V3_AUX         R3088 -2          A18X+129409Y+026106X0198Y0197R090 S2      
327P3V3_AUX         R3092 -2          A18X+130209Y+026106X0198Y0197R090 S2      
327P3V3_AUX         R3087 -2          A18X+127809Y+026106X0198Y0197R090 S2      
327P3V3_AUX         R3089 -2          A18X+128609Y+026106X0198Y0197R090 S2      
327P3V3_AUX         R3086 -2          A18X+127009Y+026106X0198Y0197R090 S2      
327P3V3_AUX         R3075 -2          A18X+126209Y+026106X0198Y0197R090 S2      
327P3V3_AUX         R4604 -1          A18X+124778Y+030331X0198Y0197R090 S2      
327P3V3_AUX         R3071 -2          A18X+125409Y+026106X0198Y0197R090 S2      
327P3V3_AUX         R4605 -1          A18X+122209Y+031172X0198Y0197R090 S2      
327P3V3_AUX         R3069 -2          A18X+123009Y+026106X0198Y0197R090 S2      
327P3V3_AUX         R3074 -2          A18X+122209Y+026106X0198Y0197R090 S2      
317P3V3_AUX         VIA   -    MD0100PA00X+136609Y+025863X0200Y         S0      
317P3V3_AUX         VIA   -    MD0100PA00X+135009Y+025863X0200Y         S0      
317P3V3_AUX         VIA   -    MD0100PA00X+135809Y+025863X0200Y         S0      
317P3V3_AUX         VIA   -    MD0100PA00X+134209Y+025863X0200Y         S0      
317P3V3_AUX         VIA   -    MD0100PA00X+132609Y+025863X0200Y         S0      
317P3V3_AUX         VIA   -    MD0100PA00X+133409Y+025863X0200Y         S0      
317P3V3_AUX         VIA   -    MD0100PA00X+131009Y+025863X0200Y         S0      
317P3V3_AUX         VIA   -    MD0100PA00X+131809Y+025863X0200Y         S0      
317P3V3_AUX         VIA   -    MD0100PA00X+129409Y+025863X0200Y         S0      
317P3V3_AUX         VIA   -    MD0100PA00X+130209Y+025863X0200Y         S0      
317P3V3_AUX         VIA   -    MD0100PA00X+127809Y+025863X0200Y         S0      
317P3V3_AUX         VIA   -    MD0100PA00X+128609Y+025863X0200Y         S0      
317P3V3_AUX         VIA   -    MD0100PA00X+127009Y+025863X0200Y         S0      
317P3V3_AUX         VIA   -    MD0100PA00X+126209Y+025863X0200Y         S0      
317P3V3_AUX         VIA   -    MD0100PA00X+125028Y+030331X0200Y         S0      
317P3V3_AUX         VIA   -    MD0100PA00X+125409Y+025863X0200Y         S0      
317P3V3_AUX         VIA   -    MD0100PA00X+122209Y+031422X0200Y    R090 S0      
317P3V3_AUX         VIA   -    MD0100PA00X+123009Y+025863X0200Y         S0      
317P3V3_AUX         VIA   -    MD0100PA00X+122209Y+025863X0200Y         S0      
317P3V3_AUX         VIA   -    MD0100PA00X+063716Y+040545X0200Y         S0      
317P3V3_AUX         VIA   -    MD0100PA00X+179344Y+017808X0200Y    R180 S0      
327P3V3_AUX         PR831 -2          A01X+179701Y+018057X0198Y0197R270 S1      
327P3V3_AUX         PC569 -2   M      A01X+179344Y+018057X0198Y0197R270 S1      
317P3V3_AUX         VIA   -    MD0100PA00X+178093Y+017941X0200Y    R180 S0      
327P3V3_AUX         PR836 -2          A01X+178093Y+018246X0198Y0197R180 S1      
317P3V3_AUX         VIA   -    MD0100PA00X+175502Y+026679X0200Y    R180 S0      
317P3V3_AUX         VIA   -    MD0100PA00X+175502Y+026979X0200Y    R180 S0      
317P3V3_AUX         VIA   -    MD0100PA00X+175802Y+026679X0200Y    R180 S0      
317P3V3_AUX         VIA   -    MD0100PA00X+175802Y+026979X0200Y    R180 S0      
317P3V3_AUX         VIA   -    MD0100PA00X+175202Y+026679X0200Y    R180 S0      
317P3V3_AUX         VIA   -    MD0100PA00X+175202Y+026979X0200Y    R180 S0      
327P3V3_AUX         C60   -1          A01X+175797Y+026243X0400Y0500R090 S1      
327P3V3_AUX         C1333 -1          A01X+176507Y+026253X0400Y0500R090 S1      
327P3V3_AUX         C1332 -1          A01X+175198Y+026121X0198Y0197R270 S1      
327P3V3_AUX         Q56   -5          A01X+173807Y+027140X1850Y1811R180 S1      
317P3V3_AUX         PC1866-1   MD0400PA00X+180000Y+028493X0600Y0600R180 S3      
317P3V3_AUX         VIA   -    MD0100PA00X+175277Y+028186X0200Y    R180 S0      
317P3V3_AUX         VIA   -    MD0100PA00X+175277Y+027886X0200Y    R180 S0      
317P3V3_AUX         VIA   -    MD0100PA00X+176457Y+026966X0200Y    R180 S0      
317P3V3_AUX         VIA   -    MD0100PA00X+176157Y+026966X0200Y    R180 S0      
317P3V3_AUX         VIA   -    MD0100PA00X+176177Y+028186X0200Y    R180 S0      
317P3V3_AUX         VIA   -    MD0100PA00X+175877Y+028186X0200Y    R180 S0      
317P3V3_AUX         VIA   -    MD0100PA00X+175577Y+028186X0200Y    R180 S0      
317P3V3_AUX         VIA   -    MD0100PA00X+177563Y+026417X0200Y    R090 S0      
317P3V3_AUX         VIA   -    MD0100PA00X+177563Y+026667X0200Y         S0      
317P3V3_AUX         VIA   -    MD0100PA00X+177563Y+026917X0200Y         S0      
317P3V3_AUX         VIA   -    MD0100PA00X+176457Y+026666X0200Y    R180 S0      
317P3V3_AUX         VIA   -    MD0100PA00X+176157Y+026666X0200Y    R180 S0      
317P3V3_AUX         VIA   -    MD0100PA00X+177563Y+027167X0200Y         S0      
317P3V3_AUX         VIA   -    MD0100PA00X+176177Y+027886X0200Y    R180 S0      
317P3V3_AUX         VIA   -    MD0100PA00X+175877Y+027886X0200Y    R180 S0      
317P3V3_AUX         VIA   -    MD0100PA00X+175577Y+027886X0200Y    R180 S0      
317P3V3_AUX         VIA   -    MD0100PA00X+180760Y+026913X0200Y         S0      
317P3V3_AUX         VIA   -    MD0100PA00X+180760Y+026663X0200Y         S0      
317P3V3_AUX         VIA   -    MD0100PA00X+180760Y+026413X0200Y    R090 S0      
317P3V3_AUX         VIA   -    MD0100PA00X+180760Y+027163X0200Y         S0      
317P3V3_AUX         VIA   -    MD0100PA00X+180117Y+027450X0200Y    R090 S0      
317P3V3_AUX         VIA   -    MD0100PA00X+179767Y+027450X0200Y    R090 S0      
327P3V3_AUX         PL8066-2          A01X+179580Y+026653X1280Y1970R090 S1      
317P3V3_AUX         VIA   -    MD0100PA00X+178390Y+026913X0200Y         S0      
317P3V3_AUX         VIA   -    MD0100PA00X+178390Y+026663X0200Y         S0      
317P3V3_AUX         VIA   -    MD0100PA00X+178390Y+027163X0200Y         S0      
317P3V3_AUX         VIA   -    MD0100PA00X+179067Y+027450X0200Y    R090 S0      
317P3V3_AUX         VIA   -    MD0100PA00X+179417Y+027450X0200Y    R090 S0      
317P3V3_AUX         VIA   -    MD0100PA00X+177880Y+026413X0200Y    R090 S0      
317P3V3_AUX         VIA   -    MD0100PA00X+177880Y+026913X0200Y         S0      
317P3V3_AUX         VIA   -    MD0100PA00X+177880Y+026663X0200Y         S0      
317P3V3_AUX         VIA   -    MD0100PA00X+177880Y+027163X0200Y         S0      
317P3V3_AUX         VIA   -    MD0100PA00X+176757Y+026966X0200Y    R180 S0      
317P3V3_AUX         VIA   -    MD0100PA00X+177563Y+026167X0200Y    R090 S0      
317P3V3_AUX         VIA   -    MD0100PA00X+176757Y+026666X0200Y    R180 S0      
317P3V3_AUX         VIA   -    MD0100PA00X+177880Y+026163X0200Y    R090 S0      
317P3V3_AUX         PC1867-1   MD0400PA00X+177044Y+028493X0600Y0600R180 S3      
327P3V3_AUX         R3623 -1          A01X+059095Y+022528X0198Y0197     S1      
327P3V3_AUX         R3621 -1          A01X+059095Y+021728X0198Y0197     S1      
327P3V3_AUX         U222  -14         A18X+081250Y+031186X0140Y0590R090 S2      
327P3V3_AUX         U67   -14         A18X+076498Y+031158X0140Y0590R090 S2      
317P3V3_AUX         VIA   -    MD0100PA00X+025469Y+037852X0200Y         S0      
317P3V3_AUX         VIA   -    MD0100PA00X+025019Y+037852X0200Y         S0      
317P3V3_AUX         VIA   -    MD0100PA00X+024769Y+037852X0200Y         S0      
317P3V3_AUX         VIA   -    MD0100PA00X+083750Y+022964X0200Y         S0      
327P3V3_AUX         R4093 -1          A18X+083750Y+022623X0198Y0197R090 S2      
317P3V3_AUX         VIA   -    MD0100PA00X+062046Y+021928X0200Y         S0      
327P3V3_AUX         U264  -9          A01X+061574Y+022192X0090Y0240R270 S1      
327P3V3_AUX         C2013 -1   M      A01X+062045Y+022178X0198Y0197     S1      
327P3V3_AUX         R3708 -1   M      A01X+100076Y+049968X0198Y0197     S1      
317P3V3_AUX         VIA   -    MD0100PA00X+099833Y+049968X0200Y         S0      
327P3V3_AUX         R3706 -1   M      A01X+100076Y+049418X0198Y0197     S1      
327P3V3_AUX         R3705 -1          A01X+100076Y+049018X0198Y0197     S1      
327P3V3_AUX         R318  -1          A01X+109036Y+048964X0198Y0197     S1      
317P3V3_AUX         VIA   -    MD0100PA00X+108796Y+048964X0200Y         S0      
327P3V3_AUX         R320  -1          A01X+109036Y+049464X0198Y0197     S1      
317P3V3_AUX         VIA   -    MD0100PA00X+108796Y+049464X0200Y         S0      
327P3V3_AUX         R1822 -1          A01X+109036Y+048460X0198Y0197     S1      
317P3V3_AUX         VIA   -    MD0100PA00X+108796Y+048460X0200Y         S0      
317P3V3_AUX         VIA   -    MD0100PA00X+108042Y+048778X0200Y         S0      
327P3V3_AUX         R4270 -1          A01X+107778Y+048778X0198Y0197R180 S1      
317P3V3_AUX         VIA   -    MD0100PA00X+105590Y+049254X0200Y    R270 S0      
327P3V3_AUX         U39   -24         A01X+105108Y+048339X0120Y0630R270 S1      
327P3V3_AUX         C2056 -1   M      A01X+105590Y+049004X0198Y0197     S1      
327P3V3_AUX         R3724 -1          A01X+100076Y+048468X0198Y0197     S1      
317P3V3_AUX         VIA   -    MD0100PA00X+099836Y+048468X0200Y         S0      
327P3V3_AUX         R3583 -1          A01X+109036Y+046810X0198Y0197     S1      
317P3V3_AUX         VIA   -    MD0100PA00X+108796Y+046810X0200Y         S0      
317P3V3_AUX         VIA   -    MD0100PA00X+107147Y+047552X0200Y         S0      
327P3V3_AUX         R3703 -1          A01X+106887Y+047552X0198Y0197R180 S1      
317P3V3_AUX         VIA   -    MD0100PA00X+108042Y+048277X0200Y         S0      
327P3V3_AUX         R4269 -1          A01X+107778Y+048378X0198Y0197R180 S1      
327P3V3_AUX         R3726 -1          A01X+100076Y+047368X0198Y0197     S1      
317P3V3_AUX         VIA   -    MD0100PA00X+099836Y+047368X0200Y         S0      
327P3V3_AUX         R3725 -1          A01X+100076Y+046818X0198Y0197     S1      
317P3V3_AUX         VIA   -    MD0100PA00X+099836Y+046818X0200Y         S0      
327P3V3_AUX         R3723 -1          A01X+100076Y+047918X0198Y0197     S1      
317P3V3_AUX         VIA   -    MD0100PA00X+099836Y+047918X0200Y         S0      
327P3V3_AUX         R638  -2          A01X+065642Y+046986X0198Y0197R180 S1      
327P3V3_AUX         R639  -2   M      A01X+065642Y+047386X0198Y0197R180 S1      
317P3V3_AUX         VIA   -    MD0100PA00X+065401Y+047386X0200Y         S0      
327P3V3_AUX         R890  -1          A18X+065642Y+046586X0198Y0197R180 S2      
317P3V3_AUX         VIA   -    MD0100PA00X+065400Y+046582X0200Y         S0      
327P3V3_AUX         R4620 -1          A01X+059045Y+047963X0198Y0197     S1      
317P3V3_AUX         VIA   -    MD0100PA00X+058780Y+047963X0200Y         S0      
327P3V3_AUX         R1089 -1          A01X+109036Y+045160X0198Y0197     S1      
317P3V3_AUX         VIA   -    MD0100PA00X+108794Y+045211X0200Y         S0      
327P3V3_AUX         R1090 -1          A01X+109036Y+045710X0198Y0197     S1      
317P3V3_AUX         VIA   -    MD0100PA00X+108796Y+045710X0200Y         S0      
327P3V3_AUX         R3582 -1          A01X+109036Y+046260X0198Y0197     S1      
317P3V3_AUX         VIA   -    MD0100PA00X+108796Y+046260X0200Y         S0      
317P3V3_AUX         VIA   -    MD0100PA00X+106274Y+045796X0200Y         S0      
327P3V3_AUX         R3732 -1          A01X+106567Y+044550X0198Y0197     S1      
317P3V3_AUX         VIA   -    MD0100PA00X+106264Y+044486X0200Y         S0      
327P3V3_AUX         R3727 -1          A01X+100076Y+045718X0198Y0197     S1      
317P3V3_AUX         VIA   -    MD0100PA00X+099836Y+045718X0200Y         S0      
327P3V3_AUX         R3728 -1          A01X+100076Y+046268X0198Y0197     S1      
317P3V3_AUX         VIA   -    MD0100PA00X+099836Y+046268X0200Y         S0      
327P3V3_AUX         R993  -2          A18X+065636Y+045388X0198Y0197     S2      
327P3V3_AUX         R888  -1          A18X+065642Y+045786X0198Y0197R180 S2      
317P3V3_AUX         VIA   -    MD0100PA00X+065345Y+045854X0200Y         S0      
327P3V3_AUX         R2233 -1          A01X+063323Y+046144X0198Y0197R180 S1      
317P3V3_AUX         VIA   -    MD0100PA00X+063569Y+046144X0200Y         S0      
327P3V3_AUX         R2230 -1   M      A01X+059055Y+045846X0198Y0197     S1      
317P3V3_AUX         VIA   -    MD0100PA00X+059253Y+046156X0200Y         S0      
327P3V3_AUX         R3536 -1          A01X+109036Y+044610X0198Y0197     S1      
317P3V3_AUX         VIA   -    MD0100PA00X+108796Y+044610X0200Y         S0      
327P3V3_AUX         R3535 -1          A01X+109036Y+044060X0198Y0197     S1      
317P3V3_AUX         VIA   -    MD0100PA00X+108796Y+044060X0200Y         S0      
327P3V3_AUX         R3730 -1   M      A01X+100076Y+045168X0198Y0197     S1      
317P3V3_AUX         VIA   -    M      A01X+099836Y+045168X0200Y         S2      
017P3V3_AUX         VIA   -    M      A18X+099836Y+045168X0260Y         S2      
017P3V3_AUX               -    MD0100PA00X+099836Y+045168                       
327P3V3_AUX         R3729 -1          A01X+100076Y+044618X0198Y0197     S1      
327P3V3_AUX         R1314 -2          A01X+078958Y+044734X0198Y0197R180 S1      
317P3V3_AUX         VIA   -    MD0100PA00X+078620Y+044705X0200Y         S0      
327P3V3_AUX         R64   -2          A01X+065642Y+045386X0198Y0197R180 S1      
317P3V3_AUX         VIA   -    MD0100PA00X+065444Y+044962X0200Y         S0      
317P3V3_AUX         VIA   -    MD0100PA00X+063950Y+044236X0200Y         S0      
327P3V3_AUX         R1071 -2          A01X+064292Y+044236X0198Y0197R180 S1      
317P3V3_AUX         VIA   -    MD0100PA00X+105780Y+042962X0200Y    R180 S0      
327P3V3_AUX         U148  -8          A01X+106247Y+042962X0140Y0630R090 S1      
317P3V3_AUX         VIA   -    MD0100PA00X+105780Y+042706X0200Y    R180 S0      
327P3V3_AUX         U148  -7          A01X+106247Y+042706X0140Y0630R090 S1      
327P3V3_AUX         R3190 -1          A01X+101713Y+042590X0198Y0197R180 S1      
317P3V3_AUX         VIA   -    MD0100PA00X+102075Y+042590X0200Y         S0      
317P3V3_AUX         VIA   -    MD0100PA00X+100365Y+043343X0200Y         S0      
327P3V3_AUX         U218  -5          A01X+100213Y+042837X0220Y0320R270 S1      
327P3V3_AUX         C1823 -1   M      A01X+100713Y+043343X0198Y0197     S1      
317P3V3_AUX         VIA   -    MD0100PA00X+063921Y+043386X0200Y         S0      
327P3V3_AUX         R1195 -2          A01X+064292Y+043386X0198Y0197R180 S1      
317P3V3_AUX         VIA   -    MD0100PA00X+105250Y+040658X0200Y         S0      
327P3V3_AUX         U148  -1          A01X+106247Y+041170X0140Y0630R090 S1      
327P3V3_AUX         U148  -2          A01X+106247Y+041426X0140Y0630R090 S1      
327P3V3_AUX         C1506 -1          A01X+105494Y+040656X0198Y0197     S1      
327P3V3_AUX         U148  -16         A01X+104042Y+041170X0140Y0630R090 S1      
317P3V3_AUX         VIA   -    MD0100PA00X+103486Y+041170X0200Y         S0      
327P3V3_AUX         R1185 -2          A01X+077608Y+041534X0198Y0197R180 S1      
317P3V3_AUX         VIA   -    MD0100PA00X+077318Y+041520X0200Y         S0      
317P3V3_AUX         VIA   -    MD0100PA00X+061798Y+040735X0200Y    R090 S0      
327P3V3_AUX         C1873 -1   M      A01X+061538Y+040685X0198Y0197R090 S1      
327P3V3_AUX         U239  -5          A01X+061072Y+040685X0170Y0240R270 S1      
317P3V3_AUX         VIA   -    MD0100PA00X+058872Y+041585X0200Y    R090 S0      
327P3V3_AUX         R3298 -1          A01X+058620Y+041585X0198Y0197R180 S1      
327P3V3_AUX         R3296 -1          A01X+055310Y+041427X0198Y0197     S1      
317P3V3_AUX         VIA   -    MD0100PA00X+055057Y+041427X0200Y    R270 S0      
327P3V3_AUX         R1304 -2          A18X+076350Y+039329X0198Y0197R090 S2      
317P3V3_AUX         VIA   -    MD0100PA00X+076350Y+039086X0200Y    R090 S0      
317P3V3_AUX         VIA   -    MD0100PA00X+058198Y+040116X0200Y    R090 S0      
327P3V3_AUX         U259  -5          A01X+057378Y+040116X0140Y0440R270 S1      
327P3V3_AUX         C2007 -1   M      A01X+057938Y+040116X0198Y0197R090 S1      
327P3V3_AUX         R2121 -1          A01X+055310Y+039959X0198Y0197     S1      
317P3V3_AUX         VIA   -    MD0100PA00X+055057Y+039959X0200Y    R270 S0      
327P3V3_AUX         R6062 -2          A18X+076750Y+038079X0198Y0197R090 S2      
317P3V3_AUX         VIA   -    MD0100PA00X+077000Y+038079X0200Y         S0      
327P3V3_AUX         U244  -5          A01X+060978Y+037643X0140Y0440R270 S1      
317P3V3_AUX         VIA   -    MD0100PA00X+061798Y+037643X0200Y    R090 S0      
327P3V3_AUX         C1878 -1   M      A01X+061538Y+037643X0198Y0197R090 S1      
327P3V3_AUX         U243  -5          A01X+060978Y+038723X0140Y0440R270 S1      
317P3V3_AUX         VIA   -    MD0100PA00X+061798Y+038723X0200Y    R090 S0      
327P3V3_AUX         C1877 -1   M      A01X+061538Y+038723X0198Y0197R090 S1      
327P3V3_AUX         C1879 -1   M      A01X+057938Y+037643X0198Y0197R090 S1      
317P3V3_AUX         VIA   -    MD0100PA00X+058198Y+037643X0200Y    R090 S0      
327P3V3_AUX         U245  -5          A01X+057378Y+037643X0140Y0440R270 S1      
327P3V3_AUX         U246  -5          A01X+057378Y+038723X0140Y0440R270 S1      
327P3V3_AUX         C1880 -1   M      A01X+057938Y+038723X0198Y0197R090 S1      
317P3V3_AUX         VIA   -    MD0100PA00X+058198Y+038723X0200Y    R090 S0      
327P3V3_AUX         R391  -1          A01X+075950Y+037679X0198Y0197R090 S1      
317P3V3_AUX         VIA   -    MD0100PA00X+075965Y+037436X0200Y         S0      
317P3V3_AUX         VIA   -    MD0100PA00X+074350Y+037436X0200Y         S0      
327P3V3_AUX         R1303 -2          A01X+074350Y+037679X0198Y0197R270 S1      
317P3V3_AUX         VIA   -    MD0100PA00X+073141Y+037433X0200Y    R270 S0      
327P3V3_AUX         R1187 -2          A01X+073141Y+037676X0198Y0197R270 S1      
327P3V3_AUX         R397  -1          A01X+073545Y+037510X0198Y0197R270 S1      
317P3V3_AUX         VIA   -    MD0100PA00X+025486Y+037539X0200Y         S0      
317P3V3_AUX         VIA   -    MD0100PA00X+025036Y+037539X0200Y         S0      
317P3V3_AUX         VIA   -    MD0100PA00X+024786Y+037539X0200Y         S0      
317P3V3_AUX         VIA   -    MD0100PA00X+011841Y+052677X0200Y    R270 S0      
327P3V3_AUX         U248  -5          A01X+012381Y+052437X0400Y0150R180 S1      
327P3V3_AUX         C1882 -1   M      A01X+011841Y+052437X0198Y0197R270 S1      
327P3V3_AUX         C640  -1   M      A18X+075704Y+031418X0198Y0197R270 S2      
317P3V3_AUX         VIA   -    MD0100PA00X+075072Y+031991X0200Y         S0      
317P3V3_AUX         VIA   -    MD0100PA00X+158629Y+030360X0200Y    R270 S0      
327P3V3_AUX         C1860 -1   M      A01X+158880Y+030360X0198Y0197R090 S1      
327P3V3_AUX         U236  -1          A01X+159454Y+030360X0240Y0460R090 S1      
327P3V3_AUX         C1826 -1   M      A18X+080424Y+031277X0198Y0197     S2      
317P3V3_AUX         VIA   -    MD0100PA00X+080646Y+031061X0200Y         S0      
327P3V3_AUX         R2125 -1          A01X+103098Y+028731X0198Y0197R180 S1      
317P3V3_AUX         VIA   -    MD0100PA00X+103359Y+028731X0200Y         S0      
327P3V3_AUX         R3773 -1          A01X+103098Y+029831X0198Y0197R180 S1      
317P3V3_AUX         VIA   -    MD0100PA00X+103359Y+029831X0200Y         S0      
327P3V3_AUX         U134  -5          A01X+100517Y+029308X0170Y0240R270 S1      
317P3V3_AUX         VIA   -    MD0100PA00X+101784Y+029124X0200Y         S0      
327P3V3_AUX         C1592 -1   M      A01X+101533Y+029124X0198Y0197R090 S1      
317P3V3_AUX         VIA   -    MD0100PA00X+087251Y+030227X0200Y         S0      
317P3V3_AUX         VIA   -    MD0100PA00X+087001Y+030227X0200Y         S0      
317P3V3_AUX         VIA   -    MD0100PA00X+087317Y+029548X0200Y         S0      
317P3V3_AUX         VIA   -    MD0100PA00X+087067Y+029548X0200Y         S0      
317P3V3_AUX         VIA   -    MD0100PA00X+087424Y+028705X0200Y         S0      
327P3V3_AUX         PR3967-1          A01X+086757Y+029696X0198Y0197R270 S1      
327P3V3_AUX         PC2208-1          A01X+086357Y+029696X0198Y0197R270 S1      
327P3V3_AUX         PU295 -A5         A01X+087528Y+028197X0090Y         S1      
327P3V3_AUX         PU295 -B5         A01X+087528Y+028000X0090Y         S1      
327P3V3_AUX         PU295 -C5         A01X+087528Y+027803X0090Y         S1      
327P3V3_AUX         PU295 -D5         A01X+087528Y+027606X0090Y         S1      
327P3V3_AUX         PU295 -A3         A01X+087134Y+028197X0090Y         S1      
327P3V3_AUX         PU295 -B3         A01X+087134Y+028000X0090Y         S1      
327P3V3_AUX         PU295 -C3         A01X+087134Y+027803X0090Y         S1      
317P3V3_AUX         VIA   -    MD0100PA00X+081983Y+028806X0200Y         S0      
327P3V3_AUX         U7    -14         A18X+081858Y+028142X0140Y0590R090 S2      
327P3V3_AUX         C641  -1   M      A18X+082300Y+028806X0198Y0197R180 S2      
317P3V3_AUX         VIA   -    MD0100PA00X+036967Y+029461X0200Y    R270 S0      
317P3V3_AUX         VIA   -    MD0100PA00X+036967Y+029211X0200Y    R270 S0      
317P3V3_AUX         VIA   -    MD0100PA00X+036917Y+029711X0200Y         S0      
327P3V3_AUX         PU207 -1_2        A01X+036659Y+028735X0295Y0354     S1      
327P3V3_AUX         PC2169-1          A01X+036598Y+029403X0198Y0197R180 S1      
317P3V3_AUX         VIA   -    MD0100PA00X+036667Y+029711X0200Y         S0      
327P3V3_AUX         R3979 -1          A01X+088650Y+027448X0198Y0197R270 S1      
317P3V3_AUX         VIA   -    MD0100PA00X+088400Y+027448X0200Y         S0      
327P3V3_AUX         R3977 -1          A01X+088650Y+027871X0198Y0197R090 S1      
317P3V3_AUX         VIA   -    MD0100PA00X+088400Y+027871X0200Y         S0      
327P3V3_AUX         PU293 -1_2        A01X+077377Y+027480X0295Y0354     S1      
327P3V3_AUX         PC2200-1          A01X+077377Y+028125X0198Y0197R090 S1      
317P3V3_AUX         VIA   -    MD0100PA00X+076346Y+028184X0200Y         S0      
317P3V3_AUX         VIA   -    MD0100PA00X+076351Y+028440X0200Y         S0      
317P3V3_AUX         VIA   -    MD0100PA00X+076338Y+027923X0200Y         S0      
317P3V3_AUX         VIA   -    MD0100PA00X+076107Y+028036X0200Y         S0      
317P3V3_AUX         VIA   -    MD0100PA00X+085362Y+026906X0200Y         S0      
327P3V3_AUX         PR3963-1          A01X+085623Y+026906X0198Y0197     S1      
317P3V3_AUX         VIA   -    MD0100PA00X+053922Y+024527X0200Y         S0      
327P3V3_AUX         C194  -1   M      A01X+053618Y+024363X0198Y0197R090 S1      
317P3V3_AUX         VIA   -    MD0100PA00X+165442Y+022991X0200Y    R090 S0      
327P3V3_AUX         C1874 -1   M      A01X+165191Y+022991X0198Y0197R090 S1      
327P3V3_AUX         U240  -8          A01X+164680Y+022991X0200Y0340R270 S1      
317P3V3_AUX         VIA   -    MD0100PA00X+054925Y+023415X0200Y         S0      
327P3V3_AUX         R1728 -1          A01X+054656Y+023556X0198Y0197R180 S1      
327P3V3_AUX         R1744 -1          A01X+055451Y+023957X0198Y0197R180 S1      
317P3V3_AUX         VIA   -    MD0100PA00X+055557Y+023697X0200Y         S0      
327P3V3_AUX         R1727 -1          A01X+049446Y+023812X0198Y0197     S1      
317P3V3_AUX         VIA   -    MD0100PA00X+049158Y+023812X0200Y    R180 S0      
327P3V3_AUX         R1745 -1          A01X+048611Y+023300X0198Y0197     S1      
317P3V3_AUX         VIA   -    MD0100PA00X+048323Y+023300X0200Y    R180 S0      
327P3V3_AUX         R1747 -1          A01X+046582Y+024776X0198Y0197     S1      
317P3V3_AUX         VIA   -    MD0100PA00X+046324Y+024498X0200Y    R180 S0      
327P3V3_AUX         R1734 -1          A01X+046897Y+023576X0198Y0197R180 S1      
317P3V3_AUX         VIA   -    MD0100PA00X+047137Y+023576X0200Y         S0      
317P3V3_AUX         VIA   -    MD0100PA00X+046062Y+024095X0200Y         S0      
327P3V3_AUX         R1731 -1          A01X+041436Y+023544X0198Y0197     S1      
317P3V3_AUX         VIA   -    MD0100PA00X+041194Y+023544X0200Y    R180 S0      
327P3V3_AUX         R1746 -1          A01X+041752Y+022632X0198Y0197R180 S1      
317P3V3_AUX         VIA   -    MD0100PA00X+042012Y+022632X0200Y         S0      
317P3V3_AUX         VIA   -    MD0100PA00X+038001Y+023962X0200Y         S0      
327P3V3_AUX         PR3795-1          A01X+037713Y+023962X0198Y0197R180 S1      
317P3V3_AUX         VIA   -    MD0100PA00X+034864Y+022918X0200Y         S0      
327P3V3_AUX         R3826 -1          A01X+034624Y+022918X0198Y0197R180 S1      
327P3V3_AUX         R178  -1          A01X+071330Y+022186X0198Y0197R180 S1      
317P3V3_AUX         VIA   -    MD0100PA00X+071702Y+022086X0200Y         S0      
317P3V3_AUX         VIA   -    MD0100PA00X+058855Y+022528X0200Y         S0      
317P3V3_AUX         VIA   -    MD0100PA00X+058855Y+021728X0200Y         S0      
327P3V3_AUX         R1659 -1          A01X+054341Y+021844X0198Y0197     S1      
317P3V3_AUX         VIA   -    MD0100PA00X+054070Y+021787X0200Y    R180 S0      
327P3V3_AUX         R1730 -1          A01X+046193Y+021510X0198Y0197R090 S1      
317P3V3_AUX         VIA   -    MD0100PA00X+046193Y+021270X0200Y    R270 S0      
327P3V3_AUX         PR3782-1          A01X+036574Y+021536X0198Y0197     S1      
327P3V3_AUX         PC2140-1          A01X+036574Y+021136X0198Y0197     S1      
317P3V3_AUX         VIA   -    MD0100PA00X+035867Y+022061X0200Y    R180 S0      
317P3V3_AUX         VIA   -    MD0100PA00X+036117Y+022061X0200Y    R180 S0      
327P3V3_AUX         PU200 -A3         A01X+036201Y+022670X0090Y    R180 S1      
327P3V3_AUX         PU200 -A5         A01X+035808Y+022670X0090Y    R180 S1      
327P3V3_AUX         PU200 -B3         A01X+036201Y+022867X0090Y    R180 S1      
327P3V3_AUX         PU200 -B5         A01X+035808Y+022867X0090Y    R180 S1      
327P3V3_AUX         PU200 -C3         A01X+036201Y+023064X0090Y    R180 S1      
327P3V3_AUX         PU200 -C5         A01X+035808Y+023064X0090Y    R180 S1      
327P3V3_AUX         PU200 -D5         A01X+035808Y+023261X0090Y    R180 S1      
317P3V3_AUX         VIA   -    MD0100PA00X+035862Y+022313X0200Y    R180 S0      
317P3V3_AUX         VIA   -    MD0100PA00X+036117Y+022311X0200Y    R180 S0      
317P3V3_AUX         VIA   -    MD0100PA00X+034411Y+022266X0200Y         S0      
327P3V3_AUX         R3833 -1          A01X+034314Y+022507X0198Y0197     S1      
327P3V3_AUX         C2015 -1   M      A01X+172550Y+037779X0198Y0197R090 S1      
327P3V3_AUX         U266  -9          A01X+172948Y+037334X0090Y0240R090 S1      
317P3V3_AUX         VIA   -    MD0100PA00X+172830Y+037779X0200Y         S0      
327P3V3_AUX         R4094 -1          A01X+176780Y+037245X0198Y0197R180 S1      
317P3V3_AUX         VIA   -    MD0100PA00X+177028Y+037245X0200Y         S0      
327P3V3_AUX         R3627 -1          A01X+175416Y+036805X0198Y0197R180 S1      
317P3V3_AUX         VIA   -    MD0100PA00X+175680Y+036805X0200Y         S0      
327P3V3_AUX         R3628 -1          A01X+175416Y+036405X0198Y0197R180 S1      
317P3V3_AUX         VIA   -    MD0100PA00X+175680Y+036405X0200Y         S0      
327P3V3_AUX         R4090 -1          A01X+059095Y+020899X0198Y0197     S1      
317P3V3_AUX         VIA   -    MD0100PA00X+058824Y+020899X0200Y         S0      
317P3V3_AUX         VIA   -    MD0100PA00X+061636Y+018223X0200Y    R180 S0      
327P3V3_AUX         R1700 -1          A01X+062131Y+017868X0198Y0197R270 S1      
327P3V3_AUX         C1305 -1   M      A01X+061636Y+017972X0198Y0197R180 S1      
327P3V3_AUX         R1396 -2          A01X+071328Y+015776X0198Y0197     S1      
317P3V3_AUX         VIA   -    MD0100PA00X+071028Y+016983X0200Y         S0      
327P3V3_AUX         R2487 -1          A01X+064230Y+015313X0198Y0197R270 S1      
317P3V3_AUX         VIA   -    MD0100PA00X+064111Y+015830X0200Y         S0      
327P3V3_AUX         R155  -1          A01X+064624Y+016605X0198Y0197     S1      
317P3V3_AUX         VIA   -    MD0100PA00X+064380Y+016605X0200Y         S0      
317P3V3_AUX         VIA   -    MD0100PA00X+056395Y+015749X0200Y    R270 S0      
327P3V3_AUX         U235  -1          A01X+057230Y+015749X0240Y0460R090 S1      
327P3V3_AUX         C1859 -1   M      A01X+056646Y+015749X0198Y0197R090 S1      
317P3V3_AUX         VIA   -    MD0100PA00X+037089Y+015525X0200Y    R180 S0      
327P3V3_AUX         R3184 -1          A01X+037089Y+015803X0198Y0197     S1      
327P3V3_AUX         U207  -5          A01X+033434Y+017117X0140Y0490     S1      
317P3V3_AUX         VIA   -    MD0100PA00X+033434Y+016258X0200Y         S0      
327P3V3_AUX         C1821 -1   M      A01X+033434Y+016517X0198Y0197     S1      
327P3V3_AUX         C1663 -1   M      A01X+063506Y+014307X0198Y0197R090 S1      
327P3V3_AUX         U157  -5          A01X+063491Y+013750X0220Y0320     S1      
317P3V3_AUX         VIA   -    MD0100PA00X+062553Y+014698X0200Y         S0      
317P3V3_AUX         VIA   -    MD0100PA00X+038635Y+013898X0200Y    R180 S0      
327P3V3_AUX         R3192 -1          A01X+039272Y+013898X0198Y0197     S1      
327P3V3_AUX         U217  -5          A01X+038416Y+015282X0170Y0240R090 S1      
327P3V3_AUX         U219  -5          A01X+038045Y+014264X0220Y0320R270 S1      
327P3V3_AUX         C1822 -1   M      A01X+037907Y+014908X0198Y0197R180 S1      
317P3V3_AUX         VIA   -    MD0100PA00X+038438Y+014736X0200Y         S0      
327P3V3_AUX         C1824 -1   M      A01X+038642Y+014294X0198Y0197     S1      
317P3V3_AUX         VIA   -    MD0100PA00X+029648Y+014920X0200Y         S0      
327P3V3_AUX         C2012 -1   M      A01X+029648Y+015170X0198Y0197     S1      
327P3V3_AUX         C38   -1   M      A01X+036362Y+013016X0198Y0197     S1      
317P3V3_AUX         VIA   -    MD0100PA00X+036362Y+012766X0200Y         S0      
327P3V3_AUX         R6136 -1          A01X+065635Y+045776X0198Y0197     S1      
327P3V3_AUX         R6137 -1          A01X+065636Y+046182X0198Y0197     S1      
327P3V3_AUX         R6186 -2   M      A01X+064245Y+040545X0198Y0197R180 S1      
327P3V3_AUX         R6188 -2          A01X+064250Y+040158X0198Y0197R180 S1      
327P3V3_AUX         C20   -1   M      A01X+060897Y+026001X0198Y0197R180 S1      
327P3V3_AUX         R6308 -1          A01X+043530Y+021765X0198Y0197R270 S1      
327P3V3_AUX         R6306 -1   M      A01X+043130Y+021765X0198Y0197R270 S1      
327P3V3_AUX         R6258 -1          A01X+047800Y+016370X0198Y0197R270 S1      
327P3V3_AUX         C6083 -1   M      A01X+044933Y+027091X0198Y0197     S1      
327P3V3_AUX         C1554 -1   M      A01X+045812Y+024095X0198Y0197R090 S1      
327P3V3_AUX         R945  -1          A01X+135220Y+009562X0198Y0197R270 S1      
317P3V3_AUX         VIA   -    MD0100PA00X+135220Y+009805X0200Y         S0      
317P3V3_AUX         VIA   -    MD0100PA00X+136011Y+009805X0200Y         S0      
327P3V3_AUX         R947  -1          A01X+136011Y+009562X0198Y0197R270 S1      
327P3V3_AUX         R946  -1          A01X+134820Y+009566X0198Y0197R270 S1      
317P3V3_AUX         VIA   -    MD0100PA00X+134820Y+009808X0200Y         S0      
317P3V3_AUX         VIA   -    MD0100PA00X+134140Y+009808X0200Y         S0      
327P3V3_AUX         R944  -1          A01X+134140Y+009566X0198Y0197R270 S1      
317P3V3_AUX         VIA   -    MD0100PA00X+133340Y+009808X0200Y         S0      
327P3V3_AUX         R1507 -1          A01X+133340Y+009566X0198Y0197R270 S1      
327P3V3_AUX         R131  -1          A01X+125947Y+009044X0198Y0197R270 S1      
317P3V3_AUX         VIA   -    MD0100PA00X+125947Y+009286X0200Y    R180 S0      
327P3V3_AUX         U99   -5          A01X+124656Y+009795X0220Y0530R270 S1      
327P3V3_AUX         C553  -1   M      A01X+125315Y+009795X0198Y0197R090 S1      
317P3V3_AUX         VIA   -    MD0100PA00X+125315Y+009552X0200Y    R180 S0      
327P3V3_AUX         R6018 -1          A01X+061826Y+010664X0198Y0197R270 S1      
317P3V3_AUX         VIA   -    MD0100PA00X+061577Y+010664X0200Y         S0      
317P3V3_AUX         VIA   -    MD0100PA00X+041040Y+010738X0200Y         S0      
317P3V3_AUX         VIA   -    MD0100PA00X+041050Y+010488X0200Y         S0      
327P3V3_AUX         L6003 -1          A18X+041517Y+010571X0440Y0540R090 S2      
317P3V3_AUX         VIA   -    MD0100PA00X+125315Y+008490X0200Y    R180 S0      
327P3V3_AUX         R1343 -1          A01X+125315Y+008732X0198Y0197R090 S1      
327P3V3_AUX         R1138 -1          A01X+084494Y+009018X0198Y0197R090 S1      
317P3V3_AUX         VIA   -    MD0100PA00X+084386Y+008771X0200Y         S0      
327P3V3_AUX         R6071 -1          A01X+058219Y+008310X0198Y0197R090 S1      
317P3V3_AUX         VIA   -    MD0100PA00X+058500Y+008250X0200Y         S0      
317P3V3_AUX         VIA   -    MD0100PA00X+133193Y+006694X0200Y         S0      
327P3V3_AUX         R948  -2          A01X+133193Y+006452X0198Y0197R090 S1      
327P3V3_AUX         R1266 -1          A01X+130811Y+006449X0198Y0197R270 S1      
317P3V3_AUX         VIA   -    MD0100PA00X+130811Y+006691X0200Y         S0      
317P3V3_AUX         VIA   -    MD0100PA00X+132002Y+006698X0200Y         S0      
327P3V3_AUX         R1444 -1          A01X+132002Y+006455X0198Y0197R270 S1      
327P3V3_AUX         R1194 -1          A01X+129620Y+006449X0198Y0197R270 S1      
317P3V3_AUX         VIA   -    MD0100PA00X+129620Y+006691X0200Y         S0      
327P3V3_AUX         C73   -1   M      A01X+116209Y+007394X0198Y0197R180 S1      
327P3V3_AUX         U271  -8          A01X+116935Y+006819X0240Y0520R270 S1      
317P3V3_AUX         VIA   -    MD0100PA00X+116209Y+007651X0200Y         S0      
327P3V3_AUX         R6036 -2          A18X+064067Y+007739X0198Y0197R090 S2      
317P3V3_AUX         VIA   -    MD0100PA00X+064067Y+007437X0200Y         S0      
327P3V3_AUX         R6037 -2          A18X+062750Y+007739X0198Y0197R090 S2      
317P3V3_AUX         VIA   -    MD0100PA00X+062750Y+007498X0200Y         S0      
317P3V3_AUX         VIA   -    MD0100PA00X+060335Y+007364X0200Y         S0      
327P3V3_AUX         R3227 -2          A18X+060233Y+006792X0198Y0197R270 S2      
327P3V3_AUX         R3226 -2   M      A18X+060626Y+006792X0198Y0197R270 S2      
327P3V3_AUX         R2999 -2          A18X+061682Y+006792X0198Y0197R270 S2      
327P3V3_AUX         R3004 -2   M      A18X+061032Y+006792X0198Y0197R270 S2      
327P3V3_AUX         R2213 -2          A18X+058944Y+007124X0198Y0197R270 S2      
327P3V3_AUX         R2212 -2   M      A18X+059444Y+007124X0198Y0197R270 S2      
327P3V3_AUX         R1546 -1          A18X+056733Y+006974X0198Y0197R090 S2      
317P3V3_AUX         VIA   -    MD0100PA00X+057956Y+007309X0200Y         S0      
327P3V3_AUX         R4200 -1          A01X+048885Y+006496X0198Y0197R180 S1      
317P3V3_AUX         VIA   -    MD0100PA00X+049185Y+006496X0200Y         S0      
327P3V3_AUX         C31   -1   M      A01X+046265Y+007002X0198Y0197     S1      
327P3V3_AUX         U273  -8          A01X+045613Y+007002X0240Y0520R270 S1      
317P3V3_AUX         VIA   -    MD0100PA00X+046265Y+007252X0200Y         S0      
327P3V3_AUX         R6273 -1          A01X+043367Y+007712X0198Y0197R090 S1      
317P3V3_AUX         VIA   -    M      A01X+043367Y+007396X0200Y         S2      
017P3V3_AUX         VIA   -    M      A18X+043367Y+007396X0260Y         S2      
017P3V3_AUX               -    MD0100PA00X+043367Y+007396                       
327P3V3_AUX         R3816 -1          A01X+032562Y+008117X0198Y0197R090 S1      
317P3V3_AUX         VIA   -    MD0100PA00X+032311Y+007694X0200Y         S0      
327P3V3_AUX         R3825 -1   M      A01X+032562Y+007694X0198Y0197R270 S1      
327P3V3_AUX         R53   -1          A01X+146483Y+006156X0198Y0197     S1      
317P3V3_AUX         VIA   -    MD0100PA00X+146483Y+005905X0200Y         S0      
327P3V3_AUX         C72   -1   M      A01X+145990Y+005841X0198Y0197R090 S1      
327P3V3_AUX         U104  -5          A01X+145482Y+006041X0220Y0320R270 S1      
327P3V3_AUX         R821  -1          A01X+143426Y+005532X0198Y0197R090 S1      
317P3V3_AUX         VIA   -    MD0100PA00X+143426Y+005289X0200Y         S0      
317P3V3_AUX         VIA   -    MD0100PA00X+134384Y+006691X0200Y         S0      
327P3V3_AUX         R950  -2          A01X+134384Y+006449X0198Y0197R090 S1      
327P3V3_AUX         R4204 -1          A01X+118176Y+006152X0198Y0197R180 S1      
317P3V3_AUX         VIA   -    MD0100PA00X+118419Y+006152X0200Y         S0      
317P3V3_AUX         VIA   -    MD0100PA00X+118419Y+005702X0200Y         S0      
327P3V3_AUX         R4188 -1          A01X+118178Y+005282X0198Y0197R180 S1      
327P3V3_AUX         R4196 -1   M      A01X+118176Y+005702X0198Y0197R180 S1      
327P3V3_AUX         R4209 -1          A01X+112666Y+005265X0198Y0197     S1      
317P3V3_AUX         VIA   -    MD0100PA00X+111968Y+005413X0200Y    R270 S0      
317P3V3_AUX         VIA   -    MD0100PA00X+082860Y+006175X0200Y         S0      
327P3V3_AUX         C1275 -1   M      A01X+083139Y+005863X0198Y0197     S1      
327P3V3_AUX         U90   -6          A01X+084260Y+005845X0140Y0590R180 S1      
327P3V3_AUX         R1384 -2          A18X+070248Y+005258X0198Y0197R090 S2      
317P3V3_AUX         VIA   -    MD0100PA00X+070248Y+004833X0200Y         S0      
327P3V3_AUX         R332  -2   M      A18X+068629Y+005576X0198Y0197R270 S2      
327P3V3_AUX         R1460 -2          A18X+068229Y+005440X0198Y0197R270 S2      
317P3V3_AUX         VIA   -    MD0100PA00X+068702Y+005836X0200Y         S0      
327P3V3_AUX         R1385 -2          A18X+069029Y+005476X0198Y0197R090 S2      
327P3V3_AUX         R329  -2          A18X+065098Y+006857X0198Y0197R180 S2      
317P3V3_AUX         VIA   -    MD0100PA00X+066547Y+005852X0200Y         S0      
327P3V3_AUX         R1386 -2          A18X+066286Y+005852X0198Y0197R270 S2      
317P3V3_AUX         VIA   -    MD0100PA00X+062469Y+005826X0200Y         S0      
327P3V3_AUX         R331  -2          A18X+062536Y+006517X0198Y0197R180 S2      
327P3V3_AUX         R330  -2          A18X+062212Y+005568X0198Y0197R180 S2      
317P3V3_AUX         VIA   -    MD0100PA00X+049185Y+006010X0200Y         S0      
327P3V3_AUX         R4192 -1          A01X+048896Y+006010X0198Y0197R180 S1      
317P3V3_AUX         VIA   -    MD0100PA00X+049185Y+005510X0200Y         S0      
327P3V3_AUX         R4184 -1          A01X+048912Y+005510X0198Y0197R180 S1      
317P3V3_AUX         VIA   -    MD0100PA00X+042498Y+005476X0200Y         S0      
327P3V3_AUX         R4208 -1          A01X+042258Y+005476X0198Y0197R180 S1      
327P3V3_AUX         R3242 -2          A18X+068062Y+003332X0198Y0197R270 S2      
327P3V3_AUX         R3243 -2          A18X+067496Y+003332X0198Y0197R270 S2      
317P3V3_AUX         VIA   -    MD0100PA00X+067748Y+003332X0200Y         S0      
327P3V3_AUX         R2205 -1          A18X+064315Y+003391X0198Y0197R270 S2      
317P3V3_AUX         VIA   -    MD0100PA00X+063849Y+003334X0200Y         S0      
327P3V3_AUX         R6034 -1          A18X+054635Y+003716X0198Y0197R090 S2      
317P3V3_AUX         VIA   -    MD0100PA00X+054635Y+003956X0200Y         S0      
317P3V3_AUX         VIA   -    MD0100PA00X+065792Y+003086X0200Y         S0      
327P3V3_AUX         R2204 -1          A18X+065629Y+003391X0198Y0197R270 S2      
327P3V3_AUX         R8165 -1          A01X+035358Y+057042X0198Y0197     S1      
317P3V3_AUX         VIA   -    MD0100PA00X+035116Y+057042X0200Y    R180 S0      
327P3V3_AUX         R8167 -1          A01X+035358Y+055522X0198Y0197R090 S1      
317P3V3_AUX         VIA   -    MD0100PA00X+035102Y+055490X0200Y    R180 S0      
327P3V3_AUX         R8009 -1          A01X+029782Y+058288X0198Y0197R090 S1      
327P3V3_AUX         PR397 -1          A18X+029732Y+058288X0198Y0197R270 S2      
317P3V3_AUX         VIA   -    MD0100PA00X+029782Y+058038X0200Y    R270 S0      
327P3V3_AUX         U47   -10         A18X+166104Y+168349X0130Y0250     S2      
327P3V3_AUX         C1071 -1   M      A18X+166112Y+168802X0120Y0150R180 S2      
327P3V3_AUX         U34   -5          A01X+033582Y+027774X0220Y0530R270 S1      
327P3V3_AUX         U31   -5          A01X+021222Y+015624X0220Y0320R270 S1      
327P3V3_AUX         U33   -5          A01X+038232Y+031124X0220Y0530R270 S1      
327P3V3_AUX         U9002 -5          A01X+085250Y+039556X0400Y0150     S1      
327P3V3_AUX         C9008 -1   M      A01X+085892Y+039550X0198Y0197     S1      
327P3V3_AUX         U9001 -5          A01X+084476Y+047672X0220Y0320     S1      
327P3V3_AUX         C1060 -1   M      A01X+083858Y+047500X0198Y0197R180 S1      
327P3V3_AUX         U28   -5          A01X+079755Y+038493X0220Y0530R270 S1      
327P3V3_AUX         C1059 -1   M      A01X+080548Y+038679X0198Y0197     S1      
327P3V3_AUX         U23   -5          A01X+059978Y+041776X0220Y0320R090 S1      
327P3V3_AUX         C9007 -1   M      A01X+060292Y+041200X0198Y0197     S1      
327P3V3_AUX         R6140 -1          A18X+064427Y+043952X0198Y0197R180 S2      
317P3V3_AUX         VIA   -    MD0100PA00X+027350Y+020750X0200Y         S0      
327P3V3_AUX         R1172 -1          A01X+027692Y+020700X0198Y0197     S1      
317P3V3_AUX         VIA   -    MD0100PA00X+025844Y+021400X0200Y         S0      
327P3V3_AUX         R1176 -1          A01X+026192Y+022150X0198Y0197     S1      
327P3V3_AUX         U35   -5          A01X+029274Y+022778X0220Y0320R180 S1      
317P3V3_AUX         VIA   -    MD0100PA00X+029000Y+022258X0200Y         S0      
327P3V3_AUX         C1064 -1   M      A01X+029300Y+022258X0198Y0197R270 S1      
327P3V3_AUX         C1865 -1          A18X+006444Y+165824X0198Y0197R270 S2      
327P3V3_AUX         C6010 -1          A18X+006193Y+164889X0400Y0500R180 S2      
327P3V3_AUX         C6009 -1          A18X+006100Y+165439X0198Y0197     S2      
327P3V3_AUX         L2    -1          A01X+039170Y+161682X0440Y0540R180 S1      
317P3V3_AUX         VIA   -    MD0100PA00X+038780Y+161480X0200Y         S0      
317P3V3_AUX         VIA   -    MD0100PA00X+038780Y+161730X0200Y         S0      
327P3V3_AUX         R560  -1          A01X+042850Y+163708X0198Y0197R270 S1      
317P3V3_AUX         VIA   -    MD0100PA00X+043100Y+164050X0200Y         S0      
327P3V3_AUX         R578  -1          A01X+040892Y+163700X0198Y0197     S1      
317P3V3_AUX         VIA   -    MD0100PA00X+040955Y+163361X0200Y         S0      
327P3V3_AUX         R3318 -1          A18X+021060Y+166448X0198Y0197     S2      
327P3V3_AUX         R3525 -1          A18X+045700Y+164708X0198Y0197R090 S2      
327P3V3_AUX         R3510 -1          A01X+044758Y+164756X0198Y0197R270 S1      
327P3V3_AUX         R3514 -1          A18X+041392Y+165750X0198Y0197R180 S2      
317P3V3_AUX         VIA   -    MD0100PA00X+047850Y+173350X0200Y         S0      
327P3V3_AUX         R3490 -1          A01X+047558Y+173350X0198Y0197R180 S1      
327P3V3_AUX         R3494 -1          A01X+047558Y+171050X0198Y0197R180 S1      
317P3V3_AUX         VIA   -    MD0100PA00X+047850Y+171050X0200Y         S0      
317P3V3_AUX         VIA   -    MD0100PA00X+046600Y+171458X0200Y         S0      
327P3V3_AUX         U257  -5          A01X+046998Y+172005X0170Y0240R180 S1      
327P3V3_AUX         C1979 -1   M      A01X+046850Y+171458X0198Y0197R270 S1      
327P3V3_AUX         R3448 -1          A01X+047558Y+169700X0198Y0197R180 S1      
317P3V3_AUX         VIA   -    MD0100PA00X+047850Y+169700X0200Y         S0      
327P3V3_AUX         R3451 -1          A01X+046542Y+169700X0198Y0197     S1      
317P3V3_AUX         VIA   -    MD0100PA00X+046250Y+169700X0200Y         S0      
317P3V3_AUX         VIA   -    MD0100PA00X+046750Y+167850X0200Y         S0      
327P3V3_AUX         U253  -5          A01X+047031Y+168474X0160Y0200R180 S1      
327P3V3_AUX         C1958 -1   M      A01X+046992Y+168000X0198Y0197     S1      
327P3V3_AUX         R8002 -1          A18X+041308Y+167250X0198Y0197     S2      
317P3V3_AUX         VIA   -    MD0100PA00X+041550Y+167250X0200Y         S0      
327P3V3_AUX         R3459 -1          A01X+041300Y+168058X0198Y0197R270 S1      
317P3V3_AUX         VIA   -    MD0100PA00X+041300Y+168350X0200Y         S0      
327P3V3_AUX         R3488 -1          A01X+040900Y+168058X0198Y0197R270 S1      
317P3V3_AUX         VIA   -    MD0100PA00X+040900Y+168350X0200Y         S0      
317P3V3_AUX         VIA   -    MD0100PA00X+039732Y+168050X0200Y         S0      
327P3V3_AUX         R4186 -1          A01X+039732Y+167807X0198Y0197R270 S1      
327P3V3_AUX         R8003 -1          A18X+038264Y+167787X0198Y0197R180 S2      
317P3V3_AUX         VIA   -    MD0100PA00X+038264Y+168098X0200Y         S0      
317P3V3_AUX         VIA   -    MD0100PA00X+039232Y+168050X0200Y         S0      
327P3V3_AUX         R4194 -1          A01X+039232Y+167807X0198Y0197R270 S1      
327P3V3_AUX         R4058 -1          A01X+038299Y+167802X0198Y0197R270 S1      
317P3V3_AUX         VIA   -    MD0100PA00X+038732Y+168050X0200Y         S0      
327P3V3_AUX         R4202 -1   M      A01X+038732Y+167807X0198Y0197R270 S1      
327P3V3_AUX         R3465 -1          A01X+047558Y+165950X0198Y0197R180 S1      
317P3V3_AUX         VIA   -    MD0100PA00X+047754Y+166146X0200Y         S0      
327P3V3_AUX         R3436 -1          A01X+046492Y+165950X0198Y0197     S1      
317P3V3_AUX         VIA   -    MD0100PA00X+046492Y+166250X0200Y         S0      
327P3V3_AUX         R3456 -1          A01X+046808Y+167200X0198Y0197R180 S1      
327P3V3_AUX         R3453 -1          A01X+047242Y+167200X0198Y0197     S1      
317P3V3_AUX         VIA   -    MD0100PA00X+047046Y+167004X0200Y         S0      
317P3V3_AUX         VIA   -    MD0100PA00X+041150Y+165750X0200Y         S0      
327P3V3_AUX         R3461 -1          A01X+041392Y+165750X0198Y0197     S1      
317P3V3_AUX         VIA   -    MD0100PA00X+042000Y+166492X0200Y         S0      
327P3V3_AUX         C1963 -1   M      A01X+041700Y+166492X0198Y0197R090 S1      
327P3V3_AUX         U255  -5          A01X+040900Y+166226X0170Y0240R180 S1      
317P3V3_AUX         VIA   -    MD0100PA00X+038212Y+166154X0200Y    R090 S0      
327P3V3_AUX         C32   -1   M      A01X+038482Y+166154X0198Y0197R090 S1      
327P3V3_AUX         R3030 -1          A01X+045700Y+164708X0198Y0197R270 S1      
317P3V3_AUX         VIA   -    MD0100PA00X+045700Y+165000X0200Y         S0      
327P3V3_AUX         R3434 -1          A01X+046500Y+165058X0198Y0197R270 S1      
317P3V3_AUX         VIA   -    MD0100PA00X+046750Y+165150X0200Y         S0      
327P3V3_AUX         R3504 -1          A18X+046119Y+163588X0198Y0197R270 S2      
317P3V3_AUX         VIA   -    MD0100PA00X+044600Y+165000X0200Y         S0      
327P3V3_AUX         R3029 -1          A01X+044359Y+164760X0198Y0197R270 S1      
327P3V3_AUX         R3503 -1          A18X+043692Y+164650X0198Y0197R180 S2      
317P3V3_AUX         VIA   -    MD0100PA00X+043692Y+164950X0200Y         S0      
327P3V3_AUX         R3034 -1          A18X+040850Y+164958X0198Y0197R090 S2      
317P3V3_AUX         VIA   -    MD0100PA00X+041145Y+165060X0200Y         S0      
327P3V3_AUX         R3492 -1          A01X+040908Y+164950X0198Y0197R180 S1      
327P3V3_AUX         R3035 -1          A18X+043200Y+164342X0198Y0197R270 S2      
327P3V3_AUX         R4545 -1          A18X+043692Y+164150X0198Y0197R180 S2      
317P3V3_AUX         VIA   -    MD0100PA00X+043450Y+164150X0200Y         S0      
327P3V3_AUX         R4543 -1          A18X+041200Y+163908X0198Y0197R090 S2      
317P3V3_AUX         VIA   -    MD0100PA00X+041450Y+163908X0200Y         S0      
317P3V3_AUX         VIA   -    MD0100PA00X+039782Y+162962X0200Y         S0      
327P3V3_AUX         R4210 -1          A01X+039900Y+162729X0198Y0197R270 S1      
327P3V3_AUX         R4546 -1          A18X+041164Y+162690X0198Y0197R090 S2      
317P3V3_AUX         VIA   -    MD0100PA00X+040886Y+162344X0200Y         S0      
327P3V3_AUX         C1957 -1   M      A01X+021100Y+171508X0198Y0197R270 S1      
327P3V3_AUX         U252  -5          A01X+020624Y+171500X0160Y0200R270 S1      
317P3V3_AUX         VIA   -    MD0100PA00X+021100Y+171768X0200Y         S0      
327P3V3_AUX         C1770 -1   M      A01X+019400Y+171808X0198Y0197R270 S1      
327P3V3_AUX         U196  -5          A01X+018924Y+171800X0160Y0200R270 S1      
317P3V3_AUX         VIA   -    MD0100PA00X+019400Y+172055X0200Y         S0      
317P3V3_AUX         VIA   -    MD0100PA00X+018576Y+173167X0200Y         S0      
327P3V3_AUX         R2912 -1          A01X+018576Y+172895X0198Y0197R270 S1      
317P3V3_AUX         VIA   -    MD0100PA00X+017192Y+171798X0200Y         S0      
327P3V3_AUX         R3506 -1          A01X+017192Y+171500X0198Y0197     S1      
327P3V3_AUX         R2936 -1          A01X+017192Y+172100X0198Y0197     S1      
327P3V3_AUX         C1977 -1   M      A01X+016750Y+171858X0198Y0197R270 S1      
327P3V3_AUX         U256  -5          A01X+016274Y+171850X0160Y0200R270 S1      
317P3V3_AUX         VIA   -    MD0100PA00X+016647Y+172097X0200Y         S0      
317P3V3_AUX         VIA   -    MD0100PA00X+015250Y+172294X0200Y         S0      
327P3V3_AUX         R2910 -1          A01X+014990Y+172294X0198Y0197R270 S1      
327P3V3_AUX         R3521 -1          A01X+014284Y+172224X0198Y0197R180 S1      
317P3V3_AUX         VIA   -    MD0100PA00X+014527Y+172224X0200Y    R180 S0      
317P3V3_AUX         VIA   -    MD0100PA00X+008250Y+172033X0200Y    R180 S0      
327P3V3_AUX         R3522 -1          A01X+008518Y+172033X0198Y0197     S1      
327P3V3_AUX         R3498 -1          A18X+020381Y+170899X0198Y0197R090 S2      
317P3V3_AUX         VIA   -    MD0100PA00X+019984Y+170984X0200Y         S0      
317P3V3_AUX         VIA   -    MD0100PA00X+018381Y+170540X0200Y         S0      
327P3V3_AUX         R3317 -1          A01X+018576Y+170731X0198Y0197R090 S1      
317P3V3_AUX         VIA   -    MD0100PA00X+015682Y+170551X0200Y         S0      
327P3V3_AUX         R2914 -1          A01X+015874Y+170742X0198Y0197R090 S1      
317P3V3_AUX         VIA   -    MD0100PA00X+012949Y+171185X0200Y         S0      
327P3V3_AUX         C1766 -1   M      A01X+012949Y+170935X0198Y0197     S1      
327P3V3_AUX         U194  -8          A01X+012011Y+170650X0140Y0560R270 S1      
327P3V3_AUX         R3524 -1          A01X+013989Y+170517X0198Y0197R180 S1      
317P3V3_AUX         VIA   -    MD0100PA00X+014229Y+170517X0200Y         S0      
317P3V3_AUX         VIA   -    MD0100PA00X+009534Y+171374X0200Y    R180 S0      
327P3V3_AUX         C1796 -1   M      A01X+009534Y+171624X0198Y0197R180 S1      
327P3V3_AUX         U200  -8          A01X+010258Y+171844X0140Y0560R090 S1      
327P3V3_AUX         R3523 -1          A01X+008534Y+170251X0198Y0197     S1      
317P3V3_AUX         VIA   -    MD0100PA00X+008294Y+170251X0200Y         S0      
327P3V3_AUX         R3439 -1          A18X+020781Y+169884X0198Y0197R270 S2      
317P3V3_AUX         VIA   -    MD0100PA00X+020781Y+169641X0200Y         S0      
327P3V3_AUX         R3487 -1          A18X+020781Y+169387X0198Y0197R090 S2      
327P3V3_AUX         R3474 -1          A18X+018252Y+169514X0198Y0197R090 S2      
317P3V3_AUX         VIA   -    MD0100PA00X+018517Y+169514X0200Y         S0      
327P3V3_AUX         R3432 -1          A18X+018252Y+169916X0198Y0197R270 S2      
317P3V3_AUX         VIA   -    MD0100PA00X+018000Y+169916X0200Y         S0      
317P3V3_AUX         VIA   -    MD0100PA00X+015535Y+168784X0200Y    R090 S0      
327P3V3_AUX         R3292 -1          A01X+015535Y+169051X0198Y0197R090 S1      
317P3V3_AUX         VIA   -    MD0100PA00X+014725Y+169634X0200Y    R180 S0      
327P3V3_AUX         R3286 -1          A01X+014725Y+169366X0198Y0197R270 S1      
317P3V3_AUX         VIA   -    MD0100PA00X+012735Y+169606X0200Y    R180 S0      
327P3V3_AUX         R3269 -1          A01X+012735Y+169366X0198Y0197R270 S1      
317P3V3_AUX         VIA   -    MD0100PA00X+012335Y+169594X0200Y    R180 S0      
327P3V3_AUX         R3280 -1          A01X+012335Y+169354X0198Y0197R270 S1      
327P3V3_AUX         R6165 -1          A01X+009013Y+168496X0198Y0197R270 S1      
317P3V3_AUX         VIA   -    MD0100PA00X+009013Y+168736X0200Y    R180 S0      
327P3V3_AUX         R6163 -1          A01X+008213Y+168496X0198Y0197R270 S1      
317P3V3_AUX         VIA   -    MD0100PA00X+008213Y+168736X0200Y    R180 S0      
327P3V3_AUX         R6169 -1          A01X+006613Y+168496X0198Y0197R270 S1      
317P3V3_AUX         VIA   -    MD0100PA00X+006613Y+168736X0200Y    R180 S0      
317P3V3_AUX         VIA   -    MD0100PA00X+020781Y+168130X0200Y         S0      
327P3V3_AUX         R3512 -1          A18X+020766Y+167875X0198Y0197R090 S2      
327P3V3_AUX         R3475 -1          A18X+020781Y+168372X0198Y0197R270 S2      
317P3V3_AUX         VIA   -    MD0100PA00X+011038Y+167431X0200Y    R180 S0      
327P3V3_AUX         R3283 -1          A01X+011278Y+167431X0198Y0197     S1      
327P3V3_AUX         R6167 -1          A01X+006220Y+168202X0198Y0197R180 S1      
317P3V3_AUX         VIA   -    MD0100PA00X+006220Y+168458X0200Y    R180 S0      
327P3V3_AUX         R2935 -1          A18X+020766Y+166860X0198Y0197R270 S2      
317P3V3_AUX         VIA   -    MD0100PA00X+021022Y+166860X0200Y         S0      
317P3V3_AUX         VIA   -    MD0100PA00X+018010Y+166892X0200Y         S0      
327P3V3_AUX         R2842 -1   M      A18X+018281Y+166892X0198Y0197R270 S2      
327P3V3_AUX         U237  -1          A01X+013977Y+166500X0070Y0240R090 S1      
317P3V3_AUX         VIA   -    MD0100PA00X+014246Y+166249X0200Y    R180 S0      
327P3V3_AUX         U237  -10         A01X+013977Y+167917X0070Y0240R090 S1      
327P3V3_AUX         C1864 -1   M      A01X+014378Y+168259X0198Y0197     S1      
317P3V3_AUX         VIA   -    MD0100PA00X+014378Y+168509X0200Y    R180 S0      
327P3V3_AUX         C1863 -1   M      A01X+012643Y+166109X0198Y0197R180 S1      
327P3V3_AUX         U237  -25         A01X+012993Y+166500X0070Y0240R270 S1      
317P3V3_AUX         VIA   -    MD0100PA00X+012643Y+165859X0200Y    R180 S0      
327P3V3_AUX         U237  -16         A01X+012993Y+167917X0070Y0240R270 S1      
327P3V3_AUX         C1866 -1   M      A18X+013010Y+168051X0198Y0197R180 S2      
317P3V3_AUX         VIA   -    MD0100PA00X+012676Y+168238X0200Y    R090 S0      
327P3V3_AUX         C1867 -1          A18X+014168Y+167233X0400Y0500R180 S2      
317P3V3_AUX         VIA   -    MD0100PA00X+011038Y+167031X0200Y    R180 S0      
327P3V3_AUX         R3277 -1          A01X+011278Y+167031X0198Y0197     S1      
327P3V3_AUX         R6171 -1   M      A01X+003535Y+166859X0198Y0197     S1      
327P3V3_AUX         R6173 -1          A01X+003535Y+166359X0198Y0197     S1      
317P3V3_AUX         VIA   -    MD0100PA00X+003293Y+166859X0200Y    R090 S0      
317P3V3_AUX         VIA   -    MD0100PA00X+021083Y+166087X0200Y         S0      
327P3V3_AUX         R3321 -1          A18X+021083Y+165819X0198Y0197     S2      
317P3V3_AUX         VIA   -    MD0100PA00X+015235Y+164661X0200Y    R180 S0      
327P3V3_AUX         R3266 -1          A01X+015235Y+164901X0198Y0197R090 S1      
317P3V3_AUX         VIA   -    MD0100PA00X+013635Y+164661X0200Y    R180 S0      
327P3V3_AUX         R3289 -1          A01X+013635Y+164901X0198Y0197R090 S1      
317P3V3_AUX         VIA   -    MD0100PA00X+013235Y+164661X0200Y    R180 S0      
327P3V3_AUX         R3275 -1          A01X+013235Y+164901X0198Y0197R090 S1      
317P3V3_AUX         VIA   -    MD0100PA00X+011235Y+164661X0200Y    R180 S0      
327P3V3_AUX         R3271 -1          A01X+011235Y+164901X0198Y0197R090 S1      
327P3V3_AUX         R6175 -1          A01X+007743Y+164681X0198Y0197R090 S1      
317P3V3_AUX         VIA   -    MD0100PA00X+007743Y+164441X0200Y    R090 S0      
327P3V3_AUX         R6177 -1          A01X+005543Y+164681X0198Y0197R090 S1      
317P3V3_AUX         VIA   -    MD0100PA00X+005682Y+164343X0200Y    R090 S0      
317P3V3_AUX         VIA   -    MD0100PA00X+006526Y+165294X0200Y    R090 S0      
317P3V3_AUX         VIA   -    MD0100PA00X+006193Y+164350X0200Y    R090 S0      
317P3V3_AUX         VIA   -    MD0100PA00X+006446Y+165562X0200Y    R090 S0      
327P3V3_AUX         U6000 -15         A01X+006446Y+165840X0098Y0236R180 S1      
317P3V3_AUX         VIA   -    MD0100PA00X+006443Y+164350X0200Y    R090 S0      
327P3V3_AUX         R6179 -1          A01X+006443Y+164681X0198Y0197R090 S1      
317P3V3_AUX         VIA   -    MD0100PA00X+003517Y+162940X0200Y    R090 S0      
317P3V3_AUX         VIA   -    MD0100PA00X+003517Y+162690X0200Y    R090 S0      
327P3V3_AUX         R663  -1          A01X+003806Y+162690X0198Y0197     S1      
317P3V3_AUX         VIA   -    MD0100PA00X+008483Y+161190X0200Y    R090 S0      
327P3V3_AUX         PR6812-1          A18X+008167Y+161198X0198Y0197R090 S2      
327P3V3_AUX         PR6818-1          A01X+008221Y+162540X0198Y0197R180 S1      
327P3V3_AUX         PR6804-1   M      A01X+008221Y+162090X0198Y0197R180 S1      
327P3V3_AUX         R665  -1   M      A01X+008221Y+161190X0198Y0197R180 S1      
327P3V3_AUX         PR6806-1   M      A01X+008221Y+161640X0198Y0197R180 S1      
327P3V3_AUX         R656  -1          A18X+006687Y+160122X0198Y0197R270 S2      
327P3V3_AUX         PR6538-2          A01X+003806Y+159440X0198Y0197R180 S1      
317P3V3_AUX         VIA   -    MD0100PA00X+003806Y+159140X0200Y    R090 S0      
327P3V3_AUX         R660  -1          A01X+006813Y+159032X0198Y0197R090 S1      
317P3V3_AUX         VIA   -    MD0100PA00X+006813Y+158790X0200Y         S0      
327P3V3_AUX         PR6620-1          A01X+004215Y+155366X0198Y0197R270 S1      
317P3V3_AUX         VIA   -    MD0100PA00X+004876Y+155930X0200Y         S0      
317P3V3_AUX         VIA   -    MD0100PA00X+044665Y+157326X0200Y         S0      
327P3V3_AUX         U42   -10         A01X+045429Y+157683X0130Y0250R180 S1      
327P3V3_AUX         C1069 -1          A01X+038446Y+159184X0120Y0150R090 S1      
317P3V3_AUX         VIA   -    MD0100PA00X+038161Y+159039X0200Y         S0      
327P3V3_AUX         U45   -10         A01X+038280Y+158753X0130Y0250     S1      
317P3V3_AUX         VIA   -    MD0100PA00X+044580Y+163600X0200Y    R180 S0      
317P3V3_AUX         VIA   -    MD0100PA00X+044580Y+163320X0200Y    R180 S0      
327P3V3_AUX         L1    -1          A01X+044174Y+163400X0440Y0540     S1      
327P3V3_AUX         R580  -1          A18X+044208Y+163000X0198Y0197     S2      
327P3V3_AUX         R3320 -1          A18X+018281Y+166507X0198Y0197R090 S2      
317P3V3_AUX         VIA   -    MD0100PA00X+144003Y+166794X0200Y    R090 S0      
327P3V3_AUX         C2010 -1   M      A01X+144258Y+166773X0198Y0197R090 S1      
327P3V3_AUX         U270  -8          A01X+144058Y+166120X0240Y0520     S1      
317P3V3_AUX         VIA   -    MD0100PA00X+145794Y+167571X0200Y         S0      
327P3V3_AUX         R4190 -1          A01X+146170Y+167096X0198Y0197R270 S1      
327P3V3_AUX         C1070 -1   M      A01X+148100Y+168195X0120Y0150R090 S1      
327P3V3_AUX         U46   -10         A01X+147627Y+167940X0130Y0250R270 S1      
317P3V3_AUX         VIA   -    MD0100PA00X+148280Y+168598X0200Y         S0      
317P3V3_AUX         VIA   -    MD0100PA00X+139960Y+165758X0200Y    R270 S0      
327P3V3_AUX         R2841 -1          A18X+139690Y+165758X0198Y0197R090 S2      
327P3V3_AUX         R9004 -1          A01X+143196Y+164709X0198Y0197R180 S1      
317P3V3_AUX         VIA   -    MD0100PA00X+143391Y+164904X0200Y         S0      
327P3V3_AUX         R4173 -1          A01X+142189Y+164697X0198Y0197R180 S1      
317P3V3_AUX         VIA   -    MD0100PA00X+142432Y+164697X0200Y    R270 S0      
317P3V3_AUX         VIA   -    MD0100PA00X+141032Y+164697X0200Y    R270 S0      
327P3V3_AUX         R4155 -1          A01X+140789Y+164697X0198Y0197R180 S1      
327P3V3_AUX         R2837 -1          A18X+140681Y+164972X0198Y0197R180 S2      
317P3V3_AUX         VIA   -    MD0100PA00X+140681Y+165244X0200Y         S0      
327P3V3_AUX         C1803 -1   M      A01X+141362Y+163777X0198Y0197R090 S1      
327P3V3_AUX         U204  -5          A01X+141362Y+163311X0170Y0240     S1      
317P3V3_AUX         VIA   -    MD0100PA00X+141111Y+163777X0200Y    R270 S0      
327P3V3_AUX         R4156 -1          A01X+140821Y+162617X0198Y0197R180 S1      
317P3V3_AUX         VIA   -    MD0100PA00X+140821Y+162865X0200Y         S0      
327P3V3_AUX         R4153 -1          A01X+139806Y+162617X0198Y0197     S1      
317P3V3_AUX         VIA   -    MD0100PA00X+139806Y+162865X0200Y         S0      
327P3V3_AUX         R2934 -1          A18X+140802Y+164140X0198Y0197R180 S2      
317P3V3_AUX         VIA   -    MD0100PA00X+140802Y+163870X0200Y         S0      
317P3V3_AUX         VIA   -    MD0100PA00X+145050Y+161450X0200Y         S0      
327P3V3_AUX         R4211 -1          A01X+145050Y+161742X0198Y0197R090 S1      
327P3V3_AUX         R9005 -1          A01X+143292Y+161957X0198Y0197     S1      
317P3V3_AUX         VIA   -    MD0100PA00X+143432Y+161691X0200Y         S0      
317P3V3_AUX         VIA   -    MD0100PA00X+141962Y+161600X0200Y    R180 S0      
327P3V3_AUX         R4515 -1          A01X+141962Y+161334X0198Y0197R270 S1      
327P3V3_AUX         R9014 -1          A01X+142372Y+161397X0198Y0197     S1      
327P3V3_AUX         R9002 -1          A01X+142372Y+161950X0198Y0197     S1      
317P3V3_AUX         VIA   -    MD0100PA00X+142372Y+161678X0200Y         S0      
327P3V3_AUX         R9017 -1          A01X+143273Y+160997X0198Y0197     S1      
317P3V3_AUX         VIA   -    MD0100PA00X+143024Y+160997X0200Y         S0      
327P3V3_AUX         R9016 -1          A01X+141562Y+160223X0198Y0197R270 S1      
317P3V3_AUX         VIA   -    MD0100PA00X+141247Y+160223X0200Y         S0      
327P3V3_AUX         C180  -1          A18X+081347Y+076376X0198Y0197     S2      
327P3V3_AUX         J37   -3          A01X+081200Y+076352X0205Y0590R090 S1      
317P3V3_AUX         VIA   -    MD0100PA00X+081650Y+076352X0190Y         S0      
327P3V3_AUX         C176  -1          A18X+078105Y+076377X0198Y0197     S2      
327P3V3_AUX         J99   -3          A01X+078230Y+076352X0205Y0590R090 S1      
317P3V3_AUX         VIA   -    MD0100PA00X+078680Y+076352X0190Y         S0      
327P3V3_AUX         C172  -1          A18X+075120Y+076377X0198Y0197     S2      
327P3V3_AUX         J29   -3          A01X+075260Y+076352X0205Y0590R090 S1      
317P3V3_AUX         VIA   -    MD0100PA00X+075710Y+076352X0190Y         S0      
327P3V3_AUX         C168  -1          A18X+072150Y+076377X0198Y0197     S2      
327P3V3_AUX         J100  -3          A01X+072290Y+076352X0205Y0590R090 S1      
317P3V3_AUX         VIA   -    MD0100PA00X+072740Y+076352X0190Y         S0      
327P3V3_AUX         C164  -1          A18X+069180Y+076377X0198Y0197     S2      
327P3V3_AUX         J27   -3          A01X+069320Y+076352X0205Y0590R090 S1      
317P3V3_AUX         VIA   -    MD0100PA00X+069770Y+076352X0190Y         S0      
327P3V3_AUX         C160  -1          A18X+066210Y+076377X0198Y0197     S2      
327P3V3_AUX         J102  -3          A01X+066350Y+076352X0205Y0590R090 S1      
317P3V3_AUX         VIA   -    MD0100PA00X+066800Y+076352X0190Y         S0      
327P3V3_AUX         U9051 -5          A01X+025016Y+021513X0220Y0320R270 S1      
327P3V3_AUX         C9051 -1   M      A01X+025527Y+021504X0198Y0197R270 S1      
327P3V3_AUX         U9050 -5          A01X+086142Y+040245X0220Y0320R090 S1      
327P3V3_AUX         C9050 -1   M      A01X+085578Y+040128X0198Y0197R180 S1      
317P3V3             VIA   -    MD0100PA00X+080041Y+076376X0190Y         S0      
327P3V3             R115  -1   M      A18X+080041Y+076376X0198Y0197     S2      
317P3V3             VIA   -    MD0100PA00X+077071Y+076377X0190Y         S0      
327P3V3             R114  -1   M      A18X+077071Y+076377X0198Y0197     S2      
317P3V3             VIA   -    MD0100PA00X+074101Y+076377X0190Y         S0      
327P3V3             R113  -1   M      A18X+074101Y+076377X0198Y0197     S2      
317P3V3             VIA   -    MD0100PA00X+071131Y+076377X0190Y         S0      
327P3V3             R112  -1   M      A18X+071131Y+076377X0198Y0197     S2      
317P3V3             VIA   -    MD0100PA00X+068161Y+076377X0190Y         S0      
327P3V3             R111  -1   M      A18X+068161Y+076377X0198Y0197     S2      
317P3V3             VIA   -    MD0100PA00X+065190Y+076377X0190Y         S0      
327P3V3             R110  -1   M      A18X+065190Y+076377X0198Y0197     S2      
327P3V3             R95   -1          A18X+163188Y+075276X0198Y0197     S2      
327P3V3             R88   -1          A18X+117373Y+075126X0198Y0197R180 S2      
317P3V3             VIA   -    MD0100PA00X+007396Y+076609X0190Y         S0      
317P3V3             VIA   -    MD0100PA00X+007393Y+076871X0190Y         S0      
317P3V3             VIA   -    MD0100PA00X+010357Y+076377X0190Y         S0      
327P3V3             R107  -1   M      A18X+010364Y+076377X0198Y0197     S2      
317P3V3             VIA   -    MD0100PA00X+013312Y+076377X0190Y         S0      
327P3V3             R106  -1   M      A18X+013334Y+076377X0198Y0197     S2      
317P3V3             VIA   -    MD0100PA00X+016298Y+076377X0190Y         S0      
327P3V3             R105  -1   M      A18X+016298Y+076377X0198Y0197     S2      
317P3V3             VIA   -    MD0100PA00X+019268Y+076377X0190Y         S0      
327P3V3             R104  -1   M      A18X+019274Y+076377X0198Y0197     S2      
317P3V3             VIA   -    MD0100PA00X+022238Y+076377X0190Y         S0      
327P3V3             R103  -1   M      A18X+022234Y+076377X0198Y0197     S2      
317P3V3             VIA   -    MD0100PA00X+018806Y+073173X0200Y         S0      
317P3V3             VIA   -    MD0100PA00X+005926Y+073742X0200Y         S0      
327P3V3             R108  -1          A18X+005550Y+075576X0198Y0197R270 S2      
327P3V3             R102  -1          A18X+019758Y+075127X0198Y0197R180 S2      
317P3V3             VIA   -    MD0100PA00X+116882Y+076376X0190Y         S0      
327P3V3             R90   -1   M      A18X+116882Y+076376X0198Y0197     S2      
317P3V3             VIA   -    MD0100PA00X+113912Y+076376X0190Y         S0      
327P3V3             R91   -1   M      A18X+113912Y+076376X0198Y0197     S2      
317P3V3             VIA   -    MD0100PA00X+107972Y+076376X0190Y         S0      
327P3V3             R93   -1   M      A18X+107972Y+076376X0198Y0197     S2      
317P3V3             VIA   -    MD0100PA00X+105002Y+076376X0190Y         S0      
327P3V3             R94   -1   M      A18X+105002Y+076376X0198Y0197     S2      
317P3V3             VIA   -    MD0100PA00X+110942Y+076376X0190Y         S0      
327P3V3             R92   -1   M      A18X+110942Y+076376X0198Y0197     S2      
317P3V3             VIA   -    MD0100PA00X+119852Y+076376X0190Y         S0      
317P3V3             VIA   -    MD0100PA00X+109127Y+066829X0200Y         S0      
317P3V3             VIA   -    MD0100PA00X+106287Y+049018X0200Y         S0      
327P3V3             R89   -1   M      A18X+119852Y+076376X0198Y0197     S2      
327P3V3             R361  -1          A18X+093492Y+085050X0198Y0197R180 S2      
317P3V3             VIA   -    MD0100PA00X+093200Y+085050X0200Y         S0      
327P3V3             R365  -1          A18X+094608Y+085050X0198Y0197     S2      
317P3V3             VIA   -    MD0100PA00X+094900Y+085050X0200Y         S0      
327P3V3             C26   -1   M      A18X+093400Y+086408X0198Y0197R090 S2      
327P3V3             U5    -8          A18X+093579Y+086979X0240Y0460     S2      
317P3V3             VIA   -    MD0100PA00X+093058Y+086408X0200Y         S0      
327P3V3             R78   -1          A18X+094800Y+085542X0198Y0197R270 S2      
317P3V3             VIA   -    MD0100PA00X+095100Y+085542X0200Y         S0      
317P3V3             VIA   -    MD0100PA00X+067412Y+073608X0200Y         S0      
317P3V3             VIA   -    MD0100PA00X+053175Y+045323X0200Y         S0      
317P3V3             VIA   -    MD0100PA00X+067905Y+067873X0200Y         S0      
327P3V3             R109  -1   M      A18X+065606Y+075127X0198Y0197     S2      
327P3V3             U6006 -3   M      A01X+046253Y+049350X0260Y0380R270 S1      
317P3V3             VIA   -    MD0100PA00X+023591Y+036087X0200Y         S0      
317P3V3             VIA   -    MD0100PA00X+023341Y+036087X0200Y         S0      
317P3V3             VIA   -    MD0100PA00X+009022Y+062235X0200Y         S0      
317P3V3             VIA   -    MD0100PA00X+009022Y+061835X0200Y         S0      
317P3V3             VIA   -    MD0100PA00X+009022Y+061435X0200Y         S0      
317P3V3             VIA   -    MD0100PA00X+009022Y+061035X0200Y         S0      
317P3V3             VIA   -    MD0100PA00X+042978Y+050695X0200Y    R180 S0      
327P3V3             R1491 -1          A01X+044350Y+048642X0198Y0197R090 S1      
317P3V3             VIA   -    M      A01X+032441Y+036774X0200Y         S2      
017P3V3             VIA   -    M      A18X+032441Y+036774X0260Y         S2      
017P3V3                   -    MD0100PA00X+032441Y+036774                       
317P3V3             VIA   -    M      A01X+024041Y+036087X0200Y         S2      
017P3V3             VIA   -    M      A18X+024041Y+036087X0260Y         S2      
017P3V3                   -    MD0100PA00X+024041Y+036087                       
327P3V3             C6500 -1   M      A01X+046850Y+049308X0198Y0197R270 S1      
327P3V3             R3100 -2          A18X+124609Y+026106X0198Y0197R090 S2      
317P3V3             VIA   -    MD0100PA00X+124609Y+025863X0200Y         S0      
317P3V3             VIA   -    MD0100PA00X+126197Y+021950X0200Y         S0      
327P3V3             R2908 -1          A01X+129918Y+016605X0198Y0197R180 S1      
317P3V3             VIA   -    MD0100PA00X+130158Y+016605X0200Y         S0      
327P3V3             R3634 -2          A01X+064932Y+023787X1150Y1380R090 S1      
317P3V3             VIA   -    MD0100PA00X+062046Y+022878X0200Y         S0      
327P3V3             U264  -11         A01X+061574Y+022586X0090Y0240R270 S1      
327P3V3             C2018 -1   M      A01X+062045Y+022628X0198Y0197     S1      
327P3V3             R3574 -1          A01X+063768Y+023098X0198Y0197R180 S1      
317P3V3             VIA   -    MD0100PA00X+064080Y+024337X0200Y         S0      
317P3V3             VIA   -    MD0100PA00X+064080Y+023937X0200Y         S0      
317P3V3             VIA   -    MD0100PA00X+063780Y+024337X0200Y         S0      
317P3V3             VIA   -    MD0100PA00X+063780Y+023937X0200Y         S0      
317P3V3             VIA   -    MD0100PA00X+064080Y+023537X0200Y         S0      
317P3V3             VIA   -    MD0100PA00X+063780Y+023537X0200Y         S0      
317P3V3             VIA   -    MD0100PA00X+162805Y+076376X0200Y    R180 S0      
327P3V3             R96   -1   M      A18X+162805Y+076376X0198Y0197     S2      
317P3V3             VIA   -    MD0100PA00X+165775Y+076376X0190Y         S0      
327P3V3             R97   -1   M      A18X+165775Y+076376X0198Y0197     S2      
317P3V3             VIA   -    MD0100PA00X+168745Y+076376X0190Y         S0      
327P3V3             R98   -1   M      A18X+168745Y+076376X0198Y0197     S2      
317P3V3             VIA   -    MD0100PA00X+171715Y+076376X0190Y         S0      
327P3V3             R99   -1   M      A18X+171715Y+076376X0198Y0197     S2      
317P3V3             VIA   -    MD0100PA00X+174685Y+076376X0190Y         S0      
327P3V3             R100  -1   M      A18X+174685Y+076376X0198Y0197     S2      
317P3V3             VIA   -    MD0100PA00X+177655Y+076376X0200Y    R180 S0      
327P3V3             R101  -1   M      A18X+177655Y+076376X0198Y0197     S2      
317P3V3             VIA   -    MD0100PA00X+174039Y+030569X0200Y    R270 S0      
317P3V3             VIA   -    MD0100PA00X+173789Y+030569X0200Y    R270 S0      
317P3V3             VIA   -    MD0100PA00X+174039Y+030269X0200Y    R270 S0      
317P3V3             VIA   -    MD0100PA00X+173789Y+030269X0200Y    R270 S0      
317P3V3             VIA   -    MD0100PA00X+173539Y+030269X0200Y    R270 S0      
317P3V3             VIA   -    MD0100PA00X+173539Y+030569X0200Y    R270 S0      
317P3V3             VIA   -    MD0100PA00X+173025Y+030273X0200Y    R270 S0      
317P3V3             VIA   -    MD0100PA00X+173275Y+030273X0200Y    R270 S0      
317P3V3             VIA   -    MD0100PA00X+173025Y+030573X0200Y    R270 S0      
317P3V3             VIA   -    MD0100PA00X+173275Y+030573X0200Y    R270 S0      
317P3V3             VIA   -    MD0100PA00X+174567Y+029368X0200Y    R270 S0      
317P3V3             VIA   -    MD0100PA00X+174567Y+029068X0200Y    R270 S0      
317P3V3             VIA   -    MD0100PA00X+173283Y+029372X0200Y    R270 S0      
317P3V3             VIA   -    MD0100PA00X+173283Y+029972X0200Y    R270 S0      
317P3V3             VIA   -    MD0100PA00X+173033Y+029972X0200Y    R270 S0      
317P3V3             VIA   -    MD0100PA00X+173283Y+029672X0200Y    R270 S0      
317P3V3             VIA   -    MD0100PA00X+173033Y+029672X0200Y    R270 S0      
317P3V3             VIA   -    MD0100PA00X+173033Y+029372X0200Y    R270 S0      
327P3V3             C61   -1          A01X+174604Y+030511X0198Y0197     S1      
327P3V3             C1340 -1          A01X+174507Y+029964X0400Y0500R180 S1      
317P3V3             VIA   -    MD0100PA00X+175135Y+029339X0200Y         S0      
317P3V3             VIA   -    MD0100PA00X+173797Y+029368X0200Y    R270 S0      
317P3V3             VIA   -    MD0100PA00X+173547Y+029968X0200Y    R270 S0      
317P3V3             VIA   -    MD0100PA00X+173547Y+029668X0200Y    R270 S0      
317P3V3             VIA   -    MD0100PA00X+173797Y+029668X0200Y    R270 S0      
317P3V3             VIA   -    MD0100PA00X+174047Y+029668X0200Y    R270 S0      
317P3V3             VIA   -    MD0100PA00X+173797Y+029968X0200Y    R270 S0      
317P3V3             VIA   -    MD0100PA00X+174047Y+029968X0200Y    R270 S0      
317P3V3             VIA   -    MD0100PA00X+174047Y+029068X0200Y    R270 S0      
317P3V3             VIA   -    MD0100PA00X+174047Y+029368X0200Y    R270 S0      
317P3V3             VIA   -    MD0100PA00X+173797Y+029068X0200Y    R270 S0      
317P3V3             VIA   -    MD0100PA00X+173547Y+029068X0200Y    R270 S0      
317P3V3             VIA   -    MD0100PA00X+173547Y+029368X0200Y    R270 S0      
317P3V3             VIA   -    MD0100PA00X+174297Y+029068X0200Y    R270 S0      
317P3V3             VIA   -    MD0100PA00X+174297Y+029368X0200Y    R270 S0      
327P3V3             Q56   -1          A01X+174557Y+028686X0280Y0460R180 S1      
327P3V3             Q56   -3          A01X+173557Y+028686X0280Y0460R180 S1      
327P3V3             Q56   -2          A01X+174057Y+028686X0280Y0460R180 S1      
317P3V3             VIA   -    MD0100PA00X+167881Y+020645X0200Y    R270 S0      
327P3V3             D1    -1          A01X+167551Y+020645X0320Y0360R090 S1      
317m4646            VIA   -    MD0080PA01X+146020Y+154997X0160Y         S0      
317m4646            VIA   -    MD0080PA01X+142663Y+113010X0160Y         S0      
327m4646            U25   -CV36       A01X+142480Y+112906X0177Y    R180 S1      
327m4646            U6013 -EW29       A01X+145815Y+154997X0150Y         S1      
317m4647            VIA   -    MD0080PA01X+146178Y+155270X0160Y         S0      
317m4647            VIA   -    MD0080PA01X+143033Y+113010X0160Y         S0      
327m4647            U25   -CV35       A01X+142850Y+112906X0177Y    R180 S1      
327m4647            U6013 -EU26       A01X+145973Y+155270X0150Y         S1      
327m4648            J41   -B65        A01X+052263Y+006516X0150Y0570R180 S1      
317m4648            VIA   -    MD0100PA01X+015751Y+166393X0200Y    R090 S0      
327m4648            R6154 -1          A01X+015581Y+166166X0120Y0150     S1      
327m4648            R6152 -1   M      A01X+015581Y+166166X0120Y0150R180 S1      
317m4648            VIA   -    MD0100PA01X+052314Y+007144X0200Y    R180 S0      
327m4649            J41   -B66        A01X+052026Y+006516X0150Y0570R180 S1      
317m4649            VIA   -    MD0100PA01X+015411Y+166393X0200Y    R090 S0      
327m4649            R6155 -1          A01X+015581Y+166621X0120Y0150     S1      
327m4649            R6153 -1   M      A01X+015581Y+166621X0120Y0150R180 S1      
317m4649            VIA   -    MD0100PA01X+051974Y+007144X0200Y    R180 S0      
327m4650            C6005 -2          A01X+011078Y+165775X0180Y0200R180 S1      
327m4650            C1870 -2   M      A01X+011078Y+165775X0180Y0200     S1      
317m4650            VIA   -    MD0100PA01X+010907Y+166024X0200Y    R090 S0      
317m4650            J112  -Q6   D0142PA01X+027028Y+165783X0302Y    R180 S3      
327m4651            C1871 -2          A01X+011077Y+166272X0180Y0200     S1      
327m4651            C6006 -2   M      A01X+011077Y+166272X0180Y0200R180 S1      
317m4651            VIA   -    MD0100PA01X+011247Y+166024X0200Y    R090 S0      
317m4651            J112  -R6   D0142PA01X+027028Y+165311X0302Y    R180 S3      
317m4652            VIA   -    MD0100PA01X+011097Y+168576X0200Y    R090 S0      
317m4652            J112  -N6   D0142PA01X+027028Y+167201X0302Y    R180 S3      
327m4652            R6158 -1   M      A01X+010927Y+168801X0120Y0150R180 S1      
327m4652            R6156 -1          A01X+010927Y+168801X0120Y0150     S1      
317m4653            VIA   -    MD0100PA01X+010757Y+168576X0200Y    R090 S0      
317m4653            J112  -O6   D0142PA01X+027028Y+166728X0302Y    R180 S3      
327m4653            R6159 -1   M      A01X+010927Y+168351X0120Y0150R180 S1      
327m4653            R6157 -1          A01X+010927Y+168351X0120Y0150     S1      
327m4654            J41   -A65        A01X+052263Y+005354X0150Y0570R180 S1      
327m4654            C6007 -2          A01X+015571Y+167938X0180Y0200     S1      
327m4654            C1868 -2   M      A01X+015571Y+167938X0180Y0200R180 S1      
317m4654            VIA   -    MD0100PA01X+015741Y+167681X0200Y    R090 S0      
317m4654            VIA   -    MD0100PA01X+052316Y+004033X0200Y         S0      
327m4655            J41   -A66        A01X+052026Y+005354X0150Y0570R180 S1      
327m4655            C6008 -2          A01X+015571Y+167424X0180Y0200     S1      
327m4655            C1869 -2   M      A01X+015571Y+167424X0180Y0200R180 S1      
317m4655            VIA   -    MD0100PA01X+015401Y+167681X0200Y    R090 S0      
317m4655            VIA   -    MD0100PA01X+051976Y+004033X0200Y         S0      
327P1V5_BAT_OUT     U9    -5   M      A01X+120485Y+010343X0160Y0360R270 S1      
327P1V5_BAT_OUT     R5053 -1          A01X+128476Y+009538X0198Y0197R270 S1      
327P1V5_BAT_OUT     U167  -3          A01X+117185Y+007601X0280Y0360R180 S1      
327P1V5_BAT_OUT     C1564 -1   M      A01X+116620Y+007735X0198Y0197R270 S1      
327P1V5_BAT_OUT     VIA   -    M      A01X+116343Y+008282X0300Y         S1      
317P1V5_BAT         VIA   -    MD0080PA00X+147289Y+105038X0160Y         S0      
317P1V5_BAT         VIA   -    MD0100PA00X+134251Y+118785X0200Y         S0      
317P1V5_BAT         VIA   -    MD0100PA00X+103790Y+125152X0200Y         S0      
317P1V5_BAT         VIA   -           A01X+059525Y+126667X0300Y    R180 S1      
017P1V5_BAT         VIA   -           A18X+059525Y+126667X0200Y    R180 S1      
017P1V5_BAT               -     D0100PA00X+059525Y+126667                       
317P1V5_BAT         VIA   -    MD0100PA00X+082673Y+124632X0200Y         S0      
327P1V5_BAT         R373  -1   M      A01X+059075Y+126667X0198Y0197R180 S1      
317P1V5_BAT         VIA   -    MD0100PA00X+140581Y+143002X0200Y         S0      
327P1V5_BAT         U25   -BN23       A01X+147106Y+104933X0177Y    R180 S1      
317P1V5_BAT         VIA   -    MD0100PA00X+152122Y+119009X0200Y         S0      
327P1V5_BAT         R5055 -1          A18X+160865Y+130074X0198Y0197R090 S2      
317P1V5_BAT         VIA   -    MD0100PA00X+160865Y+130334X0200Y         S0      
317P1V5_BAT         VIA   -    MD0100PA00X+164516Y+127618X0200Y         S0      
317P1V5_BAT         JP12  -2   MD0410PA00X+129944Y+010281X0610Y    R180 S3      
327P1V5_BAT         R1779 -2          A01X+119549Y+009112X0198Y0197R090 S1      
317P1V5_BAT         VIA   -    MD0100PA00X+119549Y+009355X0200Y    R090 S0      
317P1V5_BAT         VIA   -    MD0100PA00X+131104Y+010474X0200Y    R180 S0      
317P1V5_BAT         VIA   -    MD0100PA00X+131395Y+010474X0200Y    R180 S0      
327P1V5_BAT         C5032 -1          A01X+131251Y+010103X0400Y0500R090 S1      
327P1V5_BAT         C1567 -1          A01X+130786Y+010578X0198Y0197R090 S1      
317P1V5_BAT         VIA   -    MD0100PA00X+130786Y+010335X0200Y    R180 S0      
317P1V5_BAT         VIA   -    MD0100PA00X+162716Y+023830X0200Y         S0      
317P1V5_BAT         VIA   -    MD0100PA00X+170934Y+063725X0200Y         S0      
317P1V5_BAT         VIA   -    MD0100PA00X+160053Y+140471X0200Y         S0      
317P12V_SCM_VCC     VIA   -    M      A01X+074131Y+010874X0200Y         S2      
017P12V_SCM_VCC     VIA   -    M      A18X+074131Y+010874X0260Y         S2      
017P12V_SCM_VCC           -    MD0100PA00X+074131Y+010874                       
327P12V_SCM_VCC     PU300 -A2         A01X+074307Y+010391X0090Y         S1      
327P12V_SCM_VCC     PR4003-2          A01X+074127Y+011558X0198Y0197R270 S1      
327P12V_SCM_VCC     PC2233-1   M      A01X+074131Y+011125X0198Y0197R180 S1      
327P12V_SCM_UV_R    R3997 -1          A01X+075131Y+016146X0198Y0197R180 S1      
327P12V_SCM_UV_R    VIA   -    M      A01X+076434Y+016208X0300Y         S1      
327P12V_SCM_UV_R    Q125  -3          A01X+076872Y+017264X0170Y0200R270 S1      
327P12V_SCM_UV      R3997 -2          A01X+074816Y+016146X0198Y0197R180 S1      
317P12V_SCM_UV      VIA   -    MD0100PA00X+074503Y+016146X0200Y         S0      
317P12V_SCM_UV      VIA   -    M      A01X+073982Y+009105X0200Y    R270 S2      
017P12V_SCM_UV      VIA   -    M      A18X+073982Y+009105X0260Y    R270 S2      
017P12V_SCM_UV            -    MD0100PA00X+073982Y+009105                       
327P12V_SCM_UV      PU300 -D2         A01X+074307Y+009800X0090Y         S1      
327P12V_SCM_UV      PR4000-2          A01X+073307Y+009100X0198Y0197     S1      
327P12V_SCM_UV      PR4001-1   M      A01X+073709Y+009105X0198Y0197R270 S1      
317P12V_SCM_TIMER   VIA   -    M      A01X+070471Y+012559X0200Y         S2      
017P12V_SCM_TIMER   VIA   -    M      A18X+070471Y+012559X0260Y         S2      
017P12V_SCM_TIMER         -    MD0100PA00X+070471Y+012559                       
327P12V_SCM_TIMER   PU299 -4          A01X+070155Y+011944X0100Y0320R180 S1      
327P12V_SCM_TIMER   PC2229-1          A01X+070495Y+012809X0198Y0197R090 S1      
327P12V_SCM_SS      VIA   -    M      A01X+069655Y+012504X0300Y         S1      
327P12V_SCM_SS      PU299 -6          A01X+069762Y+011944X0100Y0320R180 S1      
327P12V_SCM_SS      PC2232-1          A01X+069445Y+012809X0198Y0197R090 S1      
317P12V_SCM_SENSE   VIA   -           A01X+073066Y+010848X0200Y    R180 S2      
017P12V_SCM_SENSE   VIA   -           A18X+073066Y+010848X0260Y    R180 S2      
017P12V_SCM_SENSE         -     D0100PA00X+073066Y+010848                       
327P12V_SCM_SENSE   PU300 -A1         A01X+074110Y+010391X0090Y         S1      
327P12V_SCM_SENSE   PR4008-1   M      A01X+073358Y+010547X0198Y0197R180 S1      
327P12V_SCM_REG     PC2234-2          A01X+073310Y+009516X0198Y0197     S1      
317P12V_SCM_REG     VIA   -    M      A01X+073577Y+009499X0200Y         S2      
017P12V_SCM_REG     VIA   -    M      A18X+073577Y+009499X0260Y         S2      
017P12V_SCM_REG           -    MD0100PA00X+073577Y+009499                       
327P12V_SCM_REG     PU300 -D1         A01X+074110Y+009800X0090Y         S1      
327P12V_SCM_R       PU299 -13         A01X+069368Y+010842X0100Y0320R180 S1      
327P12V_SCM_R       PU299 -14         A01X+069565Y+010842X0100Y0320R180 S1      
327P12V_SCM_R       PU299 -15         A01X+069762Y+010842X0100Y0320R180 S1      
327P12V_SCM_R       PU299 -16         A01X+069958Y+010842X0100Y0320R180 S1      
327P12V_SCM_R       PU299 -17         A01X+070155Y+010842X0100Y0320R180 S1      
327P12V_SCM_R       PU299 -18         A01X+070352Y+010842X0100Y0320R180 S1      
327P12V_SCM_R       PU299 -19         A01X+070549Y+010842X0100Y0320R180 S1      
327P12V_SCM_R       PU299 -20         A01X+070746Y+010842X0100Y0320R180 S1      
327P12V_SCM_R       PC2241-1          A01X+070685Y+010331X0198Y0197     S1      
327P12V_SCM_R       PR4006-1          A01X+069403Y+009167X0198Y0197R180 S1      
327P12V_SCM_R       PC2242-1          A01X+069272Y+008336X0400Y0500     S1      
327P12V_SCM_R       PC2238-1          A01X+069380Y+007696X0198Y0197R180 S1      
327P12V_SCM_R       PR4009-1          A01X+067584Y+010411X0198Y0197R090 S1      
327P12V_SCM_R       R3578 -1          A18X+079894Y+014426X0198Y0197R180 S2      
317P12V_SCM_R       VIA   -    M      A01X+082090Y+014711X0200Y         S2      
017P12V_SCM_R       VIA   -    M      A18X+082090Y+014711X0260Y         S2      
017P12V_SCM_R             -    MD0100PA00X+082090Y+014711                       
327P12V_SCM_R       C2019 -1          A18X+082112Y+014254X0198Y0197R090 S2      
327P12V_SCM_R       R3635 -2          A01X+079153Y+014675X1150Y1380R090 S1      
317P12V_SCM_R       VIA   -    MD0100PA00X+078016Y+014696X0200Y         S0      
317P12V_SCM_R       VIA   -    MD0100PA00X+078282Y+014947X0200Y         S0      
317P12V_SCM_R       VIA   -    MD0100PA00X+071229Y+010672X0200Y         S0      
317P12V_SCM_R       VIA   -    MD0100PA00X+075003Y+009289X0200Y         S0      
327P12V_SCM_R       PU300 -A4         A01X+074700Y+010391X0090Y         S1      
327P12V_SCM_R       PU300 -B4         A01X+074700Y+010194X0090Y         S1      
327P12V_SCM_R       PU300 -B6         A01X+075094Y+010194X0090Y         S1      
327P12V_SCM_R       PU300 -C4         A01X+074700Y+009997X0090Y         S1      
327P12V_SCM_R       PU300 -C6         A01X+075094Y+009997X0090Y         S1      
327P12V_SCM_R       PU300 -D4         A01X+074700Y+009800X0090Y         S1      
327P12V_SCM_R       PU300 -D6         A01X+075094Y+009800X0090Y         S1      
317P12V_SCM_R       VIA   -    MD0100PA00X+075003Y+008999X0200Y         S0      
327P12V_SCM_R       PD116 -C          A01X+074727Y+007924X0670Y0990R270 S1      
317P12V_SCM_R       VIA   -    MD0100PA00X+069922Y+010216X0200Y         S0      
327P12V_SCM_R       PC2240-1          A18X+069242Y+009706X0400Y0500R180 S2      
317P12V_SCM_R       VIA   -    MD0100PA00X+069422Y+010486X0200Y         S0      
317P12V_SCM_R       VIA   -    MD0100PA00X+069572Y+010216X0200Y         S0      
317P12V_SCM_R       VIA   -    MD0100PA00X+069772Y+010486X0200Y         S0      
317P12V_SCM_R       VIA   -    MD0100PA00X+070122Y+010486X0200Y         S0      
317P12V_SCM_R       VIA   -    MD0100PA00X+070272Y+010216X0200Y         S0      
317P12V_SCM_R       VIA   -    MD0100PA00X+070672Y+010046X0200Y         S0      
317P12V_SCM_R       VIA   -    MD0100PA00X+069673Y+008405X0200Y         S0      
317P12V_SCM_R       VIA   -    MD0100PA00X+069673Y+008155X0200Y         S0      
317P12V_SCM_R       VIA   -    MD0100PA00X+069637Y+007851X0200Y         S0      
317P12V_SCM_R       VIA   -    MD0100PA00X+069871Y+008604X0200Y         S0      
327P12V_SCM_R       U265  -11         A01X+082253Y+014241X0090Y0240     S1      
327P12V_SCM_R       PR4526-1   M      A01X+075471Y+011917X0198Y0197R180 S1      
327P12V_SCM_R       PC2236-1          A01X+075471Y+011529X0198Y0197R180 S1      
327P12V_SCM_PWRGD   PR4012-1          A01X+075704Y+008935X0198Y0197     S1      
317P12V_SCM_PWRGD   VIA   -    M      A01X+075478Y+009655X0200Y         S2      
017P12V_SCM_PWRGD   VIA   -    M      A18X+075478Y+009655X0260Y         S2      
017P12V_SCM_PWRGD         -    MD0100PA00X+075478Y+009655                       
327P12V_SCM_PWRGD   PU300 -D7         A01X+075291Y+009800X0090Y         S1      
327P12V_SCM_OV_FB   PR4009-2          A01X+067584Y+010726X0198Y0197R090 S1      
327P12V_SCM_OV_FB   VIA   -    M      A01X+067524Y+011196X0300Y         S1      
327P12V_SCM_OV_FB   PR4010-2   M      A01X+068062Y+011196X0198Y0197R090 S1      
327P12V_SCM_OV_FB   PU299 -11         A01X+069013Y+011196X0100Y0320R270 S1      
327P12V_SCM_OV_FB   PR4011-1   M      A01X+068464Y+011196X0198Y0197R270 S1      
327P12V_SCM_OV      VIA   -    M      A01X+074185Y+008710X0300Y         S1      
327P12V_SCM_OV      PU300 -D3         A01X+074504Y+009800X0090Y         S1      
327P12V_SCM_OV      PR4002-1          A01X+073307Y+008700X0198Y0197R180 S1      
327P12V_SCM_OV      PR4001-2   M      A01X+073709Y+008790X0198Y0197R270 S1      
327m4656            PR4540-2          A18X+069395Y+012810X0198Y0197R270 S2      
327m4656            PC2340-1          A18X+070785Y+013027X0198Y0197R090 S2      
327m4656            VIA   -    M      A18X+070117Y+013096X0260Y    R270 S2      
327P12V_SCM_ISET    PR4540-1          A18X+069395Y+012495X0198Y0197R270 S2      
317P12V_SCM_ISET    VIA   -    M      A01X+069940Y+012367X0200Y         S2      
017P12V_SCM_ISET    VIA   -    M      A18X+069940Y+012367X0260Y         S2      
017P12V_SCM_ISET          -    MD0100PA00X+069940Y+012367                       
327P12V_SCM_ISET    PR3999-1          A01X+070096Y+012815X0198Y0197R090 S1      
327P12V_SCM_ISET    PU299 -5          A01X+069958Y+011944X0100Y0320R180 S1      
327P12V_SCM_IMON    PC2235-1   M      A01X+068745Y+012809X0198Y0197R090 S1      
327P12V_SCM_IMON    PR4005-1   M      A01X+068345Y+012809X0198Y0197R090 S1      
327P12V_SCM_IMON    VIA   -           A01X+067807Y+012809X0300Y         S1      
327P12V_SCM_IMON    PU299 -8          A01X+069368Y+011944X0100Y0320R180 S1      
327P12V_SCM_GATE    PR4526-2          A01X+075156Y+011917X0198Y0197R180 S1      
327P12V_SCM_GATE    PC2236-2   M      A01X+075156Y+011529X0198Y0197R180 S1      
327P12V_SCM_GATE    PC2237-1   M      A01X+075156Y+011129X0198Y0197     S1      
317P12V_SCM_GATE    VIA   -    M      A01X+075070Y+010664X0200Y         S2      
017P12V_SCM_GATE    VIA   -    M      A18X+075070Y+010664X0260Y         S2      
017P12V_SCM_GATE          -    MD0100PA00X+075070Y+010664                       
327P12V_SCM_GATE    PU300 -A6         A01X+075094Y+010391X0090Y         S1      
317P12V_SCM_EN_R2   VIA   -           A01X+071234Y+012809X0200Y         S2      
017P12V_SCM_EN_R2   VIA   -           A18X+071234Y+012809X0260Y         S2      
017P12V_SCM_EN_R2         -     D0100PA00X+071234Y+012809                       
327P12V_SCM_EN_R2   PU299 -1          A01X+070746Y+011934X0098Y0335R180 S1      
327P12V_SCM_EN_R2   R3998 -2   M      A01X+070895Y+012809X0198Y0197R270 S1      
327P12V_SCM_EN_R    Q125  -2          A01X+076872Y+017008X0170Y0200R270 S1      
327P12V_SCM_EN_R    VIA   -    M      A01X+077390Y+017006X0300Y    R180 S1      
327P12V_SCM_EN_R    R4062 -2          A01X+077484Y+016325X0198Y0197R180 S1      
327P12V_SCM_EN_G    R4071 -2          A01X+075128Y+016754X0198Y0197     S1      
327P12V_SCM_EN_G    VIA   -    M      A01X+075590Y+017056X0300Y    R180 S1      
327P12V_SCM_EN_G    Q125  -6   M      A01X+076124Y+016752X0170Y0200R270 S1      
327P12V_SCM_EN_G    Q125  -5          A01X+076124Y+017008X0170Y0200R270 S1      
327P12V_SCM_EN      R3998 -1          A01X+070895Y+013124X0198Y0197R270 S1      
327P12V_SCM_EN      Q39   -D   M      A01X+076303Y+015131X0320Y0360     S1      
327P12V_SCM_EN      VIA   -    M      A01X+075350Y+015131X0300Y         S1      
327P12V_SCM_EN      R1857 -2   M      A01X+077788Y+015373X0198Y0197     S1      
327P12V_SCM_EN      R4062 -1          A01X+077800Y+016325X0198Y0197R180 S1      
327P12V_SCM_EN      R3996 -2   M      A01X+077786Y+015803X0198Y0197     S1      
327P12V_SCM_CB      PR4004-1          A01X+073358Y+010197X0198Y0197R180 S1      
327P12V_SCM_CB      PU300 -B1         A01X+074110Y+010194X0090Y         S1      
317P12V_SCM_CB      VIA   -    M      A01X+073665Y+010235X0200Y         S2      
017P12V_SCM_CB      VIA   -    M      A18X+073665Y+010235X0260Y         S2      
017P12V_SCM_CB            -    MD0100PA00X+073665Y+010235                       
327m4657            PU299 -12         A01X+069171Y+010842X0100Y0320R180 S1      
327m4657            PC2239-1          A01X+069044Y+010176X0280Y0320R090 S1      
327m4657            PR4014-2          A01X+069044Y+009686X0280Y0320R270 S1      
327m4657            VIA   -           A01X+068621Y+009149X0300Y         S1      
327m4657            PR4006-2   M      A01X+069088Y+009167X0198Y0197R180 S1      
327P12V_SCM         J41   -OB1        A01X+075221Y+006516X0150Y0570R180 S1      
327P12V_SCM         J41   -OB2        A01X+074985Y+006516X0150Y0570R180 S1      
327P12V_SCM         J41   -OA1        A01X+075221Y+005354X0150Y0570R180 S1      
327P12V_SCM         J41   -OA2        A01X+074985Y+005354X0150Y0570R180 S1      
327P12V_SCM         R3579 -1          A18X+079894Y+013926X0198Y0197R180 S2      
317P12V_SCM         VIA   -    M      A01X+076322Y+006513X0200Y    R090 S2      
017P12V_SCM         VIA   -    M      A18X+076322Y+006513X0260Y    R090 S2      
017P12V_SCM               -    MD0100PA00X+076322Y+006513                       
327P12V_SCM         R3635 -1          A01X+079153Y+012824X1150Y1380R090 S1      
317P12V_SCM         VIA   -    MD0100PA00X+078894Y+011864X0200Y         S0      
317P12V_SCM         VIA   -    MD0100PA00X+078644Y+011864X0200Y         S0      
317P12V_SCM         VIA   -    MD0100PA00X+078394Y+011864X0200Y         S0      
317P12V_SCM         VIA   -    MD0100PA00X+078768Y+012095X0200Y         S0      
317P12V_SCM         VIA   -    MD0100PA00X+079018Y+012095X0200Y         S0      
317P12V_SCM         VIA   -    MD0100PA00X+079268Y+012095X0200Y         S0      
317P12V_SCM         VIA   -    MD0100PA00X+078518Y+012095X0200Y         S0      
317P12V_SCM         VIA   -    MD0100PA00X+078144Y+011864X0200Y         S0      
317P12V_SCM         VIA   -    MD0100PA00X+076022Y+006463X0200Y    R090 S0      
317P12V_SCM         VIA   -    MD0100PA00X+075772Y+006463X0200Y    R090 S0      
317P12V_SCM         VIA   -    MD0100PA00X+075862Y+005160X0200Y         S0      
317P12V_SCM         VIA   -    MD0100PA00X+075562Y+005160X0200Y         S0      
317P12V_SCM         VIA   -    MD0100PA00X+076272Y+006213X0200Y    R090 S0      
317P12V_SCM         VIA   -    MD0100PA00X+076022Y+006213X0200Y    R090 S0      
317P12V_SCM         VIA   -    MD0100PA00X+075772Y+006213X0200Y    R090 S0      
327P12V_PSU_FUSE    FS1   -2          A01X+094755Y+164172X1280Y1350     S1      
327P12V_PSU_FUSE    PD15  -C          A01X+096869Y+163314X0950Y1300R090 S1      
327P12V_PSU_FUSE    PD13  -C          A01X+099631Y+163311X0950Y1300R090 S1      
327P12V_PSU_FUSE    R3923 -1          A01X+104240Y+165208X0198Y0197     S1      
327P12V_PSU_FUSE    R4901 -1   M      A01X+104253Y+164620X0198Y0197     S1      
317P12V_PSU         VIA   -    MD0100PA00X+078871Y+148882X0200Y         S0      
327P12V_PSU         PJ38  -1          A01X+077953Y+148882X0240Y0650R270 S1      
327P12V_PSU         R8027 -2          A01X+072844Y+161474X0198Y0197     S1      
327P12V_PSU         FS1   -1          A01X+091074Y+164172X1280Y1350     S1      
327P12V_PSU         VIA   -           A01X+088254Y+161670X0300Y         S1      
327P12V_PSU         VIA   -           A01X+087045Y+161646X0300Y         S1      
327P12V_PSU         VIA   -           A01X+085574Y+161599X0300Y         S1      
327P12V_PSU         PR6002-1A         A01X+109143Y+156269X0770Y1580R270 S1      
327P12V_PSU         PR2532-1A         A01X+105590Y+155970X1260Y2700R090 S1      
327P12V_PSU         PR2534-1A         A01X+102430Y+155970X1260Y2700R090 S1      
327P12V_PSU         PR2533-1A         A01X+099270Y+155970X1260Y2700R090 S1      
327P12V_PSU         PR6001-1A         A01X+096108Y+155968X1260Y2700R090 S1      
327P12V_PSU         PC2188-1          A01X+072844Y+161074X0198Y0197R180 S1      
327P12V_PSU         PR3926-1          A01X+072832Y+160673X0198Y0197R180 S1      
327P12V_PSU         PU297 -9          A01X+091847Y+159122X0100Y0140R180 S1      
327P12V_PSU         PU297 -16         A01X+090469Y+159122X0100Y0140R180 S1      
327P12V_PSU         PU297 -15         A01X+090666Y+159117X0100Y0150R180 S1      
327P12V_PSU         PU297 -14         A01X+090862Y+159117X0100Y0150R180 S1      
327P12V_PSU         PU297 -13         A01X+091059Y+159117X0100Y0150R180 S1      
327P12V_PSU         PU297 -12         A01X+091256Y+159117X0100Y0150R180 S1      
327P12V_PSU         PU297 -11         A01X+091453Y+159117X0100Y0150R180 S1      
327P12V_PSU         PU297 -10         A01X+091650Y+159117X0100Y0150R180 S1      
327P12V_PSU         PU296 -11         A01X+087253Y+159117X0100Y0150R180 S1      
327P12V_PSU         PU296 -10         A01X+087450Y+159117X0100Y0150R180 S1      
327P12V_PSU         PU296 -9          A01X+087647Y+159122X0100Y0140R180 S1      
327P12V_PSU         PU296 -16         A01X+086269Y+159122X0100Y0140R180 S1      
327P12V_PSU         PU296 -15         A01X+086466Y+159117X0100Y0150R180 S1      
327P12V_PSU         PU296 -14         A01X+086662Y+159117X0100Y0150R180 S1      
327P12V_PSU         PU296 -13         A01X+086859Y+159117X0100Y0150R180 S1      
327P12V_PSU         PU296 -12         A01X+087056Y+159117X0100Y0150R180 S1      
327P12V_PSU         PU288 -12         A01X+082856Y+159117X0100Y0150R180 S1      
327P12V_PSU         PU288 -11         A01X+083053Y+159117X0100Y0150R180 S1      
327P12V_PSU         PU288 -10         A01X+083250Y+159117X0100Y0150R180 S1      
327P12V_PSU         PU288 -9          A01X+083447Y+159122X0100Y0140R180 S1      
327P12V_PSU         PU288 -16         A01X+082069Y+159122X0100Y0140R180 S1      
327P12V_PSU         PU288 -15         A01X+082266Y+159117X0100Y0150R180 S1      
327P12V_PSU         PU288 -14         A01X+082462Y+159117X0100Y0150R180 S1      
327P12V_PSU         PU288 -13         A01X+082659Y+159117X0100Y0150R180 S1      
327P12V_PSU         PU287 -13         A01X+078459Y+159117X0100Y0150R180 S1      
327P12V_PSU         PU287 -12         A01X+078656Y+159117X0100Y0150R180 S1      
327P12V_PSU         PU287 -11         A01X+078853Y+159117X0100Y0150R180 S1      
327P12V_PSU         PU287 -10         A01X+079050Y+159117X0100Y0150R180 S1      
327P12V_PSU         PU287 -9          A01X+079247Y+159122X0100Y0140R180 S1      
327P12V_PSU         PU287 -16         A01X+077869Y+159122X0100Y0140R180 S1      
327P12V_PSU         PU287 -15         A01X+078066Y+159117X0100Y0150R180 S1      
327P12V_PSU         PU287 -14         A01X+078262Y+159117X0100Y0150R180 S1      
327P12V_PSU         PU289 -42         A01X+074219Y+158856X0090Y0150R270 S1      
327P12V_PSU         PU289 -2          A01X+073830Y+159117X0090Y0150     S1      
327P12V_PSU         PU289 -1          A01X+074007Y+159117X0090Y0150     S1      
327P12V_PSU         PU289 -8          A01X+072767Y+159117X0090Y0150     S1      
327P12V_PSU         PU289 -7          A01X+072944Y+159117X0090Y0150     S1      
327P12V_PSU         PU289 -6          A01X+073122Y+159117X0090Y0150     S1      
327P12V_PSU         PU289 -5          A01X+073299Y+159117X0090Y0150     S1      
327P12V_PSU         PU289 -4          A01X+073476Y+159117X0090Y0150     S1      
327P12V_PSU         PU289 -3          A01X+073653Y+159117X0090Y0150     S1      
317P12V_PSU         J45   -P4_1MD0402PA00X+089878Y+171489X0657Y    R270 S3      
317P12V_PSU         J45   -P4_2MD0402PA00X+089878Y+170489X0657Y    R270 S3      
317P12V_PSU         J45   -P4_3MD0402PA00X+089878Y+169489X0657Y    R270 S3      
317P12V_PSU         J45   -P4_4MD0402PA00X+089878Y+168489X0657Y    R270 S3      
317P12V_PSU         J45   -P4_5MD0402PA00X+088878Y+171489X0657Y    R270 S3      
317P12V_PSU         J45   -P4_6MD0402PA00X+088878Y+170489X0657Y    R270 S3      
317P12V_PSU         J45   -P4_7MD0402PA00X+088878Y+169489X0657Y    R270 S3      
317P12V_PSU         J45   -P4_8MD0402PA00X+088878Y+168489X0657Y    R270 S3      
317P12V_PSU         J45   -P5_1MD0402PA00X+086378Y+171489X0657Y    R270 S3      
317P12V_PSU         J45   -P5_2MD0402PA00X+086378Y+170489X0657Y    R270 S3      
317P12V_PSU         J45   -P5_3MD0402PA00X+086378Y+169489X0657Y    R270 S3      
317P12V_PSU         J45   -P5_4MD0402PA00X+086378Y+168489X0657Y    R270 S3      
317P12V_PSU         J45   -P5_5MD0402PA00X+085378Y+171489X0657Y    R270 S3      
317P12V_PSU         J45   -P5_6MD0402PA00X+085378Y+170489X0657Y    R270 S3      
317P12V_PSU         J45   -P5_7MD0402PA00X+085378Y+169489X0657Y    R270 S3      
317P12V_PSU         J45   -P5_8MD0402PA00X+085378Y+168489X0657Y    R270 S3      
317P12V_PSU         J45   -P6_1MD0402PA00X+082878Y+171489X0657Y    R270 S3      
317P12V_PSU         J45   -P6_2MD0402PA00X+082878Y+170489X0657Y    R270 S3      
317P12V_PSU         J45   -P6_3MD0402PA00X+082878Y+169489X0657Y    R270 S3      
317P12V_PSU         J45   -P6_4MD0402PA00X+082878Y+168489X0657Y    R270 S3      
317P12V_PSU         J45   -P6_5MD0402PA00X+081878Y+171489X0657Y    R270 S3      
317P12V_PSU         J45   -P6_6MD0402PA00X+081878Y+170489X0657Y    R270 S3      
317P12V_PSU         J45   -P6_7MD0402PA00X+081878Y+169489X0657Y    R270 S3      
317P12V_PSU         J45   -P6_8MD0402PA00X+081878Y+168489X0657Y    R270 S3      
317P12V_PSU         VIA   -    MD0100PA00X+109740Y+158604X0200Y    R270 S0      
317P12V_PSU         VIA   -    MD0100PA00X+109740Y+158904X0200Y    R270 S0      
317P12V_PSU         VIA   -    MD0100PA00X+108540Y+158604X0200Y    R270 S0      
317P12V_PSU         VIA   -    MD0100PA00X+108840Y+158604X0200Y    R270 S0      
317P12V_PSU         VIA   -    MD0100PA00X+108840Y+158904X0200Y    R270 S0      
317P12V_PSU         VIA   -    MD0100PA00X+108540Y+158904X0200Y    R270 S0      
317P12V_PSU         VIA   -    MD0100PA00X+109440Y+158604X0200Y    R270 S0      
317P12V_PSU         VIA   -    MD0100PA00X+109140Y+158604X0200Y    R270 S0      
317P12V_PSU         VIA   -    MD0100PA00X+109140Y+158904X0200Y    R270 S0      
317P12V_PSU         VIA   -    MD0100PA00X+109440Y+158904X0200Y    R270 S0      
317P12V_PSU         VIA   -    MD0100PA00X+106622Y+158888X0200Y    R270 S0      
317P12V_PSU         VIA   -    MD0100PA00X+106322Y+158888X0200Y    R270 S0      
317P12V_PSU         VIA   -    MD0100PA00X+106322Y+158588X0200Y    R270 S0      
317P12V_PSU         VIA   -    MD0100PA00X+106622Y+158588X0200Y    R270 S0      
317P12V_PSU         VIA   -    MD0100PA00X+106022Y+158888X0200Y    R270 S0      
317P12V_PSU         VIA   -    MD0100PA00X+106022Y+158588X0200Y    R270 S0      
317P12V_PSU         VIA   -    MD0100PA00X+105722Y+158888X0200Y    R270 S0      
317P12V_PSU         VIA   -    MD0100PA00X+105122Y+158888X0200Y    R090 S0      
317P12V_PSU         VIA   -    MD0100PA00X+105422Y+158888X0200Y    R090 S0      
317P12V_PSU         VIA   -    MD0100PA00X+104822Y+158888X0200Y    R090 S0      
317P12V_PSU         VIA   -    MD0100PA00X+104822Y+158588X0200Y    R090 S0      
317P12V_PSU         VIA   -    MD0100PA00X+105422Y+158588X0200Y    R090 S0      
317P12V_PSU         VIA   -    MD0100PA00X+105122Y+158588X0200Y    R090 S0      
317P12V_PSU         VIA   -    MD0100PA00X+105722Y+158588X0200Y    R270 S0      
317P12V_PSU         VIA   -    MD0100PA00X+103175Y+158871X0200Y    R270 S0      
317P12V_PSU         VIA   -    MD0100PA00X+103175Y+158571X0200Y    R270 S0      
317P12V_PSU         VIA   -    MD0100PA00X+102875Y+158871X0200Y    R270 S0      
317P12V_PSU         VIA   -    MD0100PA00X+102875Y+158571X0200Y    R270 S0      
317P12V_PSU         VIA   -    MD0100PA00X+102575Y+158871X0200Y    R270 S0      
317P12V_PSU         VIA   -    MD0100PA00X+101975Y+158871X0200Y    R090 S0      
317P12V_PSU         VIA   -    MD0100PA00X+102275Y+158871X0200Y    R090 S0      
317P12V_PSU         VIA   -    MD0100PA00X+101675Y+158871X0200Y    R090 S0      
317P12V_PSU         VIA   -    MD0100PA00X+101675Y+158571X0200Y    R090 S0      
317P12V_PSU         VIA   -    MD0100PA00X+102275Y+158571X0200Y    R090 S0      
317P12V_PSU         VIA   -    MD0100PA00X+101975Y+158571X0200Y    R090 S0      
317P12V_PSU         VIA   -    MD0100PA00X+102575Y+158571X0200Y    R270 S0      
317P12V_PSU         VIA   -    MD0100PA00X+100016Y+158571X0200Y    R270 S0      
317P12V_PSU         VIA   -    MD0100PA00X+100016Y+158871X0200Y    R270 S0      
317P12V_PSU         VIA   -    MD0100PA00X+099416Y+158571X0200Y    R270 S0      
317P12V_PSU         VIA   -    MD0100PA00X+099716Y+158571X0200Y    R270 S0      
317P12V_PSU         VIA   -    MD0100PA00X+098816Y+158571X0200Y    R090 S0      
317P12V_PSU         VIA   -    MD0100PA00X+099116Y+158571X0200Y    R090 S0      
317P12V_PSU         VIA   -    MD0100PA00X+098516Y+158571X0200Y    R090 S0      
317P12V_PSU         VIA   -    MD0100PA00X+098516Y+158871X0200Y    R090 S0      
317P12V_PSU         VIA   -    MD0100PA00X+099116Y+158871X0200Y    R090 S0      
317P12V_PSU         VIA   -    MD0100PA00X+098816Y+158871X0200Y    R090 S0      
317P12V_PSU         VIA   -    MD0100PA00X+099716Y+158871X0200Y    R270 S0      
317P12V_PSU         VIA   -    MD0100PA00X+099416Y+158871X0200Y    R270 S0      
317P12V_PSU         VIA   -    MD0100PA00X+096852Y+158557X0200Y    R270 S0      
317P12V_PSU         VIA   -    MD0100PA00X+096852Y+158857X0200Y    R270 S0      
317P12V_PSU         VIA   -    MD0100PA00X+095952Y+158557X0200Y    R090 S0      
317P12V_PSU         VIA   -    MD0100PA00X+095652Y+158557X0200Y    R090 S0      
317P12V_PSU         VIA   -    MD0100PA00X+096552Y+158557X0200Y    R270 S0      
317P12V_PSU         VIA   -    MD0100PA00X+096252Y+158557X0200Y    R270 S0      
317P12V_PSU         VIA   -    MD0100PA00X+096252Y+158857X0200Y    R270 S0      
317P12V_PSU         VIA   -    MD0100PA00X+096552Y+158857X0200Y    R270 S0      
317P12V_PSU         VIA   -    MD0100PA00X+095652Y+158857X0200Y    R090 S0      
317P12V_PSU         VIA   -    MD0100PA00X+095952Y+158857X0200Y    R090 S0      
317P12V_PSU         VIA   -    MD0100PA00X+095352Y+158557X0200Y    R090 S0      
317P12V_PSU         VIA   -    MD0100PA00X+095052Y+158557X0200Y    R090 S0      
317P12V_PSU         VIA   -    MD0100PA00X+095052Y+158857X0200Y    R090 S0      
317P12V_PSU         VIA   -    MD0100PA00X+095352Y+158857X0200Y    R090 S0      
317P12V_PSU         VIA   -    MD0100PA00X+109740Y+157704X0200Y    R270 S0      
317P12V_PSU         VIA   -    MD0100PA00X+109740Y+157404X0200Y    R270 S0      
317P12V_PSU         VIA   -    MD0100PA00X+109740Y+157104X0200Y    R270 S0      
317P12V_PSU         VIA   -    MD0100PA00X+109740Y+158004X0200Y    R270 S0      
317P12V_PSU         VIA   -    MD0100PA00X+109740Y+158304X0200Y    R270 S0      
317P12V_PSU         VIA   -    MD0100PA00X+108840Y+157704X0200Y    R270 S0      
317P12V_PSU         VIA   -    MD0100PA00X+108540Y+157704X0200Y    R270 S0      
317P12V_PSU         VIA   -    MD0100PA00X+108840Y+157404X0200Y    R270 S0      
317P12V_PSU         VIA   -    MD0100PA00X+108540Y+157404X0200Y    R270 S0      
317P12V_PSU         VIA   -    MD0100PA00X+108540Y+157104X0200Y    R270 S0      
317P12V_PSU         VIA   -    MD0100PA00X+108840Y+157104X0200Y    R270 S0      
317P12V_PSU         VIA   -    MD0100PA00X+108540Y+158004X0200Y    R270 S0      
317P12V_PSU         VIA   -    MD0100PA00X+108840Y+158004X0200Y    R270 S0      
317P12V_PSU         VIA   -    MD0100PA00X+108840Y+158304X0200Y    R270 S0      
317P12V_PSU         VIA   -    MD0100PA00X+108540Y+158304X0200Y    R270 S0      
317P12V_PSU         VIA   -    MD0100PA00X+109140Y+157704X0200Y    R270 S0      
317P12V_PSU         VIA   -    MD0100PA00X+109140Y+157404X0200Y    R270 S0      
317P12V_PSU         VIA   -    MD0100PA00X+109140Y+157104X0200Y    R270 S0      
317P12V_PSU         VIA   -    MD0100PA00X+109440Y+157704X0200Y    R270 S0      
317P12V_PSU         VIA   -    MD0100PA00X+109440Y+157404X0200Y    R270 S0      
317P12V_PSU         VIA   -    MD0100PA00X+109440Y+157104X0200Y    R270 S0      
317P12V_PSU         VIA   -    MD0100PA00X+109440Y+158004X0200Y    R270 S0      
317P12V_PSU         VIA   -    MD0100PA00X+109140Y+158004X0200Y    R270 S0      
317P12V_PSU         VIA   -    MD0100PA00X+109140Y+158304X0200Y    R270 S0      
317P12V_PSU         VIA   -    MD0100PA00X+109440Y+158304X0200Y    R270 S0      
317P12V_PSU         VIA   -    MD0100PA00X+106622Y+158288X0200Y    R270 S0      
317P12V_PSU         VIA   -    MD0100PA00X+106322Y+158288X0200Y    R270 S0      
317P12V_PSU         VIA   -    MD0100PA00X+106322Y+157988X0200Y    R270 S0      
317P12V_PSU         VIA   -    MD0100PA00X+106622Y+157988X0200Y    R270 S0      
317P12V_PSU         VIA   -    MD0100PA00X+106622Y+157088X0200Y    R270 S0      
317P12V_PSU         VIA   -    MD0100PA00X+106622Y+157388X0200Y    R270 S0      
317P12V_PSU         VIA   -    MD0100PA00X+106622Y+157688X0200Y    R270 S0      
317P12V_PSU         VIA   -    MD0100PA00X+106322Y+157088X0200Y    R270 S0      
317P12V_PSU         VIA   -    MD0100PA00X+106322Y+157388X0200Y    R270 S0      
317P12V_PSU         VIA   -    MD0100PA00X+106322Y+157688X0200Y    R270 S0      
317P12V_PSU         VIA   -    MD0100PA00X+106022Y+158288X0200Y    R270 S0      
317P12V_PSU         VIA   -    MD0100PA00X+106022Y+157988X0200Y    R270 S0      
317P12V_PSU         VIA   -    MD0100PA00X+106022Y+157088X0200Y    R270 S0      
317P12V_PSU         VIA   -    MD0100PA00X+106022Y+157388X0200Y    R270 S0      
317P12V_PSU         VIA   -    MD0100PA00X+106022Y+157688X0200Y    R270 S0      
317P12V_PSU         VIA   -    MD0100PA00X+105722Y+158288X0200Y    R270 S0      
317P12V_PSU         VIA   -    MD0100PA00X+105122Y+158288X0200Y    R090 S0      
317P12V_PSU         VIA   -    MD0100PA00X+105422Y+158288X0200Y    R090 S0      
317P12V_PSU         VIA   -    MD0100PA00X+104822Y+158288X0200Y    R090 S0      
317P12V_PSU         VIA   -    MD0100PA00X+104822Y+157988X0200Y    R090 S0      
317P12V_PSU         VIA   -    MD0100PA00X+105422Y+157988X0200Y    R090 S0      
317P12V_PSU         VIA   -    MD0100PA00X+105122Y+157988X0200Y    R090 S0      
317P12V_PSU         VIA   -    MD0100PA00X+105722Y+157988X0200Y    R270 S0      
317P12V_PSU         VIA   -    MD0100PA00X+105422Y+157088X0200Y    R090 S0      
317P12V_PSU         VIA   -    MD0100PA00X+105122Y+157088X0200Y    R090 S0      
317P12V_PSU         VIA   -    MD0100PA00X+105722Y+157088X0200Y    R270 S0      
317P12V_PSU         VIA   -    MD0100PA00X+105722Y+157388X0200Y    R270 S0      
317P12V_PSU         VIA   -    MD0100PA00X+105122Y+157388X0200Y    R090 S0      
317P12V_PSU         VIA   -    MD0100PA00X+105422Y+157388X0200Y    R090 S0      
317P12V_PSU         VIA   -    MD0100PA00X+105722Y+157688X0200Y    R270 S0      
317P12V_PSU         VIA   -    MD0100PA00X+105122Y+157688X0200Y    R090 S0      
317P12V_PSU         VIA   -    MD0100PA00X+105422Y+157688X0200Y    R090 S0      
317P12V_PSU         VIA   -    MD0100PA00X+104822Y+157088X0200Y    R090 S0      
317P12V_PSU         VIA   -    MD0100PA00X+104822Y+157388X0200Y    R090 S0      
317P12V_PSU         VIA   -    MD0100PA00X+104822Y+157688X0200Y    R090 S0      
317P12V_PSU         VIA   -    MD0100PA00X+103175Y+158271X0200Y    R270 S0      
317P12V_PSU         VIA   -    MD0100PA00X+103175Y+157971X0200Y    R270 S0      
317P12V_PSU         VIA   -    MD0100PA00X+103175Y+157071X0200Y    R270 S0      
317P12V_PSU         VIA   -    MD0100PA00X+103175Y+157371X0200Y    R270 S0      
317P12V_PSU         VIA   -    MD0100PA00X+103175Y+157671X0200Y    R270 S0      
317P12V_PSU         VIA   -    MD0100PA00X+102875Y+158271X0200Y    R270 S0      
317P12V_PSU         VIA   -    MD0100PA00X+102875Y+157971X0200Y    R270 S0      
317P12V_PSU         VIA   -    MD0100PA00X+102875Y+157071X0200Y    R270 S0      
317P12V_PSU         VIA   -    MD0100PA00X+102875Y+157371X0200Y    R270 S0      
317P12V_PSU         VIA   -    MD0100PA00X+102875Y+157671X0200Y    R270 S0      
317P12V_PSU         VIA   -    MD0100PA00X+102575Y+158271X0200Y    R270 S0      
317P12V_PSU         VIA   -    MD0100PA00X+101975Y+158271X0200Y    R090 S0      
317P12V_PSU         VIA   -    MD0100PA00X+102275Y+158271X0200Y    R090 S0      
317P12V_PSU         VIA   -    MD0100PA00X+101675Y+158271X0200Y    R090 S0      
317P12V_PSU         VIA   -    MD0100PA00X+101675Y+157971X0200Y    R090 S0      
317P12V_PSU         VIA   -    MD0100PA00X+102275Y+157971X0200Y    R090 S0      
317P12V_PSU         VIA   -    MD0100PA00X+101975Y+157971X0200Y    R090 S0      
317P12V_PSU         VIA   -    MD0100PA00X+102575Y+157971X0200Y    R270 S0      
317P12V_PSU         VIA   -    MD0100PA00X+102275Y+157071X0200Y    R090 S0      
317P12V_PSU         VIA   -    MD0100PA00X+101975Y+157071X0200Y    R090 S0      
317P12V_PSU         VIA   -    MD0100PA00X+102575Y+157071X0200Y    R270 S0      
317P12V_PSU         VIA   -    MD0100PA00X+102575Y+157371X0200Y    R270 S0      
317P12V_PSU         VIA   -    MD0100PA00X+101975Y+157371X0200Y    R090 S0      
317P12V_PSU         VIA   -    MD0100PA00X+102275Y+157371X0200Y    R090 S0      
317P12V_PSU         VIA   -    MD0100PA00X+102575Y+157671X0200Y    R270 S0      
317P12V_PSU         VIA   -    MD0100PA00X+101975Y+157671X0200Y    R090 S0      
317P12V_PSU         VIA   -    MD0100PA00X+102275Y+157671X0200Y    R090 S0      
317P12V_PSU         VIA   -    MD0100PA00X+101675Y+157071X0200Y    R090 S0      
317P12V_PSU         VIA   -    MD0100PA00X+101675Y+157371X0200Y    R090 S0      
317P12V_PSU         VIA   -    MD0100PA00X+101675Y+157671X0200Y    R090 S0      
317P12V_PSU         VIA   -    MD0100PA00X+100016Y+157671X0200Y    R270 S0      
317P12V_PSU         VIA   -    MD0100PA00X+100016Y+157371X0200Y    R270 S0      
317P12V_PSU         VIA   -    MD0100PA00X+100016Y+157071X0200Y    R270 S0      
317P12V_PSU         VIA   -    MD0100PA00X+100016Y+157971X0200Y    R270 S0      
317P12V_PSU         VIA   -    MD0100PA00X+100016Y+158271X0200Y    R270 S0      
317P12V_PSU         VIA   -    MD0100PA00X+098516Y+157671X0200Y    R090 S0      
317P12V_PSU         VIA   -    MD0100PA00X+098516Y+157371X0200Y    R090 S0      
317P12V_PSU         VIA   -    MD0100PA00X+098516Y+157071X0200Y    R090 S0      
317P12V_PSU         VIA   -    MD0100PA00X+099116Y+157671X0200Y    R090 S0      
317P12V_PSU         VIA   -    MD0100PA00X+098816Y+157671X0200Y    R090 S0      
317P12V_PSU         VIA   -    MD0100PA00X+099716Y+157671X0200Y    R270 S0      
317P12V_PSU         VIA   -    MD0100PA00X+099416Y+157671X0200Y    R270 S0      
317P12V_PSU         VIA   -    MD0100PA00X+099116Y+157371X0200Y    R090 S0      
317P12V_PSU         VIA   -    MD0100PA00X+098816Y+157371X0200Y    R090 S0      
317P12V_PSU         VIA   -    MD0100PA00X+099716Y+157371X0200Y    R270 S0      
317P12V_PSU         VIA   -    MD0100PA00X+099416Y+157371X0200Y    R270 S0      
317P12V_PSU         VIA   -    MD0100PA00X+099416Y+157071X0200Y    R270 S0      
317P12V_PSU         VIA   -    MD0100PA00X+099716Y+157071X0200Y    R270 S0      
317P12V_PSU         VIA   -    MD0100PA00X+098816Y+157071X0200Y    R090 S0      
317P12V_PSU         VIA   -    MD0100PA00X+099116Y+157071X0200Y    R090 S0      
317P12V_PSU         VIA   -    MD0100PA00X+099416Y+157971X0200Y    R270 S0      
317P12V_PSU         VIA   -    MD0100PA00X+099716Y+157971X0200Y    R270 S0      
317P12V_PSU         VIA   -    MD0100PA00X+098816Y+157971X0200Y    R090 S0      
317P12V_PSU         VIA   -    MD0100PA00X+099116Y+157971X0200Y    R090 S0      
317P12V_PSU         VIA   -    MD0100PA00X+098516Y+157971X0200Y    R090 S0      
317P12V_PSU         VIA   -    MD0100PA00X+098516Y+158271X0200Y    R090 S0      
317P12V_PSU         VIA   -    MD0100PA00X+099116Y+158271X0200Y    R090 S0      
317P12V_PSU         VIA   -    MD0100PA00X+098816Y+158271X0200Y    R090 S0      
317P12V_PSU         VIA   -    MD0100PA00X+099716Y+158271X0200Y    R270 S0      
317P12V_PSU         VIA   -    MD0100PA00X+099416Y+158271X0200Y    R270 S0      
317P12V_PSU         VIA   -    MD0100PA00X+096852Y+157057X0200Y    R270 S0      
317P12V_PSU         VIA   -    MD0100PA00X+096852Y+157357X0200Y    R270 S0      
317P12V_PSU         VIA   -    MD0100PA00X+096852Y+157657X0200Y    R270 S0      
317P12V_PSU         VIA   -    MD0100PA00X+096852Y+157957X0200Y    R270 S0      
317P12V_PSU         VIA   -    MD0100PA00X+096852Y+158257X0200Y    R270 S0      
317P12V_PSU         VIA   -    MD0100PA00X+095952Y+157057X0200Y    R090 S0      
317P12V_PSU         VIA   -    MD0100PA00X+095652Y+157057X0200Y    R090 S0      
317P12V_PSU         VIA   -    MD0100PA00X+096552Y+157057X0200Y    R270 S0      
317P12V_PSU         VIA   -    MD0100PA00X+096252Y+157057X0200Y    R270 S0      
317P12V_PSU         VIA   -    MD0100PA00X+096252Y+157357X0200Y    R270 S0      
317P12V_PSU         VIA   -    MD0100PA00X+096552Y+157357X0200Y    R270 S0      
317P12V_PSU         VIA   -    MD0100PA00X+095652Y+157357X0200Y    R090 S0      
317P12V_PSU         VIA   -    MD0100PA00X+095952Y+157357X0200Y    R090 S0      
317P12V_PSU         VIA   -    MD0100PA00X+096252Y+157657X0200Y    R270 S0      
317P12V_PSU         VIA   -    MD0100PA00X+096552Y+157657X0200Y    R270 S0      
317P12V_PSU         VIA   -    MD0100PA00X+095652Y+157657X0200Y    R090 S0      
317P12V_PSU         VIA   -    MD0100PA00X+095952Y+157657X0200Y    R090 S0      
317P12V_PSU         VIA   -    MD0100PA00X+095952Y+157957X0200Y    R090 S0      
317P12V_PSU         VIA   -    MD0100PA00X+095652Y+157957X0200Y    R090 S0      
317P12V_PSU         VIA   -    MD0100PA00X+096552Y+157957X0200Y    R270 S0      
317P12V_PSU         VIA   -    MD0100PA00X+096252Y+157957X0200Y    R270 S0      
317P12V_PSU         VIA   -    MD0100PA00X+096252Y+158257X0200Y    R270 S0      
317P12V_PSU         VIA   -    MD0100PA00X+096552Y+158257X0200Y    R270 S0      
317P12V_PSU         VIA   -    MD0100PA00X+095652Y+158257X0200Y    R090 S0      
317P12V_PSU         VIA   -    MD0100PA00X+095952Y+158257X0200Y    R090 S0      
317P12V_PSU         VIA   -    MD0100PA00X+095352Y+157057X0200Y    R090 S0      
317P12V_PSU         VIA   -    MD0100PA00X+095052Y+157057X0200Y    R090 S0      
317P12V_PSU         VIA   -    MD0100PA00X+095052Y+157357X0200Y    R090 S0      
317P12V_PSU         VIA   -    MD0100PA00X+095352Y+157357X0200Y    R090 S0      
317P12V_PSU         VIA   -    MD0100PA00X+095052Y+157657X0200Y    R090 S0      
317P12V_PSU         VIA   -    MD0100PA00X+095352Y+157657X0200Y    R090 S0      
317P12V_PSU         VIA   -    MD0100PA00X+095352Y+157957X0200Y    R090 S0      
317P12V_PSU         VIA   -    MD0100PA00X+095052Y+157957X0200Y    R090 S0      
317P12V_PSU         VIA   -    MD0100PA00X+095052Y+158257X0200Y    R090 S0      
317P12V_PSU         VIA   -    MD0100PA00X+095352Y+158257X0200Y    R090 S0      
317P12V_PSU         VIA   -    MD0100PA00X+109740Y+156804X0200Y    R270 S0      
317P12V_PSU         VIA   -    MD0100PA00X+108840Y+156804X0200Y    R270 S0      
317P12V_PSU         VIA   -    MD0100PA00X+108540Y+156804X0200Y    R270 S0      
317P12V_PSU         VIA   -    MD0100PA00X+109140Y+156804X0200Y    R270 S0      
317P12V_PSU         VIA   -    MD0100PA00X+109440Y+156804X0200Y    R270 S0      
317P12V_PSU         VIA   -    MD0100PA00X+106622Y+156788X0200Y    R270 S0      
317P12V_PSU         VIA   -    MD0100PA00X+106322Y+156788X0200Y    R270 S0      
317P12V_PSU         VIA   -    MD0100PA00X+106022Y+156788X0200Y    R270 S0      
317P12V_PSU         VIA   -    MD0100PA00X+105722Y+156788X0200Y    R270 S0      
317P12V_PSU         VIA   -    MD0100PA00X+105122Y+156788X0200Y    R090 S0      
317P12V_PSU         VIA   -    MD0100PA00X+105422Y+156788X0200Y    R090 S0      
317P12V_PSU         VIA   -    MD0100PA00X+104822Y+156788X0200Y    R090 S0      
317P12V_PSU         VIA   -    MD0100PA00X+102875Y+156771X0200Y    R270 S0      
317P12V_PSU         VIA   -    MD0100PA00X+103175Y+156771X0200Y    R270 S0      
317P12V_PSU         VIA   -    MD0100PA00X+102575Y+156771X0200Y    R270 S0      
317P12V_PSU         VIA   -    MD0100PA00X+101975Y+156771X0200Y    R090 S0      
317P12V_PSU         VIA   -    MD0100PA00X+102275Y+156771X0200Y    R090 S0      
317P12V_PSU         VIA   -    MD0100PA00X+101675Y+156771X0200Y    R090 S0      
317P12V_PSU         VIA   -    MD0100PA00X+100016Y+156771X0200Y    R270 S0      
317P12V_PSU         VIA   -    MD0100PA00X+098516Y+156771X0200Y    R090 S0      
317P12V_PSU         VIA   -    MD0100PA00X+099116Y+156771X0200Y    R090 S0      
317P12V_PSU         VIA   -    MD0100PA00X+098816Y+156771X0200Y    R090 S0      
317P12V_PSU         VIA   -    MD0100PA00X+099716Y+156771X0200Y    R270 S0      
317P12V_PSU         VIA   -    MD0100PA00X+099416Y+156771X0200Y    R270 S0      
317P12V_PSU         VIA   -    MD0100PA00X+096852Y+156757X0200Y    R270 S0      
317P12V_PSU         VIA   -    MD0100PA00X+096252Y+156757X0200Y    R270 S0      
317P12V_PSU         VIA   -    MD0100PA00X+096552Y+156757X0200Y    R270 S0      
317P12V_PSU         VIA   -    MD0100PA00X+095652Y+156757X0200Y    R090 S0      
317P12V_PSU         VIA   -    MD0100PA00X+095952Y+156757X0200Y    R090 S0      
317P12V_PSU         VIA   -    MD0100PA00X+095052Y+156757X0200Y    R090 S0      
317P12V_PSU         VIA   -    MD0100PA00X+095352Y+156757X0200Y    R090 S0      
317P12V_PSU         VIA   -    MD0100PA00X+092055Y+160653X0200Y    R270 S0      
317P12V_PSU         VIA   -    MD0100PA00X+092055Y+160353X0200Y    R270 S0      
317P12V_PSU         VIA   -    MD0100PA00X+091755Y+160653X0200Y    R270 S0      
317P12V_PSU         VIA   -    MD0100PA00X+091755Y+160353X0200Y    R270 S0      
317P12V_PSU         VIA   -    MD0100PA00X+090555Y+160653X0200Y    R270 S0      
317P12V_PSU         VIA   -    MD0100PA00X+090855Y+160653X0200Y    R270 S0      
317P12V_PSU         VIA   -    MD0100PA00X+091155Y+160653X0200Y    R270 S0      
317P12V_PSU         VIA   -    MD0100PA00X+091155Y+160353X0200Y    R270 S0      
317P12V_PSU         VIA   -    MD0100PA00X+090855Y+160353X0200Y    R270 S0      
317P12V_PSU         VIA   -    MD0100PA00X+090555Y+160353X0200Y    R270 S0      
317P12V_PSU         VIA   -    MD0100PA00X+091455Y+160653X0200Y    R270 S0      
317P12V_PSU         VIA   -    MD0100PA00X+091455Y+160353X0200Y    R270 S0      
317P12V_PSU         VIA   -    MD0100PA00X+090255Y+160653X0200Y    R270 S0      
317P12V_PSU         VIA   -    MD0100PA00X+090255Y+160353X0200Y    R270 S0      
317P12V_PSU         VIA   -    MD0100PA00X+089955Y+160653X0200Y    R270 S0      
317P12V_PSU         VIA   -    MD0100PA00X+087555Y+160353X0200Y    R270 S0      
317P12V_PSU         VIA   -    MD0100PA00X+087855Y+160353X0200Y    R270 S0      
317P12V_PSU         VIA   -    MD0100PA00X+087855Y+160653X0200Y    R270 S0      
317P12V_PSU         VIA   -    MD0100PA00X+087555Y+160653X0200Y    R270 S0      
317P12V_PSU         VIA   -    MD0100PA00X+086055Y+160353X0200Y    R270 S0      
317P12V_PSU         VIA   -    MD0100PA00X+086355Y+160353X0200Y    R270 S0      
317P12V_PSU         VIA   -    MD0100PA00X+086655Y+160353X0200Y    R270 S0      
317P12V_PSU         VIA   -    MD0100PA00X+086955Y+160353X0200Y    R270 S0      
317P12V_PSU         VIA   -    MD0100PA00X+086055Y+160653X0200Y    R270 S0      
317P12V_PSU         VIA   -    MD0100PA00X+086955Y+160653X0200Y    R270 S0      
317P12V_PSU         VIA   -    MD0100PA00X+086655Y+160653X0200Y    R270 S0      
317P12V_PSU         VIA   -    MD0100PA00X+086355Y+160653X0200Y    R270 S0      
317P12V_PSU         VIA   -    MD0100PA00X+087255Y+160353X0200Y    R270 S0      
317P12V_PSU         VIA   -    MD0100PA00X+087255Y+160653X0200Y    R270 S0      
317P12V_PSU         VIA   -    MD0100PA00X+085755Y+160653X0200Y    R270 S0      
317P12V_PSU         VIA   -    MD0100PA00X+083355Y+160653X0200Y    R270 S0      
317P12V_PSU         VIA   -    MD0100PA00X+083055Y+160653X0200Y    R270 S0      
317P12V_PSU         VIA   -    MD0100PA00X+083355Y+160353X0200Y    R270 S0      
317P12V_PSU         VIA   -    MD0100PA00X+083655Y+160353X0200Y    R270 S0      
317P12V_PSU         VIA   -    MD0100PA00X+083655Y+160653X0200Y    R270 S0      
317P12V_PSU         VIA   -    MD0100PA00X+083055Y+160353X0200Y    R270 S0      
317P12V_PSU         VIA   -    MD0100PA00X+082455Y+160353X0200Y    R270 S0      
317P12V_PSU         VIA   -    MD0100PA00X+082755Y+160353X0200Y    R270 S0      
317P12V_PSU         VIA   -    MD0100PA00X+082155Y+160653X0200Y    R270 S0      
317P12V_PSU         VIA   -    MD0100PA00X+082455Y+160653X0200Y    R270 S0      
317P12V_PSU         VIA   -    MD0100PA00X+082755Y+160653X0200Y    R270 S0      
317P12V_PSU         VIA   -    MD0100PA00X+081855Y+160353X0200Y    R270 S0      
317P12V_PSU         VIA   -    MD0100PA00X+082155Y+160353X0200Y    R270 S0      
317P12V_PSU         VIA   -    MD0100PA00X+081855Y+160653X0200Y    R270 S0      
317P12V_PSU         VIA   -    MD0100PA00X+081555Y+160653X0200Y    R270 S0      
317P12V_PSU         VIA   -    MD0100PA00X+078555Y+160353X0200Y    R270 S0      
317P12V_PSU         VIA   -    MD0100PA00X+078855Y+160353X0200Y    R270 S0      
317P12V_PSU         VIA   -    MD0100PA00X+079155Y+160353X0200Y    R270 S0      
317P12V_PSU         VIA   -    MD0100PA00X+078555Y+160653X0200Y    R270 S0      
317P12V_PSU         VIA   -    MD0100PA00X+078855Y+160653X0200Y    R270 S0      
317P12V_PSU         VIA   -    MD0100PA00X+079155Y+160653X0200Y    R270 S0      
317P12V_PSU         VIA   -    MD0100PA00X+078255Y+160653X0200Y    R270 S0      
317P12V_PSU         VIA   -    MD0100PA00X+077655Y+160353X0200Y    R270 S0      
317P12V_PSU         VIA   -    MD0100PA00X+077655Y+160653X0200Y    R270 S0      
317P12V_PSU         VIA   -    MD0100PA00X+077955Y+160353X0200Y    R270 S0      
317P12V_PSU         VIA   -    MD0100PA00X+078255Y+160353X0200Y    R270 S0      
317P12V_PSU         VIA   -    MD0100PA00X+077955Y+160653X0200Y    R270 S0      
317P12V_PSU         VIA   -    MD0100PA00X+074000Y+160666X0200Y    R270 S0      
317P12V_PSU         VIA   -    MD0100PA00X+074300Y+160666X0200Y    R270 S0      
317P12V_PSU         VIA   -    MD0100PA00X+074600Y+160666X0200Y    R270 S0      
317P12V_PSU         VIA   -    MD0100PA00X+074000Y+160366X0200Y    R270 S0      
317P12V_PSU         VIA   -    MD0100PA00X+074300Y+160366X0200Y    R270 S0      
317P12V_PSU         VIA   -    MD0100PA00X+074600Y+160366X0200Y    R270 S0      
317P12V_PSU         VIA   -    MD0100PA00X+073100Y+160666X0200Y    R270 S0      
317P12V_PSU         VIA   -    MD0100PA00X+073100Y+160366X0200Y    R270 S0      
317P12V_PSU         VIA   -    MD0100PA00X+073700Y+160666X0200Y    R270 S0      
317P12V_PSU         VIA   -    MD0100PA00X+073400Y+160666X0200Y    R270 S0      
317P12V_PSU         VIA   -    MD0100PA00X+073700Y+160366X0200Y    R270 S0      
317P12V_PSU         VIA   -    MD0100PA00X+073400Y+160366X0200Y    R270 S0      
317P12V_PSU         VIA   -    MD0100PA00X+091755Y+159453X0200Y    R270 S0      
317P12V_PSU         VIA   -    MD0100PA00X+091755Y+160053X0200Y    R270 S0      
317P12V_PSU         VIA   -    MD0100PA00X+091755Y+159753X0200Y    R270 S0      
317P12V_PSU         VIA   -    MD0100PA00X+090555Y+159753X0200Y    R270 S0      
317P12V_PSU         VIA   -    MD0100PA00X+090855Y+159453X0200Y    R270 S0      
317P12V_PSU         VIA   -    MD0100PA00X+090855Y+160053X0200Y    R270 S0      
317P12V_PSU         VIA   -    MD0100PA00X+090855Y+159753X0200Y    R270 S0      
317P12V_PSU         VIA   -    MD0100PA00X+091155Y+159453X0200Y    R270 S0      
317P12V_PSU         VIA   -    MD0100PA00X+091155Y+160053X0200Y    R270 S0      
317P12V_PSU         VIA   -    MD0100PA00X+091155Y+159753X0200Y    R270 S0      
317P12V_PSU         VIA   -    MD0100PA00X+090555Y+159453X0200Y    R270 S0      
317P12V_PSU         VIA   -    MD0100PA00X+090555Y+160053X0200Y    R270 S0      
317P12V_PSU         VIA   -    MD0100PA00X+091455Y+159453X0200Y    R270 S0      
317P12V_PSU         VIA   -    MD0100PA00X+091455Y+160053X0200Y    R270 S0      
317P12V_PSU         VIA   -    MD0100PA00X+091455Y+159753X0200Y    R270 S0      
317P12V_PSU         VIA   -    MD0100PA00X+087555Y+159453X0200Y    R270 S0      
317P12V_PSU         VIA   -    MD0100PA00X+087555Y+159753X0200Y    R270 S0      
317P12V_PSU         VIA   -    MD0100PA00X+087555Y+160053X0200Y    R270 S0      
317P12V_PSU         VIA   -    MD0100PA00X+087255Y+159753X0200Y    R270 S0      
317P12V_PSU         VIA   -    MD0100PA00X+087255Y+160053X0200Y    R270 S0      
317P12V_PSU         VIA   -    MD0100PA00X+087255Y+159453X0200Y    R270 S0      
317P12V_PSU         VIA   -    MD0100PA00X+086355Y+160053X0200Y    R270 S0      
317P12V_PSU         VIA   -    MD0100PA00X+086355Y+159453X0200Y    R270 S0      
317P12V_PSU         VIA   -    MD0100PA00X+086955Y+159753X0200Y    R270 S0      
317P12V_PSU         VIA   -    MD0100PA00X+086955Y+160053X0200Y    R270 S0      
317P12V_PSU         VIA   -    MD0100PA00X+086955Y+159453X0200Y    R270 S0      
317P12V_PSU         VIA   -    MD0100PA00X+086655Y+159753X0200Y    R270 S0      
317P12V_PSU         VIA   -    MD0100PA00X+086655Y+160053X0200Y    R270 S0      
317P12V_PSU         VIA   -    MD0100PA00X+086655Y+159453X0200Y    R270 S0      
317P12V_PSU         VIA   -    MD0100PA00X+086355Y+159753X0200Y    R270 S0      
317P12V_PSU         VIA   -    MD0100PA00X+083355Y+159453X0200Y    R270 S0      
317P12V_PSU         VIA   -    MD0100PA00X+083055Y+159453X0200Y    R270 S0      
317P12V_PSU         VIA   -    MD0100PA00X+083355Y+160053X0200Y    R270 S0      
317P12V_PSU         VIA   -    MD0100PA00X+083355Y+159753X0200Y    R270 S0      
317P12V_PSU         VIA   -    MD0100PA00X+083055Y+160053X0200Y    R270 S0      
317P12V_PSU         VIA   -    MD0100PA00X+083055Y+159753X0200Y    R270 S0      
317P12V_PSU         VIA   -    MD0100PA00X+082155Y+159753X0200Y    R270 S0      
317P12V_PSU         VIA   -    MD0100PA00X+082455Y+159453X0200Y    R270 S0      
317P12V_PSU         VIA   -    MD0100PA00X+082455Y+160053X0200Y    R270 S0      
317P12V_PSU         VIA   -    MD0100PA00X+082455Y+159753X0200Y    R270 S0      
317P12V_PSU         VIA   -    MD0100PA00X+082755Y+159453X0200Y    R270 S0      
317P12V_PSU         VIA   -    MD0100PA00X+082755Y+160053X0200Y    R270 S0      
317P12V_PSU         VIA   -    MD0100PA00X+082755Y+159753X0200Y    R270 S0      
317P12V_PSU         VIA   -    MD0100PA00X+082155Y+159453X0200Y    R270 S0      
317P12V_PSU         VIA   -    MD0100PA00X+082155Y+160053X0200Y    R270 S0      
317P12V_PSU         VIA   -    MD0100PA00X+078855Y+159753X0200Y    R270 S0      
317P12V_PSU         VIA   -    MD0100PA00X+078555Y+159753X0200Y    R270 S0      
317P12V_PSU         VIA   -    MD0100PA00X+079155Y+159453X0200Y    R270 S0      
317P12V_PSU         VIA   -    MD0100PA00X+078855Y+159453X0200Y    R270 S0      
317P12V_PSU         VIA   -    MD0100PA00X+078555Y+159453X0200Y    R270 S0      
317P12V_PSU         VIA   -    MD0100PA00X+079155Y+160053X0200Y    R270 S0      
317P12V_PSU         VIA   -    MD0100PA00X+078855Y+160053X0200Y    R270 S0      
317P12V_PSU         VIA   -    MD0100PA00X+078555Y+160053X0200Y    R270 S0      
317P12V_PSU         VIA   -    MD0100PA00X+079155Y+159753X0200Y    R270 S0      
317P12V_PSU         VIA   -    MD0100PA00X+077955Y+160053X0200Y    R270 S0      
317P12V_PSU         VIA   -    MD0100PA00X+078255Y+159753X0200Y    R270 S0      
317P12V_PSU         VIA   -    MD0100PA00X+077955Y+159753X0200Y    R270 S0      
317P12V_PSU         VIA   -    MD0100PA00X+077655Y+159453X0200Y    R270 S0      
317P12V_PSU         VIA   -    MD0100PA00X+077655Y+160053X0200Y    R270 S0      
317P12V_PSU         VIA   -    MD0100PA00X+077655Y+159753X0200Y    R270 S0      
317P12V_PSU         VIA   -    MD0100PA00X+078255Y+159453X0200Y    R270 S0      
317P12V_PSU         VIA   -    MD0100PA00X+077955Y+159453X0200Y    R270 S0      
317P12V_PSU         VIA   -    MD0100PA00X+078255Y+160053X0200Y    R270 S0      
317P12V_PSU         VIA   -    MD0100PA00X+074000Y+159446X0200Y    R270 S0      
317P12V_PSU         VIA   -    MD0100PA00X+074000Y+159746X0200Y    R270 S0      
317P12V_PSU         VIA   -    MD0100PA00X+074000Y+160046X0200Y    R270 S0      
317P12V_PSU         VIA   -    MD0100PA00X+074300Y+159446X0200Y    R270 S0      
317P12V_PSU         VIA   -    MD0100PA00X+074600Y+159446X0200Y    R270 S0      
317P12V_PSU         VIA   -    MD0100PA00X+074300Y+159746X0200Y    R270 S0      
317P12V_PSU         VIA   -    MD0100PA00X+074600Y+159746X0200Y    R270 S0      
317P12V_PSU         VIA   -    MD0100PA00X+074300Y+160046X0200Y    R270 S0      
317P12V_PSU         VIA   -    MD0100PA00X+074600Y+160046X0200Y    R270 S0      
317P12V_PSU         VIA   -    MD0100PA00X+073400Y+159446X0200Y    R270 S0      
317P12V_PSU         VIA   -    MD0100PA00X+073100Y+159446X0200Y    R270 S0      
317P12V_PSU         VIA   -    MD0100PA00X+073700Y+159446X0200Y    R270 S0      
317P12V_PSU         VIA   -    MD0100PA00X+073400Y+159746X0200Y    R270 S0      
317P12V_PSU         VIA   -    MD0100PA00X+073100Y+159746X0200Y    R270 S0      
317P12V_PSU         VIA   -    MD0100PA00X+073400Y+160046X0200Y    R270 S0      
317P12V_PSU         VIA   -    MD0100PA00X+073100Y+160046X0200Y    R270 S0      
317P12V_PSU         VIA   -    MD0100PA00X+073700Y+159746X0200Y    R270 S0      
317P12V_PSU         VIA   -    MD0100PA00X+073700Y+160046X0200Y    R270 S0      
317P12V_PSU         VIA   -    MD0100PA00X+091708Y+158236X0200Y    R270 S0      
317P12V_PSU         VIA   -    MD0100PA00X+091708Y+158749X0200Y    R270 S0      
317P12V_PSU         VIA   -    MD0100PA00X+091708Y+157723X0200Y    R270 S0      
317P12V_PSU         VIA   -    MD0100PA00X+091158Y+158749X0200Y    R270 S0      
317P12V_PSU         VIA   -    MD0100PA00X+091158Y+157723X0200Y    R270 S0      
317P12V_PSU         VIA   -    MD0100PA00X+090598Y+158236X0200Y    R270 S0      
317P12V_PSU         VIA   -    MD0100PA00X+090598Y+158749X0200Y    R270 S0      
317P12V_PSU         VIA   -    MD0100PA00X+090598Y+157723X0200Y    R270 S0      
327P12V_PSU         PU297 -33  M      A01X+091158Y+158236X1340Y1340R180 S1      
317P12V_PSU         VIA   -    MD0100PA00X+086958Y+158749X0200Y    R270 S0      
317P12V_PSU         VIA   -    MD0100PA00X+086958Y+157723X0200Y    R270 S0      
317P12V_PSU         VIA   -    MD0100PA00X+086398Y+158749X0200Y    R270 S0      
317P12V_PSU         VIA   -    MD0100PA00X+086398Y+158236X0200Y    R270 S0      
317P12V_PSU         VIA   -    MD0100PA00X+086398Y+157723X0200Y    R270 S0      
317P12V_PSU         VIA   -    MD0100PA00X+087508Y+158749X0200Y    R270 S0      
317P12V_PSU         VIA   -    MD0100PA00X+087508Y+158236X0200Y    R270 S0      
317P12V_PSU         VIA   -    MD0100PA00X+087508Y+157723X0200Y    R270 S0      
327P12V_PSU         PU296 -33  M      A01X+086958Y+158236X1340Y1340R180 S1      
317P12V_PSU         VIA   -    MD0100PA00X+082758Y+158749X0200Y    R270 S0      
317P12V_PSU         VIA   -    MD0100PA00X+082198Y+158749X0200Y    R270 S0      
317P12V_PSU         VIA   -    MD0100PA00X+082198Y+158236X0200Y    R270 S0      
317P12V_PSU         VIA   -    MD0100PA00X+082758Y+157723X0200Y    R270 S0      
317P12V_PSU         VIA   -    MD0100PA00X+082198Y+157723X0200Y    R270 S0      
317P12V_PSU         VIA   -    MD0100PA00X+083308Y+158749X0200Y    R270 S0      
317P12V_PSU         VIA   -    MD0100PA00X+083308Y+158236X0200Y    R270 S0      
317P12V_PSU         VIA   -    MD0100PA00X+083308Y+157723X0200Y    R270 S0      
327P12V_PSU         PU288 -33  M      A01X+082758Y+158236X1340Y1340R180 S1      
317P12V_PSU         VIA   -    MD0100PA00X+077998Y+158749X0200Y    R270 S0      
317P12V_PSU         VIA   -    MD0100PA00X+077998Y+158236X0200Y    R270 S0      
317P12V_PSU         VIA   -    MD0100PA00X+077998Y+157723X0200Y    R270 S0      
317P12V_PSU         VIA   -    MD0100PA00X+079108Y+158749X0200Y    R270 S0      
317P12V_PSU         VIA   -    MD0100PA00X+078558Y+158749X0200Y    R270 S0      
317P12V_PSU         VIA   -    MD0100PA00X+079108Y+158236X0200Y    R270 S0      
317P12V_PSU         VIA   -    MD0100PA00X+078558Y+157723X0200Y    R270 S0      
317P12V_PSU         VIA   -    MD0100PA00X+079108Y+157723X0200Y    R270 S0      
327P12V_PSU         PU287 -33  M      A01X+078558Y+158236X1340Y1340R180 S1      
317P12V_PSU         VIA   -    MD0100PA00X+072778Y+157723X0200Y    R270 S0      
317P12V_PSU         VIA   -    MD0100PA00X+072778Y+158236X0200Y    R270 S0      
317P12V_PSU         VIA   -    MD0100PA00X+073338Y+157723X0200Y    R270 S0      
317P12V_PSU         VIA   -    MD0100PA00X+072778Y+158749X0200Y    R270 S0      
317P12V_PSU         VIA   -    MD0100PA00X+073338Y+158749X0200Y    R270 S0      
317P12V_PSU         VIA   -    MD0100PA00X+073888Y+157723X0200Y    R270 S0      
317P12V_PSU         VIA   -    MD0100PA00X+073888Y+158236X0200Y    R270 S0      
317P12V_PSU         VIA   -    MD0100PA00X+073888Y+158749X0200Y    R270 S0      
327P12V_PSU         PU289 -43  M      A01X+073338Y+158236X1340Y1340R270 S1      
317P12V_OCP_VCC_2   VIA   -           A01X+030782Y+009573X0200Y         S2      
017P12V_OCP_VCC_2   VIA   -           A18X+030782Y+009573X0260Y         S2      
017P12V_OCP_VCC_2         -     D0100PA00X+030782Y+009573                       
327P12V_OCP_VCC_2   PR3830-2   M      A01X+030532Y+009572X0198Y0197R270 S1      
327P12V_OCP_VCC_2   PU201 -A2         A01X+030849Y+008443X0090Y         S1      
327P12V_OCP_VCC_2   PC2098-1   M      A01X+030523Y+009177X0198Y0197R180 S1      
327P12V_OCP_VCC_1   PR3792-2          A01X+177189Y+009724X0198Y0197R270 S1      
327P12V_OCP_VCC_1   PC2085-1   M      A01X+177185Y+009289X0198Y0197R180 S1      
317P12V_OCP_VCC_1   VIA   -    M      A01X+177358Y+008834X0200Y         S2      
017P12V_OCP_VCC_1   VIA   -    M      A18X+177358Y+008834X0260Y         S2      
017P12V_OCP_VCC_1         -    MD0100PA00X+177358Y+008834                       
327P12V_OCP_VCC_1   PU203 -A2         A01X+177361Y+008555X0090Y         S1      
327m4658            R3862 -1          A01X+127574Y+017605X0180Y0200     S1      
327m4658            R3874 -2          A01X+024230Y+012712X0198Y0197R090 S1      
317m4658            VIA   -    MD0100PA00X+024127Y+013072X0200Y         S0      
317m4658            VIA   -    M      A01X+126315Y+012102X0200Y         S2      
017m4658            VIA   -    M      A18X+126315Y+012102X0260Y         S2      
017m4658                  -    MD0100PA00X+126315Y+012102                       
317m4658            VIA   -    MD0100PA00X+127814Y+017605X0200Y         S0      
327m4659            R3860 -1          A01X+123127Y+012824X0180Y0200     S1      
317m4659            VIA   -    M      A01X+024381Y+013238X0300Y         S1      
017m4659            VIA   -    M      A18X+024381Y+013238X0200Y         S1      
017m4659                  -    MD0100PA00X+024381Y+013238                       
327m4659            R3873 -2          A01X+024630Y+012712X0198Y0197R090 S1      
317m4659            VIA   -    MD0100PA00X+123367Y+012824X0200Y         S0      
327m4660            R3868 -2          A01X+023515Y+012712X0180Y0200     S1      
327m4660            R3861 -1          A01X+126944Y+017605X0180Y0200R180 S1      
317m4660            VIA   -    MD0100PA00X+023515Y+012444X0200Y         S0      
317m4660            VIA   -    M      A01X+126915Y+012102X0200Y         S2      
017m4660            VIA   -    M      A18X+126915Y+012102X0260Y         S2      
017m4660                  -    MD0100PA00X+126915Y+012102                       
317m4660            VIA   -    MD0100PA00X+126704Y+017503X0200Y         S0      
327m4661            R3867 -2          A01X+023830Y+012397X0180Y0200R090 S1      
327m4661            R3859 -1          A01X+122497Y+012824X0180Y0200R180 S1      
317m4661            VIA   -    MD0100PA00X+023830Y+012156X0200Y         S0      
317m4661            VIA   -    M      A01X+122151Y+012824X0200Y         S2      
017m4661            VIA   -    M      A18X+122151Y+012824X0260Y         S2      
017m4661                  -    MD0100PA00X+122151Y+012824                       
327m4662            R1193 -2          A01X+027978Y+012399X0198Y0197R270 S1      
327m4662            R3630 -2   M      A01X+027580Y+012397X0198Y0197R270 S1      
317m4662            VIA   -    M      A01X+027579Y+012025X0200Y         S2      
017m4662            VIA   -    M      A18X+027579Y+012025X0260Y         S2      
017m4662                  -    MD0100PA00X+027579Y+012025                       
327m4662            PU206 -1          A01X+027430Y+011522X0098Y0335R180 S1      
327P12V_OCP_V3_2    PC2141-1          A18X+025897Y+007893X0400Y0500R180 S2      
317P12V_OCP_V3_2    VIA   -    MD0100PA00X+010168Y+016069X0200Y         S0      
327P12V_OCP_V3_2    C1109 -1   M      A01X+010168Y+015819X0198Y0197     S1      
327P12V_OCP_V3_2    U56   -11         A01X+009697Y+015778X0090Y0240R270 S1      
327P12V_OCP_V3_2    PU206 -14         A01X+026249Y+010429X0100Y0320R180 S1      
327P12V_OCP_V3_2    PU206 -15         A01X+026446Y+010429X0100Y0320R180 S1      
327P12V_OCP_V3_2    PU206 -16         A01X+026643Y+010429X0100Y0320R180 S1      
327P12V_OCP_V3_2    PU206 -17         A01X+026840Y+010429X0100Y0320R180 S1      
327P12V_OCP_V3_2    PU206 -18         A01X+027036Y+010429X0100Y0320R180 S1      
327P12V_OCP_V3_2    PU206 -19         A01X+027233Y+010429X0100Y0320R180 S1      
327P12V_OCP_V3_2    PU206 -20         A01X+027430Y+010429X0100Y0320R180 S1      
327P12V_OCP_V3_2    PC2174-1          A01X+027369Y+009918X0198Y0197     S1      
327P12V_OCP_V3_2    PU206 -13         A01X+026052Y+010429X0100Y0320R180 S1      
327P12V_OCP_V3_2    PU201 -A4         A01X+031243Y+008443X0090Y         S1      
327P12V_OCP_V3_2    PU201 -B4         A01X+031243Y+008246X0090Y         S1      
327P12V_OCP_V3_2    PU201 -B6         A01X+031636Y+008246X0090Y         S1      
327P12V_OCP_V3_2    PU201 -C4         A01X+031243Y+008049X0090Y         S1      
327P12V_OCP_V3_2    PU201 -C6         A01X+031636Y+008049X0090Y         S1      
327P12V_OCP_V3_2    PU201 -D4         A01X+031243Y+007852X0090Y         S1      
327P12V_OCP_V3_2    PU201 -D6         A01X+031636Y+007852X0090Y         S1      
327P12V_OCP_V3_2    PR3850-1          A01X+026087Y+008754X0198Y0197R180 S1      
327P12V_OCP_V3_2    PC2143-1          A01X+025897Y+007893X0400Y0500     S1      
327P12V_OCP_V3_2    PR3852-1          A01X+024349Y+010468X0198Y0197R090 S1      
327P12V_OCP_V3_2    PR4522-1          A01X+032018Y+009984X0198Y0197R180 S1      
327P12V_OCP_V3_2    C40   -1   M      A01X+032017Y+009585X0198Y0197R180 S1      
317P12V_OCP_V3_2    VIA   -    MD0100PA00X+030647Y+006516X0200Y         S0      
327P12V_OCP_V3_2    R1291 -1          A01X+028203Y+007454X0198Y0197R180 S1      
327P12V_OCP_V3_2    PC2152-1          A01X+025788Y+007340X0198Y0197R180 S1      
327P12V_OCP_V3_2    PD108 -C          A01X+031269Y+005975X0670Y0990R270 S1      
327P12V_OCP_V3_2    R1325 -2          A01X+028892Y+006424X1150Y1380     S1      
317P12V_OCP_V3_2    VIA   -    MD0100PA00X+030385Y+006504X0200Y         S0      
317P12V_OCP_V3_2    VIA   -    M      A01X+027362Y+009666X0200Y         S2      
017P12V_OCP_V3_2    VIA   -    M      A18X+027362Y+009666X0260Y         S2      
017P12V_OCP_V3_2          -    MD0100PA00X+027362Y+009666                       
317P12V_OCP_V3_2    VIA   -    MD0100PA00X+026992Y+009796X0200Y         S0      
317P12V_OCP_V3_2    VIA   -    MD0100PA00X+026642Y+009796X0200Y         S0      
317P12V_OCP_V3_2    VIA   -    MD0100PA00X+026292Y+009796X0200Y         S0      
317P12V_OCP_V3_2    VIA   -    MD0100PA00X+026842Y+010066X0200Y         S0      
317P12V_OCP_V3_2    VIA   -    MD0100PA00X+026492Y+010066X0200Y         S0      
317P12V_OCP_V3_2    VIA   -    MD0100PA00X+026142Y+010066X0200Y         S0      
317P12V_OCP_V3_2    VIA   -    MD0100PA00X+026318Y+007340X0200Y         S0      
317P12V_OCP_V3_2    VIA   -    MD0100PA00X+026332Y+008766X0200Y         S0      
317P12V_OCP_V3_2    VIA   -    MD0100PA00X+026289Y+008003X0200Y         S0      
317P12V_OCP_V3_2    VIA   -    MD0100PA00X+026289Y+007753X0200Y         S0      
317P12V_OCP_V3_2    VIA   -    MD0100PA00X+031465Y+006891X0200Y         S0      
317P12V_OCP_V3_2    VIA   -    MD0100PA00X+031465Y+007181X0200Y         S0      
327m4663            R3827 -1          A01X+026010Y+015389X0198Y0197R090 S1      
327m4663            VIA   -    M      A01X+025482Y+015194X0300Y         S1      
327m4663            Q118  -3          A01X+024970Y+014944X0170Y0200R270 S1      
327P12V_OCP_UV_2    PR3805-2          A01X+030124Y+007113X0198Y0197     S1      
327P12V_OCP_UV_2    PR3806-1   M      A01X+030527Y+007118X0198Y0197R270 S1      
317P12V_OCP_UV_2    VIA   -    M      A01X+030582Y+007369X0200Y    R270 S2      
017P12V_OCP_UV_2    VIA   -    M      A18X+030582Y+007369X0260Y    R270 S2      
017P12V_OCP_UV_2          -    MD0100PA00X+030582Y+007369                       
327P12V_OCP_UV_2    PU201 -D2         A01X+030849Y+007852X0090Y         S1      
327P12V_OCP_UV_2    R3827 -2          A01X+026010Y+015704X0198Y0197R090 S1      
317P12V_OCP_UV_2    VIA   -    MD0100PA00X+026250Y+016110X0200Y    R180 S0      
327m4664            Q123  -3          A01X+183512Y+016439X0170Y0200R270 S1      
327m4664            R3784 -1          A01X+179296Y+015683X0198Y0197R180 S1      
327m4664            VIA   -    M      A01X+179776Y+015683X0300Y    R270 S1      
327P12V_OCP_UV_1    R3784 -2          A01X+178982Y+015683X0198Y0197R180 S1      
317P12V_OCP_UV_1    VIA   -    M      A01X+178739Y+015683X0200Y    R270 S2      
017P12V_OCP_UV_1    VIA   -    M      A18X+178739Y+015683X0260Y    R270 S2      
017P12V_OCP_UV_1          -    MD0100PA00X+178739Y+015683                       
317P12V_OCP_UV_1    VIA   -    MD0100PA00X+177033Y+007274X0200Y    R270 S0      
327P12V_OCP_UV_1    PU203 -D2         A01X+177361Y+007964X0090Y         S1      
327P12V_OCP_UV_1    PR3786-2          A01X+176361Y+007264X0198Y0197     S1      
327P12V_OCP_UV_1    PR3787-1   M      A01X+176764Y+007269X0198Y0197R270 S1      
327m4665            PC2164-1          A01X+027180Y+012397X0198Y0197R090 S1      
317m4665            VIA   -    M      A01X+026949Y+012110X0200Y         S2      
017m4665            VIA   -    M      A18X+026949Y+012110X0260Y         S2      
017m4665                  -    MD0100PA00X+026949Y+012110                       
327m4665            PU206 -4          A01X+026840Y+011532X0100Y0320R180 S1      
327m4666            PC2153-1          A01X+174692Y+012509X0198Y0197R090 S1      
317m4666            VIA   -    M      A01X+174498Y+012300X0200Y         S2      
017m4666            VIA   -    M      A18X+174498Y+012300X0260Y         S2      
017m4666                  -    MD0100PA00X+174498Y+012300                       
327m4666            PU204 -4          A01X+174352Y+011644X0100Y0320R180 S1      
327P12V_OCP_SS_2    PU206 -6          A01X+026446Y+011532X0100Y0320R180 S1      
317P12V_OCP_SS_2    VIA   -    M      A01X+026429Y+012097X0200Y         S2      
017P12V_OCP_SS_2    VIA   -    M      A18X+026429Y+012097X0260Y         S2      
017P12V_OCP_SS_2          -    MD0100PA00X+026429Y+012097                       
327P12V_OCP_SS_2    PC2166-1          A01X+026130Y+012397X0198Y0197R090 S1      
327P12V_OCP_SS_1    PC2155-1          A01X+173642Y+012509X0198Y0197R090 S1      
317P12V_OCP_SS_1    VIA   -    M      A01X+173969Y+012094X0200Y         S2      
017P12V_OCP_SS_1    VIA   -    M      A18X+173969Y+012094X0260Y         S2      
017P12V_OCP_SS_1          -    MD0100PA00X+173969Y+012094                       
327P12V_OCP_SS_1    PU204 -6          A01X+173958Y+011644X0100Y0320R180 S1      
327m4667            R3866 -1          A01X+126944Y+018056X0180Y0200R180 S1      
317m4667            VIA   -    M      A01X+126704Y+018056X0200Y         S2      
017m4667            VIA   -    M      A18X+126704Y+018056X0260Y         S2      
017m4667                  -    MD0100PA00X+126704Y+018056                       
317m4667            VIA   -    MD0100PA00X+126894Y+020602X0200Y         S0      
327m4667            R3872 -2          A01X+171742Y+012824X0198Y0197R090 S1      
317m4667            VIA   -    MD0100PA00X+171738Y+013537X0200Y    R180 S0      
327m4668            R3864 -1          A01X+123127Y+013274X0180Y0200     S1      
317m4668            VIA   -    M      A01X+172138Y+013537X0300Y    R180 S1      
017m4668            VIA   -    M      A18X+172138Y+013537X0200Y    R180 S1      
017m4668                  -    MD0100PA00X+172138Y+013537                       
317m4668            VIA   -    MD0100PA00X+123367Y+013274X0200Y         S0      
317m4668            VIA   -    MD0100PA00X+130630Y+020392X0200Y         S0      
327m4668            R3871 -2          A01X+172142Y+012824X0198Y0197R090 S1      
327m4669            R3865 -1          A01X+127574Y+018056X0180Y0200     S1      
317m4669            VIA   -    M      A01X+127945Y+021329X0200Y         S2      
017m4669            VIA   -    M      A18X+127945Y+021329X0260Y         S2      
017m4669                  -    MD0100PA00X+127945Y+021329                       
317m4669            VIA   -    MD0100PA00X+127814Y+018056X0200Y         S0      
327m4669            R3870 -2          A01X+171331Y+014130X0198Y0197R090 S1      
317m4669            VIA   -    MD0100PA00X+171661Y+014130X0200Y         S0      
327m4670            R3863 -1          A01X+122497Y+013274X0180Y0200R180 S1      
317m4670            VIA   -    M      A01X+122141Y+013423X0200Y         S2      
017m4670            VIA   -    M      A18X+122141Y+013423X0260Y         S2      
017m4670                  -    MD0100PA00X+122141Y+013423                       
317m4670            VIA   -    MD0100PA00X+170512Y+014361X0200Y         S0      
327m4670            R3869 -2          A01X+171342Y+012509X0198Y0197R270 S1      
317m4670            VIA   -    MD0100PA00X+126936Y+021963X0200Y         S0      
327P12V_OCP_SFF     PC2080-1          A18X+173639Y+008635X0400Y0500R180 S2      
327P12V_OCP_SFF     U55   -11         A01X+156173Y+030140X0090Y0240R270 S1      
327P12V_OCP_SFF     C1108 -1   M      A01X+156644Y+030182X0198Y0197     S1      
317P12V_OCP_SFF     VIA   -    MD0100PA00X+157152Y+031910X0200Y         S0      
327P12V_OCP_SFF     PU204 -14         A01X+173761Y+010542X0100Y0320R180 S1      
327P12V_OCP_SFF     PU204 -15         A01X+173958Y+010542X0100Y0320R180 S1      
327P12V_OCP_SFF     PU204 -16         A01X+174155Y+010542X0100Y0320R180 S1      
327P12V_OCP_SFF     PU204 -17         A01X+174352Y+010542X0100Y0320R180 S1      
327P12V_OCP_SFF     PU204 -18         A01X+174548Y+010542X0100Y0320R180 S1      
327P12V_OCP_SFF     PU204 -19         A01X+174745Y+010542X0100Y0320R180 S1      
327P12V_OCP_SFF     PU204 -20         A01X+174942Y+010542X0100Y0320R180 S1      
327P12V_OCP_SFF     PC2160-1          A01X+174881Y+010031X0198Y0197     S1      
327P12V_OCP_SFF     PU204 -13         A01X+173564Y+010542X0100Y0320R180 S1      
327P12V_OCP_SFF     PU203 -B6         A01X+178148Y+008358X0090Y         S1      
327P12V_OCP_SFF     PU203 -C6         A01X+178148Y+008161X0090Y         S1      
327P12V_OCP_SFF     PU203 -D6         A01X+178148Y+007964X0090Y         S1      
327P12V_OCP_SFF     PU203 -A4         A01X+177755Y+008555X0090Y         S1      
327P12V_OCP_SFF     PU203 -B4         A01X+177755Y+008358X0090Y         S1      
327P12V_OCP_SFF     PU203 -C4         A01X+177755Y+008161X0090Y         S1      
327P12V_OCP_SFF     PU203 -D4         A01X+177755Y+007964X0090Y         S1      
327P12V_OCP_SFF     PC2092-1          A01X+175336Y+008541X0198Y0197     S1      
327P12V_OCP_SFF     PC2082-1          A01X+175064Y+009308X0400Y0500R180 S1      
327P12V_OCP_SFF     R1284 -1          A01X+174688Y+008534X0198Y0197R180 S1      
327P12V_OCP_SFF     PR3838-1   M      A01X+173619Y+008983X0198Y0197R180 S1      
327P12V_OCP_SFF     PR3840-1          A01X+171861Y+010101X0198Y0197R090 S1      
327P12V_OCP_SFF     PC2088-1   M      A01X+178525Y+009693X0198Y0197R180 S1      
327P12V_OCP_SFF     PR4524-1          A01X+178521Y+010094X0198Y0197R180 S1      
327P12V_OCP_SFF     R1324 -2          A01X+174887Y+007504X1150Y1380     S1      
327P12V_OCP_SFF     PD102 -C          A01X+178436Y+006104X0670Y0990R270 S1      
317P12V_OCP_SFF     VIA   -    MD0100PA00X+174162Y+007411X0200Y         S0      
317P12V_OCP_SFF     VIA   -    M      A01X+174869Y+009741X0200Y         S2      
017P12V_OCP_SFF     VIA   -    M      A18X+174869Y+009741X0260Y         S2      
017P12V_OCP_SFF           -    MD0100PA00X+174869Y+009741                       
317P12V_OCP_SFF     VIA   -    MD0100PA00X+173673Y+010229X0200Y         S0      
317P12V_OCP_SFF     VIA   -    MD0100PA00X+174373Y+010229X0200Y         S0      
317P12V_OCP_SFF     VIA   -    MD0100PA00X+174023Y+010229X0200Y         S0      
317P12V_OCP_SFF     VIA   -    MD0100PA00X+174544Y+010024X0200Y         S0      
317P12V_OCP_SFF     VIA   -    MD0100PA00X+174194Y+010024X0200Y         S0      
317P12V_OCP_SFF     VIA   -    MD0100PA00X+173844Y+010024X0200Y         S0      
317P12V_OCP_SFF     VIA   -    MD0100PA00X+174162Y+008011X0200Y         S0      
317P12V_OCP_SFF     VIA   -    MD0100PA00X+174162Y+008261X0200Y         S0      
317P12V_OCP_SFF     VIA   -    MD0100PA00X+174162Y+007661X0200Y         S0      
317P12V_OCP_SFF     VIA   -    MD0100PA00X+177429Y+005719X0200Y         S0      
317P12V_OCP_SFF     VIA   -    MD0100PA00X+177974Y+007007X0200Y         S0      
317P12V_OCP_SFF     VIA   -    MD0100PA00X+177974Y+007297X0200Y         S0      
317P12V_OCP_SFF     VIA   -    MD0100PA00X+177429Y+006013X0200Y         S0      
317P12V_OCP_SFF     VIA   -    MD0100PA00X+177429Y+006303X0200Y         S0      
327m4671            R3867 -1          A01X+023830Y+012712X0180Y0200R090 S1      
327m4671            R3868 -1   M      A01X+023830Y+012712X0180Y0200     S1      
317m4671            VIA   -    MD0100PA00X+023860Y+013040X0200Y         S0      
327m4671            PU201 -A1         A01X+030652Y+008443X0090Y         S1      
317m4671            VIA   -    M      A01X+029900Y+008870X0200Y    R180 S2      
017m4671            VIA   -    M      A18X+029900Y+008870X0260Y    R180 S2      
017m4671                  -    MD0100PA00X+029900Y+008870                       
327m4671            PR3823-1   M      A01X+029900Y+008598X0198Y0197R180 S1      
317m4672            VIA   -    M      A01X+171340Y+013286X0200Y         S2      
017m4672            VIA   -    M      A18X+171340Y+013286X0260Y         S2      
017m4672                  -    MD0100PA00X+171340Y+013286                       
327m4672            R3870 -1          A01X+171331Y+013815X0198Y0197R090 S1      
327m4672            R3869 -1          A01X+171342Y+012824X0198Y0197R270 S1      
317m4672            VIA   -    MD0100PA00X+176142Y+009002X0200Y         S0      
327m4672            PU203 -A1         A01X+177164Y+008555X0090Y         S1      
327m4672            PR3781-1   M      A01X+176412Y+008711X0198Y0197R180 S1      
317P12V_OCP_REG_2   VIA   -    M      A01X+030111Y+007568X0200Y         S2      
017P12V_OCP_REG_2   VIA   -    M      A18X+030111Y+007568X0260Y         S2      
017P12V_OCP_REG_2         -    MD0100PA00X+030111Y+007568                       
327P12V_OCP_REG_2   PC2146-2          A01X+029852Y+007567X0198Y0197     S1      
327P12V_OCP_REG_2   PU201 -D1         A01X+030652Y+007852X0090Y         S1      
327P12V_OCP_REG_1   PU203 -D1         A01X+177164Y+007964X0090Y         S1      
317P12V_OCP_REG_1   VIA   -    M      A01X+176796Y+007684X0200Y         S2      
017P12V_OCP_REG_1   VIA   -    M      A18X+176796Y+007684X0260Y         S2      
017P12V_OCP_REG_1         -    MD0100PA00X+176796Y+007684                       
327P12V_OCP_REG_1   PC2087-2          A01X+176364Y+007680X0198Y0197     S1      
327m4673            PU201 -D7         A01X+031833Y+007852X0090Y         S1      
317m4673            VIA   -    M      A01X+032019Y+007765X0200Y         S2      
017m4673            VIA   -    M      A18X+032019Y+007765X0260Y         S2      
017m4673                  -    MD0100PA00X+032019Y+007765                       
327m4673            R3831 -1          A01X+032247Y+006986X0198Y0197     S1      
327m4674            R3144 -1          A01X+178759Y+007099X0198Y0197     S1      
317m4674            VIA   -    M      A01X+178511Y+007608X0200Y         S2      
017m4674            VIA   -    M      A18X+178511Y+007608X0260Y         S2      
017m4674                  -    MD0100PA00X+178511Y+007608                       
327m4674            PU203 -D7         A01X+178345Y+007964X0090Y         S1      
327m4675            VIA   -           A01X+023793Y+010784X0300Y         S1      
327m4675            PR3852-2   M      A01X+024349Y+010784X0198Y0197R090 S1      
327m4675            PR3853-2   M      A01X+024749Y+010784X0198Y0197R090 S1      
327m4675            PU206 -11         A01X+025698Y+010784X0100Y0320R270 S1      
327m4675            PR3854-1   M      A01X+025149Y+010784X0198Y0197R270 S1      
327m4676            PR3840-2          A01X+171861Y+010416X0198Y0197R090 S1      
327m4676            VIA   -    M      A01X+171781Y+010896X0300Y    R270 S1      
327m4676            PR3841-2   M      A01X+172261Y+010896X0198Y0197R090 S1      
327m4676            PU204 -11         A01X+173210Y+010896X0100Y0320R270 S1      
327m4676            PR3842-1   M      A01X+172661Y+010896X0198Y0197R270 S1      
327P12V_OCP_OV_2    PR3806-2   M      A01X+030527Y+006803X0198Y0197R270 S1      
327P12V_OCP_OV_2    PR3828-1          A01X+030124Y+006713X0198Y0197R180 S1      
327P12V_OCP_OV_2    PU201 -D3         A01X+031046Y+007852X0090Y         S1      
317P12V_OCP_OV_2    VIA   -    M      A01X+031046Y+007590X0200Y         S2      
017P12V_OCP_OV_2    VIA   -    M      A18X+031046Y+007590X0260Y         S2      
017P12V_OCP_OV_2          -    MD0100PA00X+031046Y+007590                       
317P12V_OCP_OV_1    VIA   -    M      A01X+177555Y+007338X0200Y         S2      
017P12V_OCP_OV_1    VIA   -    M      A18X+177555Y+007338X0260Y         S2      
017P12V_OCP_OV_1          -    MD0100PA00X+177555Y+007338                       
327P12V_OCP_OV_1    PU203 -D3         A01X+177558Y+007964X0090Y         S1      
327P12V_OCP_OV_1    PR3788-1          A01X+176361Y+006864X0198Y0197R180 S1      
327P12V_OCP_OV_1    PR3787-2   M      A01X+176764Y+006954X0198Y0197R270 S1      
327m4677            PU206 -5          A01X+026643Y+011532X0100Y0320R180 S1      
317m4677            VIA   -    M      A01X+026600Y+012580X0200Y         S2      
017m4677            VIA   -    M      A18X+026600Y+012580X0260Y         S2      
017m4677                  -    MD0100PA00X+026600Y+012580                       
327m4677            PR3847-1          A01X+026830Y+012747X0198Y0197R090 S1      
327m4678            PR3835-1          A01X+174342Y+012859X0198Y0197R090 S1      
327m4678            VIA   -    M      A01X+174185Y+012377X0300Y         S1      
327m4678            PU204 -5          A01X+174155Y+011644X0100Y0320R180 S1      
327m4679            PC2167-1   M      A01X+025430Y+012397X0198Y0197R090 S1      
327m4679            PR3849-1   M      A01X+025030Y+012397X0198Y0197R090 S1      
327m4679            R3873 -1   M      A01X+024630Y+012397X0198Y0197R090 S1      
327m4679            PU206 -8          A01X+026052Y+011532X0100Y0320R180 S1      
327m4679            VIA   -    M      A01X+024220Y+011930X0300Y         S1      
327m4679            R3874 -1          A01X+024230Y+012397X0198Y0197R090 S1      
327m4680            R3872 -1          A01X+171742Y+012509X0198Y0197R090 S1      
327m4680            VIA   -    M      A01X+171688Y+012028X0300Y    R180 S1      
327m4680            R3871 -1   M      A01X+172142Y+012509X0198Y0197R090 S1      
327m4680            PR3837-1   M      A01X+172542Y+012509X0198Y0197R090 S1      
327m4680            PC2156-1   M      A01X+172942Y+012509X0198Y0197R090 S1      
327m4680            PU204 -8          A01X+173564Y+011644X0100Y0320R180 S1      
327m4681            PC2150-1   M      A01X+031698Y+009180X0198Y0197     S1      
327m4681            PU201 -A6         A01X+031636Y+008443X0090Y         S1      
317m4681            VIA   -    M      A01X+031698Y+008900X0200Y         S2      
017m4681            VIA   -    M      A18X+031698Y+008900X0260Y         S2      
017m4681                  -    MD0100PA00X+031698Y+008900                       
327m4681            PR4522-2          A01X+031703Y+009984X0198Y0197R180 S1      
327m4681            C40   -2   M      A01X+031702Y+009585X0198Y0197R180 S1      
327m4682            PC4056-1   M      A01X+178210Y+009293X0198Y0197     S1      
317m4682            VIA   -    M      A01X+178145Y+008824X0200Y         S2      
017m4682            VIA   -    M      A18X+178145Y+008824X0260Y         S2      
017m4682                  -    MD0100PA00X+178145Y+008824                       
327m4682            PU203 -A6         A01X+178148Y+008555X0090Y         S1      
327m4682            PR4524-2          A01X+178206Y+010094X0198Y0197R180 S1      
327m4682            PC2088-2   M      A01X+178210Y+009693X0198Y0197R180 S1      
327m4683            PU206 -9          A01X+025855Y+011532X0100Y0320R180 S1      
327m4683            PR3851-1          A01X+025037Y+011574X0198Y0197R180 S1      
317m4683            VIA   -           A01X+025280Y+011480X0200Y         S2      
017m4683            VIA   -           A18X+025280Y+011480X0260Y         S2      
017m4683                  -     D0100PA00X+025280Y+011480                       
327m4684            PU204 -9          A01X+173367Y+011644X0100Y0320R180 S1      
327m4684            PR3839-1          A01X+172549Y+011687X0198Y0197R180 S1      
317m4684            VIA   -           A01X+172905Y+011818X0200Y         S2      
017m4684            VIA   -           A18X+172905Y+011818X0260Y         S2      
017m4684                  -     D0100PA00X+172905Y+011818                       
327m4685            R3816 -2          A01X+032562Y+008432X0198Y0197R090 S1      
317m4685            VIA   -    M      A01X+032287Y+008432X0200Y         S2      
017m4685            VIA   -    M      A18X+032287Y+008432X0260Y         S2      
017m4685                  -    MD0100PA00X+032287Y+008432                       
327m4685            PU201 -C7         A01X+031833Y+008049X0090Y         S1      
327m4686            R3799 -2          A01X+179074Y+008544X0198Y0197R090 S1      
317m4686            VIA   -    M      A01X+178776Y+008518X0200Y         S2      
017m4686            VIA   -    M      A18X+178776Y+008518X0260Y         S2      
017m4686                  -    MD0100PA00X+178776Y+008518                       
327m4686            PU203 -C7         A01X+178345Y+008161X0090Y         S1      
327m4687            R1181 -2          A01X+026703Y+013730X0198Y0197R180 S1      
327m4687            R6060 -1   M      A01X+025974Y+014488X0198Y0197     S1      
327m4687            R4059 -2   M      A01X+025974Y+014088X0198Y0197     S1      
327m4687            VIA   -    M      A01X+025494Y+014688X0300Y    R180 S1      
327m4687            Q118  -2          A01X+024970Y+014688X0170Y0200R270 S1      
327m4688            R591  -2          A01X+175732Y+012510X0198Y0197R270 S1      
327m4688            R3834 -2   M      A01X+175092Y+012509X0198Y0197R270 S1      
317m4688            VIA   -    M      A01X+175079Y+012002X0200Y         S2      
017m4688            VIA   -    M      A18X+175079Y+012002X0260Y         S2      
017m4688                  -    MD0100PA00X+175079Y+012002                       
327m4688            PU204 -1          A01X+174942Y+011634X0098Y0335R180 S1      
327m4689            R561  -2          A01X+184469Y+017029X0198Y0197R180 S1      
327m4689            R6045 -1   M      A01X+184472Y+016183X0198Y0197     S1      
327m4689            R4061 -2   M      A01X+184472Y+016583X0198Y0197R180 S1      
327m4689            Q123  -2          A01X+183512Y+016183X0170Y0200R270 S1      
327m4689            VIA   -    M      A01X+183992Y+016183X0300Y    R090 S1      
327m4690            R152  -1          A01X+065958Y+043386X0198Y0197R180 S1      
327m4690            U18   -F9         A01X+071308Y+044509X0160Y    R090 S1      
317m4690            VIA   -    M      A01X+066200Y+043386X0200Y    R270 S2      
017m4690            VIA   -    M      A18X+066200Y+043386X0260Y    R270 S2      
017m4690                  -    MD0100PA00X+066200Y+043386                       
317m4690            VIA   -    MD0100PA00X+071154Y+044356X0180Y    R090 S0      
327P12V_OCP_CB_2    PR3821-1          A01X+029900Y+008248X0198Y0197R180 S1      
317P12V_OCP_CB_2    VIA   -    M      A01X+030178Y+008290X0200Y         S2      
017P12V_OCP_CB_2    VIA   -    M      A18X+030178Y+008290X0260Y         S2      
017P12V_OCP_CB_2          -    MD0100PA00X+030178Y+008290                       
327P12V_OCP_CB_2    PU201 -B1         A01X+030652Y+008246X0090Y         S1      
327P12V_OCP_CB_1    PR5484-1          A01X+176412Y+008361X0198Y0197R180 S1      
317P12V_OCP_CB_1    VIA   -    M      A01X+176714Y+008365X0200Y         S2      
017P12V_OCP_CB_1    VIA   -    M      A18X+176714Y+008365X0260Y         S2      
017P12V_OCP_CB_1          -    MD0100PA00X+176714Y+008365                       
327P12V_OCP_CB_1    PU203 -B1         A01X+177164Y+008358X0090Y         S1      
327m4691            PU206 -12         A01X+025855Y+010429X0100Y0320R180 S1      
327m4691            PC1320-1          A01X+025729Y+009763X0280Y0320R090 S1      
327m4691            PR3857-2          A01X+025729Y+009273X0280Y0320R270 S1      
327m4691            PR3850-2   M      A01X+025772Y+008754X0198Y0197R180 S1      
327m4691            VIA   -           A01X+025309Y+008736X0300Y         S1      
327m4692            PU204 -12         A01X+173367Y+010542X0100Y0320R180 S1      
327m4692            PR3843-2          A01X+173241Y+009453X0280Y0320R270 S1      
327m4692            PC2158-1          A01X+173241Y+009973X0280Y0320R090 S1      
327m4692            PR3838-2          A01X+173304Y+008983X0198Y0197R180 S1      
327m4692            VIA   -           A01X+172961Y+009001X0300Y    R180 S1      
327m4693            R4065 -2          A01X+023412Y+014206X0198Y0197R180 S1      
327m4693            VIA   -    M      A01X+023692Y+014683X0300Y    R180 S1      
327m4693            Q118  -5   M      A01X+024222Y+014688X0170Y0200R270 S1      
327m4693            Q118  -6          A01X+024222Y+014432X0170Y0200R270 S1      
327m4694            Q123  -6   M      A01X+182764Y+015928X0170Y0200R270 S1      
327m4694            Q123  -5          A01X+182764Y+016183X0170Y0200R270 S1      
327m4694            VIA   -           A01X+181490Y+015680X0300Y    R270 S1      
327m4694            R4068 -2   M      A01X+181970Y+015680X0198Y0197R270 S1      
317P12V_E1S_VCC_0   VIA   -    M      A01X+100283Y+017248X0200Y    R180 S2      
017P12V_E1S_VCC_0   VIA   -    M      A18X+100283Y+017248X0260Y    R180 S2      
017P12V_E1S_VCC_0         -    MD0100PA00X+100283Y+017248                       
327P12V_E1S_VCC_0   PR3966-2          A01X+100980Y+017128X0198Y0197R180 S1      
327P12V_E1S_VCC_0   PU294 -A2         A01X+099836Y+016951X0090Y    R270 S1      
327P12V_E1S_VCC_0   PC2209-1   M      A01X+100570Y+017127X0198Y0197R090 S1      
327m4695            R3958 -1          A18X+098456Y+018056X0198Y0197R090 S2      
317m4695            VIA   -    M      A01X+099730Y+023488X0200Y         S2      
017m4695            VIA   -    M      A18X+099730Y+023488X0260Y         S2      
017m4695                  -    MD0100PA00X+099730Y+023488                       
327m4695            Q127  -3          A01X+099769Y+025822X0170Y0200R090 S1      
327P12V_E1S_UV_0    R3958 -2          A18X+098456Y+017741X0198Y0197R090 S2      
327P12V_E1S_UV_0    PR3960-2          A01X+098544Y+017951X0198Y0197R270 S1      
327P12V_E1S_UV_0    PR3961-1   M      A01X+098550Y+017548X0198Y0197R180 S1      
327P12V_E1S_UV_0    PU294 -D2         A01X+099245Y+016951X0090Y    R270 S1      
317P12V_E1S_UV_0    VIA   -    M      A01X+098592Y+017186X0200Y    R180 S2      
017P12V_E1S_UV_0    VIA   -    M      A18X+098592Y+017186X0260Y    R180 S2      
017P12V_E1S_UV_0          -    MD0100PA00X+098592Y+017186                       
317m4696            VIA   -    M      A01X+101112Y+019811X0200Y    R270 S2      
017m4696            VIA   -    M      A18X+101112Y+019811X0260Y    R270 S2      
017m4696                  -    MD0100PA00X+101112Y+019811                       
327m4696            PU292 -4          A01X+100497Y+020032X0100Y0320R090 S1      
327m4696            PC2196-1          A01X+101364Y+019900X0198Y0197     S1      
327P12V_E1S_SS_0    PC2281-1          A01X+101362Y+020742X0198Y0197     S1      
327P12V_E1S_SS_0    PU292 -6          A01X+100497Y+020426X0100Y0320R090 S1      
317P12V_E1S_SS_0    VIA   -    M      A01X+101107Y+020767X0200Y         S2      
017P12V_E1S_SS_0    VIA   -    M      A18X+101107Y+020767X0260Y         S2      
017P12V_E1S_SS_0          -    MD0100PA00X+101107Y+020767                       
327m4697            R3975 -1          A01X+101677Y+023042X0180Y0200R270 S1      
327m4697            R3974 -1   M      A01X+101677Y+023042X0180Y0200     S1      
317m4697            VIA   -    M      A01X+100292Y+017880X0200Y    R090 S2      
017m4697            VIA   -    M      A18X+100292Y+017880X0260Y    R090 S2      
017m4697                  -    MD0100PA00X+100292Y+017880                       
327m4697            PR3970-1   M      A01X+099992Y+017900X0198Y0197R090 S1      
327m4697            PU294 -A1         A01X+099836Y+017148X0090Y    R270 S1      
317m4697            VIA   -    MD0100PA00X+101953Y+023042X0200Y    R090 S0      
327P12V_E1S_REG_0   PU294 -D1         A01X+099245Y+017148X0090Y    R270 S1      
317P12V_E1S_REG_0   VIA   -    M      A01X+098960Y+017540X0200Y         S2      
017P12V_E1S_REG_0   VIA   -    M      A18X+098960Y+017540X0260Y         S2      
017P12V_E1S_REG_0         -    MD0100PA00X+098960Y+017540                       
327P12V_E1S_REG_0   PC2211-2          A01X+098960Y+017948X0198Y0197R270 S1      
327m4698            PU294 -D7         A01X+099245Y+015967X0090Y    R270 S1      
327m4698            R3972 -1          A01X+098550Y+015537X0198Y0197R270 S1      
317m4698            VIA   -    M      A01X+098645Y+015821X0200Y         S2      
017m4698            VIA   -    M      A18X+098645Y+015821X0260Y         S2      
017m4698                  -    MD0100PA00X+098645Y+015821                       
327m4699            VIA   -           A01X+099746Y+023002X0300Y         S1      
327m4699            PR3952-2   M      A01X+099749Y+022523X0198Y0197     S1      
327m4699            PR3953-2   M      A01X+099749Y+022123X0198Y0197     S1      
327m4699            PU292 -11         A01X+099749Y+021174X0100Y0320R180 S1      
327m4699            PR3954-1   M      A01X+099749Y+021723X0198Y0197R180 S1      
327P12V_E1S_OV_0    PU294 -D3         A01X+099245Y+016754X0090Y    R270 S1      
327P12V_E1S_OV_0    PR3962-1          A01X+098144Y+017951X0198Y0197R090 S1      
317P12V_E1S_OV_0    VIA   -    M      A01X+098875Y+016754X0200Y         S2      
017P12V_E1S_OV_0    VIA   -    M      A18X+098875Y+016754X0260Y         S2      
017P12V_E1S_OV_0          -    MD0100PA00X+098875Y+016754                       
327P12V_E1S_OV_0    PR3961-2   M      A01X+098235Y+017548X0198Y0197R180 S1      
327m4700            VIA   -    M      A18X+101736Y+020311X0260Y         S2      
327m4700            PC2341-1          A18X+102191Y+020005X0198Y0197R270 S2      
327m4700            PR4541-2          A18X+101657Y+020755X0198Y0197R090 S2      
317m4701            VIA   -    M      A01X+100812Y+020352X0200Y         S2      
017m4701            VIA   -    M      A18X+100812Y+020352X0260Y         S2      
017m4701                  -    MD0100PA00X+100812Y+020352                       
327m4701            PR4541-1          A18X+101657Y+021070X0198Y0197R090 S2      
327m4701            PR3944-1          A01X+101354Y+020310X0198Y0197     S1      
327m4701            PU292 -5          A01X+100497Y+020229X0100Y0320R090 S1      
327m4702            R3955 -1          A01X+101362Y+022642X0198Y0197     S1      
327m4702            R3956 -1   M      A01X+101362Y+022242X0198Y0197     S1      
327m4702            PR3949-1   M      A01X+101362Y+021842X0198Y0197     S1      
327m4702            PU292 -8          A01X+100497Y+020820X0100Y0320R090 S1      
327m4702            PC2202-1   M      A01X+101362Y+021442X0198Y0197     S1      
317m4702            VIA   -    M      A01X+101091Y+021371X0200Y         S2      
017m4702            VIA   -    M      A18X+101091Y+021371X0260Y         S2      
017m4702                  -    MD0100PA00X+101091Y+021371                       
327m4703            PR4528-2          A01X+101288Y+015387X0198Y0197     S1      
327m4703            VIA   -    M      A01X+101444Y+016052X0300Y         S1      
327m4703            PC2214-2   M      A01X+100974Y+016102X0198Y0197R090 S1      
327m4703            PU294 -A6         A01X+099836Y+016164X0090Y    R270 S1      
327m4703            PC2215-1   M      A01X+100574Y+016102X0198Y0197R270 S1      
327m4704            PR3951-1          A01X+100540Y+021835X0198Y0197R090 S1      
327m4704            PU292 -9          A01X+100497Y+021017X0100Y0320R090 S1      
317m4704            VIA   -           A01X+100564Y+021497X0200Y         S2      
017m4704            VIA   -           A18X+100564Y+021497X0260Y         S2      
017m4704                  -     D0100PA00X+100564Y+021497                       
327m4705            R3976 -2          A01X+099842Y+015230X0198Y0197R180 S1      
317m4705            VIA   -    M      A01X+099518Y+015769X0200Y         S2      
017m4705            VIA   -    M      A18X+099518Y+015769X0260Y         S2      
017m4705                  -    MD0100PA00X+099518Y+015769                       
327m4705            PU294 -C7         A01X+099442Y+015967X0090Y    R270 S1      
317m4706            VIA   -    M      A01X+100892Y+019299X0200Y    R270 S2      
017m4706            VIA   -    M      A18X+100892Y+019299X0260Y    R270 S2      
017m4706                  -    MD0100PA00X+100892Y+019299                       
327m4706            PU292 -1          A01X+100487Y+019442X0098Y0335R090 S1      
327m4706            R3943 -2          A01X+101374Y+019450X0198Y0197R180 S1      
327m4707            R4073 -1          A01X+098803Y+026478X0198Y0197R180 S1      
327m4707            R4064 -2   M      A01X+098803Y+026078X0198Y0197     S1      
327m4707            VIA   -    M      A01X+099283Y+026078X0300Y         S1      
327m4707            Q127  -2          A01X+099769Y+026078X0170Y0200R090 S1      
327P12V_E1S_CB_0    PU294 -B1         A01X+099639Y+017148X0090Y    R270 S1      
317P12V_E1S_CB_0    VIA   -    M      A01X+099642Y+017658X0200Y         S2      
017P12V_E1S_CB_0    VIA   -    M      A18X+099642Y+017658X0260Y         S2      
017P12V_E1S_CB_0          -    MD0100PA00X+099642Y+017658                       
327P12V_E1S_CB_0    PR3968-1          A01X+099642Y+017900X0198Y0197R090 S1      
327m4708            PR3950-2          A01X+097720Y+021100X0198Y0197R090 S1      
327m4708            PU292 -12         A01X+099394Y+021017X0100Y0320R090 S1      
327m4708            PC2205-1          A01X+098823Y+021143X0280Y0320     S1      
327m4708            PR3957-2          A01X+098333Y+021143X0280Y0320R180 S1      
327m4708            VIA   -           A01X+097707Y+021571X0300Y         S1      
317P12V_E1S_0_EN    VIA   -    MD0100PA00X+077268Y+045137X0200Y         S2      
327P12V_E1S_0_EN    R199  -2          A01X+077508Y+045134X0198Y0197R180 S1      
327P12V_E1S_0_EN    U18   -AA11       A01X+076032Y+045139X0160Y    R090 S1      
327m4709            R3942 -1          A18X+124246Y+016354X0180Y0200R270 S2      
317m4709            VIA   -    M      A01X+101936Y+022242X0200Y    R090 S2      
017m4709            VIA   -    M      A18X+101936Y+022242X0260Y    R090 S2      
017m4709                  -    MD0100PA00X+101936Y+022242                       
327m4709            R3956 -2          A01X+101677Y+022242X0198Y0197     S1      
327m4710            R3940 -1          A18X+128203Y+013170X0180Y0200R090 S2      
317m4710            VIA   -    M      A01X+102144Y+022642X0300Y    R090 S1      
017m4710            VIA   -    M      A18X+102144Y+022642X0200Y    R090 S1      
017m4710                  -    MD0100PA00X+102144Y+022642                       
327m4710            R3955 -2          A01X+101677Y+022642X0198Y0197     S1      
327m4711            R3941 -1          A18X+124246Y+015724X0180Y0200R090 S2      
327m4711            R3975 -2          A01X+101677Y+023357X0180Y0200R270 S1      
317m4711            VIA   -    M      A01X+101172Y+023370X0200Y         S2      
017m4711            VIA   -    M      A18X+101172Y+023370X0260Y         S2      
017m4711                  -    MD0100PA00X+101172Y+023370                       
327m4712            R3939 -1          A18X+128203Y+013800X0180Y0200R270 S2      
327m4712            R3974 -2          A01X+101362Y+023042X0180Y0200     S1      
317m4712            VIA   -    M      A01X+100871Y+023042X0300Y         S1      
017m4712            VIA   -    M      A18X+100871Y+023042X0200Y         S1      
017m4712                  -    MD0100PA00X+100871Y+023042                       
327m4713            Q127  -5          A01X+100517Y+026078X0170Y0200R090 S1      
327m4713            R4074 -2          A01X+101483Y+026484X0198Y0197R090 S1      
327m4713            VIA   -    M      A01X+101003Y+026334X0300Y         S1      
327m4713            Q127  -6   M      A01X+100517Y+026334X0170Y0200R090 S1      
327P12V_E1S_0       C1107 -1   M      A01X+129013Y+040812X0198Y0197     S1      
327P12V_E1S_0       PC2280-1          A18X+096858Y+020880X0400Y0500R090 S2      
327P12V_E1S_0       PU292 -13         A01X+099394Y+020820X0100Y0320R090 S1      
327P12V_E1S_0       PU292 -14         A01X+099394Y+020623X0100Y0320R090 S1      
327P12V_E1S_0       PU292 -15         A01X+099394Y+020426X0100Y0320R090 S1      
327P12V_E1S_0       PU292 -16         A01X+099394Y+020229X0100Y0320R090 S1      
327P12V_E1S_0       PU292 -17         A01X+099394Y+020032X0100Y0320R090 S1      
327P12V_E1S_0       PU292 -18         A01X+099394Y+019836X0100Y0320R090 S1      
327P12V_E1S_0       PU292 -19         A01X+099394Y+019639X0100Y0320R090 S1      
327P12V_E1S_0       PR3950-1          A01X+097720Y+020785X0198Y0197R090 S1      
327P12V_E1S_0       PC2219-1          A01X+096939Y+020909X0400Y0500R270 S1      
327P12V_E1S_0       R1283 -1          A01X+096820Y+019817X0198Y0197R180 S1      
327P12V_E1S_0       PU292 -20         A01X+099394Y+019442X0100Y0320R090 S1      
327P12V_E1S_0       PC2217-1          A01X+098155Y+018935X0198Y0197     S1      
327P12V_E1S_0       PC2206-1          A01X+098884Y+019503X0198Y0197R270 S1      
327P12V_E1S_0       VIA   -           A01X+098190Y+019863X0300Y         S1      
327P12V_E1S_0       R1323 -2          A01X+097220Y+018787X1150Y1380     S1      
327P12V_E1S_0       PU294 -A4         A01X+099836Y+016557X0090Y    R270 S1      
327P12V_E1S_0       PU294 -B4         A01X+099639Y+016557X0090Y    R270 S1      
327P12V_E1S_0       PU294 -B6         A01X+099639Y+016164X0090Y    R270 S1      
327P12V_E1S_0       PU294 -C4         A01X+099442Y+016557X0090Y    R270 S1      
327P12V_E1S_0       PU294 -C6         A01X+099442Y+016164X0090Y    R270 S1      
327P12V_E1S_0       PU294 -D4         A01X+099245Y+016557X0090Y    R270 S1      
327P12V_E1S_0       PU294 -D6         A01X+099245Y+016164X0090Y    R270 S1      
327P12V_E1S_0       PD112 -C          A01X+097441Y+016891X0670Y0990R180 S1      
317P12V_E1S_0       VIA   -    MD0100PA00X+098732Y+020560X0200Y         S0      
317P12V_E1S_0       VIA   -    MD0100PA00X+099022Y+020320X0200Y         S0      
317P12V_E1S_0       VIA   -    MD0100PA00X+099022Y+020670X0200Y         S0      
317P12V_E1S_0       VIA   -    MD0100PA00X+098732Y+020210X0200Y         S0      
317P12V_E1S_0       VIA   -    MD0100PA00X+098732Y+019860X0200Y         S0      
317P12V_E1S_0       VIA   -    MD0100PA00X+099022Y+019970X0200Y         S0      
317P12V_E1S_0       VIA   -    MD0100PA00X+098388Y+020216X0200Y         S0      
317P12V_E1S_0       VIA   -    MD0100PA00X+098602Y+019510X0200Y         S0      
317P12V_E1S_0       VIA   -    MD0100PA00X+097985Y+020205X0200Y         S0      
317P12V_E1S_0       VIA   -    MD0100PA00X+097722Y+020540X0200Y         S0      
317P12V_E1S_0       VIA   -    MD0100PA00X+097575Y+020205X0200Y         S0      
317P12V_E1S_0       VIA   -    MD0100PA00X+097194Y+020481X0200Y         S0      
317P12V_E1S_0       VIA   -    MD0100PA00X+096794Y+020481X0200Y         S0      
317P12V_E1S_0       VIA   -    MD0100PA00X+098111Y+016120X0200Y    R090 S0      
317P12V_E1S_0       VIA   -    MD0100PA00X+097569Y+016122X0200Y    R090 S0      
327P12V_E1S_0       PC2214-1          A01X+100974Y+015787X0198Y0197R090 S1      
327P12V_E1S_0       PR4528-1   M      A01X+100974Y+015387X0198Y0197     S1      
317P12V_E1S_0       VIA   -    MD0100PA00X+100531Y+015504X0200Y         S0      
327P12V_E1S_0       PR3952-1          A01X+099434Y+022523X0198Y0197     S1      
317P12V_E1S_0       VIA   -    MD0100PA00X+129013Y+041064X0200Y         S0      
327P12V_E1S_0       U52   -11         A01X+128541Y+040771X0090Y0240R270 S1      
327P12V_AUX         R700  -1          A01X+017142Y+039504X0198Y0197R180 S1      
317P12V_AUX         VIA   -    MD0100PA00X+017432Y+039504X0200Y    R180 S0      
317P12V_AUX         VIA   -    MD0100PA00X+013989Y+050344X0200Y         S0      
317P12V_AUX         VIA   -    MD0100PA00X+013998Y+050742X0200Y         S0      
327P12V_AUX         R1480 -1          A01X+014729Y+050534X0850Y1150R270 S1      
317P12V_AUX         VIA   -    MD0100PA00X+014036Y+043016X0200Y    R270 S0      
327P12V_AUX         R1007 -1          A01X+014036Y+042716X0198Y0197R270 S1      
317P12V_AUX         VIA   -    MD0100PA00X+018389Y+038818X0200Y    R090 S0      
327P12V_AUX         R896  -1          A01X+018389Y+039058X0198Y0197R090 S1      
327P12V_AUX         PL6503-1          A01X+088030Y+106853X0420Y0990     S1      
327P12V_AUX         PC6519-1          A01X+088591Y+105603X0198Y0197     S1      
327P12V_AUX         PR6606-1          A18X+177184Y+167686X0198Y0197     S2      
317P12V_AUX         VIA   -    MD0100PA00X+177434Y+167686X0200Y    R090 S0      
327P12V_AUX         PC6620-1          A01X+010452Y+159780X0198Y0197     S1      
317P12V_AUX         VIA   -    MD0100PA00X+035721Y+139522X0200Y    R180 S0      
317P12V_AUX         VIA   -    MD0100PA00X+035986Y+139522X0200Y    R180 S0      
317P12V_AUX         VIA   -    MD0100PA00X+035231Y+139522X0200Y    R180 S0      
327P12V_AUX         PU297 -1          A01X+092044Y+157547X0100Y0140R270 S1      
327P12V_AUX         PU297 -32         A01X+091847Y+157350X0100Y0140R180 S1      
327P12V_AUX         PU297 -2          A01X+092039Y+157744X0100Y0150R270 S1      
327P12V_AUX         PU297 -25         A01X+090469Y+157350X0100Y0140R180 S1      
327P12V_AUX         PU297 -26         A01X+090666Y+157355X0100Y0150R180 S1      
327P12V_AUX         PU297 -27         A01X+090862Y+157355X0100Y0150R180 S1      
327P12V_AUX         PU297 -28         A01X+091059Y+157355X0100Y0150R180 S1      
327P12V_AUX         PU297 -29         A01X+091256Y+157355X0100Y0150R180 S1      
327P12V_AUX         PU297 -30         A01X+091453Y+157355X0100Y0150R180 S1      
327P12V_AUX         PU297 -31         A01X+091650Y+157355X0100Y0150R180 S1      
327P12V_AUX         PU296 -1          A01X+087844Y+157547X0100Y0140R270 S1      
327P12V_AUX         PU296 -32         A01X+087647Y+157350X0100Y0140R180 S1      
327P12V_AUX         PU296 -2          A01X+087839Y+157744X0100Y0150R270 S1      
327P12V_AUX         PU296 -30         A01X+087253Y+157355X0100Y0150R180 S1      
327P12V_AUX         PU296 -31         A01X+087450Y+157355X0100Y0150R180 S1      
327P12V_AUX         PU296 -25         A01X+086269Y+157350X0100Y0140R180 S1      
327P12V_AUX         PU296 -26         A01X+086466Y+157355X0100Y0150R180 S1      
327P12V_AUX         PU296 -27         A01X+086662Y+157355X0100Y0150R180 S1      
327P12V_AUX         PU296 -28         A01X+086859Y+157355X0100Y0150R180 S1      
327P12V_AUX         PU296 -29         A01X+087056Y+157355X0100Y0150R180 S1      
327P12V_AUX         PU288 -1          A01X+083644Y+157547X0100Y0140R270 S1      
327P12V_AUX         PU288 -32         A01X+083447Y+157350X0100Y0140R180 S1      
327P12V_AUX         PU288 -2          A01X+083639Y+157744X0100Y0150R270 S1      
327P12V_AUX         PU288 -29         A01X+082856Y+157355X0100Y0150R180 S1      
327P12V_AUX         PU288 -30         A01X+083053Y+157355X0100Y0150R180 S1      
327P12V_AUX         PU288 -31         A01X+083250Y+157355X0100Y0150R180 S1      
327P12V_AUX         PU288 -25         A01X+082069Y+157350X0100Y0140R180 S1      
327P12V_AUX         PU288 -26         A01X+082266Y+157355X0100Y0150R180 S1      
327P12V_AUX         PU288 -27         A01X+082462Y+157355X0100Y0150R180 S1      
327P12V_AUX         PU288 -28         A01X+082659Y+157355X0100Y0150R180 S1      
327P12V_AUX         PU287 -1          A01X+079444Y+157547X0100Y0140R270 S1      
327P12V_AUX         PU287 -32         A01X+079247Y+157350X0100Y0140R180 S1      
327P12V_AUX         PU287 -2          A01X+079439Y+157744X0100Y0150R270 S1      
327P12V_AUX         PU287 -28         A01X+078459Y+157355X0100Y0150R180 S1      
327P12V_AUX         PU287 -29         A01X+078656Y+157355X0100Y0150R180 S1      
327P12V_AUX         PU287 -30         A01X+078853Y+157355X0100Y0150R180 S1      
327P12V_AUX         PU287 -31         A01X+079050Y+157355X0100Y0150R180 S1      
327P12V_AUX         PU287 -25         A01X+077869Y+157350X0100Y0140R180 S1      
327P12V_AUX         PU287 -26         A01X+078066Y+157355X0100Y0150R180 S1      
327P12V_AUX         PU287 -27         A01X+078262Y+157355X0100Y0150R180 S1      
327P12V_AUX         PU289 -36         A01X+074219Y+157793X0090Y0150R270 S1      
327P12V_AUX         PU289 -33         A01X+073830Y+157355X0090Y0150     S1      
327P12V_AUX         PU289 -34         A01X+074007Y+157355X0090Y0150     S1      
327P12V_AUX         PU289 -35         A01X+074219Y+157616X0090Y0150R270 S1      
327P12V_AUX         PU289 -27         A01X+072767Y+157355X0090Y0150     S1      
327P12V_AUX         PU289 -28         A01X+072944Y+157355X0090Y0150     S1      
327P12V_AUX         PU289 -29         A01X+073122Y+157355X0090Y0150     S1      
327P12V_AUX         PU289 -30         A01X+073299Y+157355X0090Y0150     S1      
327P12V_AUX         PU289 -31         A01X+073476Y+157355X0090Y0150     S1      
327P12V_AUX         PU289 -32         A01X+073653Y+157355X0090Y0150     S1      
327P12V_AUX         PD111 -K          A01X+084938Y+154102X1860Y1890R270 S1      
327P12V_AUX         PPQ9  -1          A01X+108410Y+150503X0280Y0460     S1      
327P12V_AUX         PPQ9  -2          A01X+108910Y+150503X0280Y0460     S1      
327P12V_AUX         PPQ9  -3          A01X+109410Y+150503X0280Y0460     S1      
327P12V_AUX         PPQ8  -3          A01X+107073Y+150503X0280Y0460     S1      
327P12V_AUX         PPQ8  -1          A01X+106073Y+150503X0280Y0460     S1      
327P12V_AUX         PPQ8  -2          A01X+106573Y+150503X0280Y0460     S1      
327P12V_AUX         PPQ7  -1          A01X+103737Y+150503X0280Y0460     S1      
327P12V_AUX         PPQ7  -2          A01X+104237Y+150503X0280Y0460     S1      
327P12V_AUX         PPQ7  -3          A01X+104737Y+150503X0280Y0460     S1      
327P12V_AUX         PPQ6  -3          A01X+102400Y+150503X0280Y0460     S1      
327P12V_AUX         PPQ6  -1          A01X+101400Y+150503X0280Y0460     S1      
327P12V_AUX         PPQ6  -2          A01X+101900Y+150503X0280Y0460     S1      
327P12V_AUX         PPQ5  -2          A01X+099563Y+150503X0280Y0460     S1      
327P12V_AUX         PPQ5  -3          A01X+100063Y+150503X0280Y0460     S1      
327P12V_AUX         PPQ5  -1          A01X+099063Y+150503X0280Y0460     S1      
327P12V_AUX         PPQ2  -1          A01X+096727Y+150503X0280Y0460     S1      
327P12V_AUX         PPQ2  -2          A01X+097227Y+150503X0280Y0460     S1      
327P12V_AUX         PPQ2  -3          A01X+097727Y+150503X0280Y0460     S1      
327P12V_AUX         PPQ1  -2          A01X+094890Y+150503X0280Y0460     S1      
327P12V_AUX         PPQ1  -3          A01X+095390Y+150503X0280Y0460     S1      
327P12V_AUX         PPQ1  -1          A01X+094390Y+150503X0280Y0460     S1      
327P12V_AUX         PD17  -K          A01X+094927Y+147973X1860Y1890R270 S1      
327P12V_AUX         PR2537-1          A18X+095395Y+150978X0198Y0197R180 S2      
317P12V_AUX         VIA   -    MD0100PA00X+033011Y+060588X0200Y    R180 S0      
317P12V_AUX         VIA   -    MD0100PA00X+033011Y+060288X0200Y    R180 S0      
317P12V_AUX         VIA   -    MD0100PA00X+033350Y+060302X0200Y    R180 S0      
317P12V_AUX         VIA   -    MD0100PA00X+033350Y+060002X0200Y    R180 S0      
317P12V_AUX         VIA   -    MD0100PA00X+034903Y+139268X0200Y    R180 S0      
317P12V_AUX         VIA   -    MD0100PA00X+034883Y+139539X0200Y    R180 S0      
317P12V_AUX         VIA   -    MD0100PA00X+034630Y+139524X0200Y    R180 S0      
317P12V_AUX         VIA   -    MD0100PA00X+034378Y+139517X0200Y    R180 S0      
317P12V_AUX         VIA   -    MD0100PA00X+036836Y+139550X0200Y    R180 S0      
317P12V_AUX         VIA   -    MD0100PA00X+036579Y+139551X0200Y    R180 S0      
317P12V_AUX         VIA   -    MD0100PA00X+036300Y+139539X0200Y    R180 S0      
317P12V_AUX         VIA   -    MD0100PA00X+036598Y+139041X0200Y    R180 S0      
317P12V_AUX         VIA   -    MD0100PA00X+036598Y+139291X0200Y    R180 S0      
317P12V_AUX         VIA   -    MD0100PA00X+036598Y+138764X0200Y    R180 S0      
317P12V_AUX         VIA   -    MD0100PA00X+036854Y+139290X0200Y    R180 S0      
317P12V_AUX         VIA   -    MD0100PA00X+036854Y+139040X0200Y    R180 S0      
317P12V_AUX         VIA   -    MD0100PA00X+036854Y+138764X0200Y    R180 S0      
317P12V_AUX         VIA   -    MD0100PA00X+036319Y+139279X0200Y    R180 S0      
317P12V_AUX         VIA   -    MD0100PA00X+036319Y+139029X0200Y    R180 S0      
317P12V_AUX         VIA   -    MD0100PA00X+036319Y+138753X0200Y    R180 S0      
317P12V_AUX         VIA   -    MD0100PA00X+035983Y+139189X0200Y    R180 S0      
317P12V_AUX         VIA   -    MD0100PA00X+035733Y+139189X0200Y    R180 S0      
317P12V_AUX         VIA   -    MD0100PA00X+035483Y+139189X0200Y    R180 S0      
317P12V_AUX         VIA   -    MD0100PA00X+035233Y+139189X0200Y    R180 S0      
317P12V_AUX         VIA   -    MD0100PA00X+035957Y+138766X0200Y    R180 S0      
317P12V_AUX         VIA   -    MD0100PA00X+035707Y+138766X0200Y    R180 S0      
317P12V_AUX         VIA   -    MD0100PA00X+035457Y+138766X0200Y    R180 S0      
317P12V_AUX         VIA   -    MD0100PA00X+035207Y+138766X0200Y    R180 S0      
317P12V_AUX         VIA   -    MD0100PA00X+020806Y+141860X0200Y    R180 S0      
327P12V_AUX         PR3931-1          A18X+072732Y+156633X0198Y0197     S2      
327P12V_AUX         PC1750-1          A18X+095395Y+150578X0198Y0197R180 S2      
317P12V_AUX         VIA   -    MD0100PA00X+093378Y+150120X0200Y         S0      
317P12V_AUX         VIA   -    MD0100PA00X+093378Y+149870X0200Y         S0      
317P12V_AUX         VIA   -    MD0100PA00X+093378Y+149620X0200Y         S0      
317P12V_AUX         VIA   -    MD0100PA00X+093378Y+149370X0200Y         S0      
317P12V_AUX         VIA   -    MD0100PA00X+093378Y+149120X0200Y         S0      
317P12V_AUX         VIA   -    MD0100PA00X+178662Y+163702X0200Y    R090 S0      
317P12V_AUX         VIA   -    MD0100PA00X+178659Y+163447X0200Y    R090 S0      
317P12V_AUX         VIA   -    MD0100PA00X+009065Y+159851X0200Y         S0      
317P12V_AUX         VIA   -    MD0100PA00X+009894Y+159861X0200Y         S0      
317P12V_AUX         VIA   -    MD0100PA00X+010164Y+159861X0200Y         S0      
317P12V_AUX         VIA   -    MD0100PA00X+009624Y+159851X0200Y         S0      
317P12V_AUX         VIA   -    MD0100PA00X+009354Y+159851X0200Y         S0      
327P12V_AUX         PL77  -1          A01X+130770Y+051872X0280Y0320R270 S1      
327P12V_AUX         PR6809-1          A18X+003806Y+159890X0198Y0197R180 S2      
317P12V_AUX         VIA   -    MD0100PA00X+003517Y+159890X0200Y         S0      
327P12V_AUX         PR3805-1          A01X+029809Y+007113X0198Y0197     S1      
327P12V_AUX         PL42  -2   M      A01X+035625Y+138985X0650Y1030R090 S1      
327P12V_AUX         PC375 -1          A01X+037119Y+138770X0198Y0197     S1      
317P12V_AUX         VIA   -    MD0100PA00X+034646Y+138260X0200Y    R180 S0      
317P12V_AUX         VIA   -    MD0100PA00X+034396Y+138260X0200Y    R180 S0      
317P12V_AUX         VIA   -    MD0100PA00X+034646Y+138760X0200Y    R180 S0      
317P12V_AUX         VIA   -    MD0100PA00X+034646Y+139010X0200Y    R180 S0      
317P12V_AUX         VIA   -    MD0100PA00X+034646Y+138510X0200Y    R180 S0      
317P12V_AUX         VIA   -    MD0100PA00X+034646Y+139260X0200Y    R180 S0      
317P12V_AUX         VIA   -    MD0100PA00X+034396Y+139260X0200Y    R180 S0      
317P12V_AUX         VIA   -    MD0100PA00X+034396Y+138760X0200Y    R180 S0      
317P12V_AUX         VIA   -    MD0100PA00X+034396Y+139010X0200Y    R180 S0      
317P12V_AUX         VIA   -    MD0100PA00X+034396Y+138510X0200Y    R180 S0      
317P12V_AUX         VIA   -    MD0100PA00X+035396Y+138260X0200Y    R180 S0      
317P12V_AUX         VIA   -    MD0100PA00X+035646Y+138260X0200Y    R180 S0      
317P12V_AUX         VIA   -    MD0100PA00X+035896Y+138260X0200Y    R180 S0      
317P12V_AUX         VIA   -    MD0100PA00X+036146Y+138260X0200Y    R180 S0      
317P12V_AUX         VIA   -    MD0100PA00X+034896Y+138260X0200Y    R180 S0      
317P12V_AUX         VIA   -    MD0100PA00X+035146Y+138260X0200Y    R180 S0      
317P12V_AUX         VIA   -    MD0100PA00X+035896Y+138510X0200Y    R180 S0      
317P12V_AUX         VIA   -    MD0100PA00X+035646Y+138510X0200Y    R180 S0      
317P12V_AUX         VIA   -    MD0100PA00X+036146Y+138510X0200Y    R180 S0      
317P12V_AUX         VIA   -    MD0100PA00X+035396Y+138510X0200Y    R180 S0      
317P12V_AUX         VIA   -    MD0100PA00X+034896Y+138510X0200Y    R180 S0      
317P12V_AUX         VIA   -    MD0100PA00X+035146Y+138510X0200Y    R180 S0      
317P12V_AUX         VIA   -    MD0100PA00X+034896Y+138760X0200Y    R180 S0      
317P12V_AUX         VIA   -    MD0100PA00X+034896Y+139010X0200Y    R180 S0      
317P12V_AUX         VIA   -    MD0100PA00X+036646Y+138260X0200Y    R180 S0      
317P12V_AUX         VIA   -    MD0100PA00X+036396Y+138260X0200Y    R180 S0      
317P12V_AUX         VIA   -    MD0100PA00X+034896Y+138010X0200Y    R180 S0      
317P12V_AUX         VIA   -    MD0100PA00X+034396Y+138010X0200Y    R180 S0      
317P12V_AUX         VIA   -    MD0100PA00X+034646Y+138010X0200Y    R180 S0      
317P12V_AUX         VIA   -    MD0100PA00X+036396Y+138010X0200Y    R180 S0      
317P12V_AUX         VIA   -    MD0100PA00X+035146Y+138010X0200Y    R180 S0      
317P12V_AUX         VIA   -    MD0100PA00X+035396Y+138010X0200Y    R180 S0      
317P12V_AUX         VIA   -    MD0100PA00X+036146Y+138010X0200Y    R180 S0      
317P12V_AUX         VIA   -    MD0100PA00X+035896Y+138010X0200Y    R180 S0      
317P12V_AUX         VIA   -    MD0100PA00X+035646Y+138010X0200Y    R180 S0      
317P12V_AUX         VIA   -    MD0100PA00X+036646Y+138010X0200Y    R180 S0      
317P12V_AUX         VIA   -    MD0100PA00X+036896Y+138010X0200Y    R180 S0      
317P12V_AUX         VIA   -    MD0100PA00X+036396Y+138510X0200Y    R180 S0      
317P12V_AUX         VIA   -    MD0100PA00X+036646Y+138510X0200Y    R180 S0      
317P12V_AUX         VIA   -    MD0100PA00X+036896Y+138510X0200Y    R180 S0      
317P12V_AUX         VIA   -    MD0100PA00X+036896Y+138260X0200Y    R180 S0      
317P12V_AUX         VIA   -    MD0100PA00X+172318Y+009331X0200Y         S0      
327P12V_AUX         PR3841-1          A01X+172261Y+010581X0198Y0197R090 S1      
327P12V_AUX         PR3843-1          A01X+172661Y+009453X0280Y0320R270 S1      
317P12V_AUX         VIA   -    MD0100PA00X+172298Y+010171X0200Y         S0      
327P12V_AUX         PR3853-1          A01X+024749Y+010468X0198Y0197R090 S1      
327P12V_AUX         PR3857-1          A01X+025149Y+009273X0280Y0320R270 S1      
317P12V_AUX         VIA   -    MD0100PA00X+024809Y+009215X0200Y         S0      
327P12V_AUX         PR3960-1          A01X+098544Y+018266X0198Y0197R270 S1      
317P12V_AUX         VIA   -    MD0100PA00X+098544Y+018539X0200Y         S0      
317P12V_AUX         VIA   -    MD0100PA00X+024789Y+010055X0200Y         S0      
317P12V_AUX         VIA   -    MD0100PA00X+029576Y+007280X0200Y         S0      
317P12V_AUX         VIA   -    MD0100PA00X+125622Y+143008X0200Y         S0      
327P12V_AUX         PR74  -1          A01X+125300Y+143008X0198Y0197R270 S1      
327P12V_AUX         PR251 -1          A01X+015100Y+144242X0198Y0197R090 S1      
317P12V_AUX         VIA   -    MD0100PA00X+015444Y+144120X0200Y         S0      
327P12V_AUX         C8016 -1   M      A18X+074130Y+168884X0198Y0197     S2      
327P12V_AUX         C8019 -1   M      A01X+053642Y+044550X0198Y0197     S1      
327P12V_AUX         C8022 -1   M      A01X+054908Y+045900X0198Y0197R180 S1      
327P12V_AUX         PC6562-1          A01X+176800Y+163569X0198Y0197R180 S1      
327P12V_AUX         PC6500-1          A01X+098030Y+105548X0198Y0197R180 S1      
327P12V_AUX         R554  -1          A01X+080842Y+053450X0198Y0197     S1      
327P12V_AUX         R568  -1          A01X+083100Y+051158X0198Y0197R270 S1      
327P12V_AUX         R8114 -1          A01X+051200Y+042942X0198Y0197R090 S1      
327P12V_AUX         R8121 -1          A01X+057508Y+045450X0198Y0197R180 S1      
327P12V_AUX         R8024 -2          A01X+074842Y+017550X0198Y0197R180 S1      
327P12V_AUX         PR6807-1          A18X+176093Y+165138X0198Y0197R270 S2      
327P12V_AUX         PR6808-1          A18X+004817Y+163298X0198Y0197R090 S2      
327P12V_AUX         R3933 -1          A01X+070192Y+160850X0198Y0197     S1      
317P12V_AUX         VIA   -    MD0100PA00X+069950Y+160850X0200Y         S0      
327P12V_AUX         PR125 -1          A01X+168100Y+144308X0198Y0197R270 S1      
317P12V_AUX         VIA   -    MD0100PA00X+168374Y+144308X0200Y    R180 S0      
327P12V_AUX         R335  -1          A18X+157400Y+056542X0198Y0197R270 S2      
317P12V_AUX         VIA   -    MD0100PA00X+004249Y+163866X0200Y    R090 S0      
317P12V_AUX         VIA   -    MD0100PA00X+009068Y+159578X0200Y         S0      
317P12V_AUX         VIA   -    MD0100PA00X+009342Y+159596X0200Y         S0      
317P12V_AUX         VIA   -    MD0100PA00X+009068Y+159328X0200Y         S0      
317P12V_AUX         VIA   -    MD0100PA00X+009342Y+159346X0200Y         S0      
317P12V_AUX         VIA   -    MD0100PA00X+010152Y+159606X0200Y         S0      
317P12V_AUX         VIA   -    MD0100PA00X+009612Y+159596X0200Y         S0      
317P12V_AUX         VIA   -    MD0100PA00X+009882Y+159606X0200Y         S0      
317P12V_AUX         VIA   -    MD0100PA00X+010152Y+159356X0200Y         S0      
317P12V_AUX         VIA   -    MD0100PA00X+009612Y+159346X0200Y         S0      
317P12V_AUX         VIA   -    MD0100PA00X+009882Y+159356X0200Y         S0      
317P12V_AUX         VIA   -    MD0100PA00X+009068Y+159078X0200Y         S0      
327P12V_AUX         PL6510-2   M      A01X+009748Y+159222X0420Y0990R090 S1      
317P12V_AUX         VIA   -    MD0100PA00X+176585Y+164646X0200Y    R270 S0      
317P12V_AUX         VIA   -    MD0100PA00X+079187Y+152425X0200Y         S0      
327P12V_AUX         PC1789-1   M      A01X+078928Y+152425X0198Y0197R090 S1      
327P12V_AUX         PJ38  -10         A01X+077953Y+152425X0240Y0650R270 S1      
327P12V_AUX         PL6500-1          A01X+098541Y+106798X0420Y0990R180 S1      
327P12V_AUX         PC6000-1          A01X+080784Y+136419X0198Y0197     S1      
327P12V_AUX         PL71  -1          A01X+080334Y+136419X0280Y0320R090 S1      
317P12V_AUX         VIA   -    MD0100PA00X+098312Y+107453X0200Y    R090 S0      
317P12V_AUX         VIA   -    MD0100PA00X+098612Y+107453X0200Y    R090 S0      
317P12V_AUX         VIA   -    MD0100PA00X+098912Y+107453X0200Y    R090 S0      
317P12V_AUX         VIA   -    MD0100PA00X+098912Y+107098X0200Y    R090 S0      
317P12V_AUX         VIA   -    MD0100PA00X+099212Y+107098X0200Y    R090 S0      
317P12V_AUX         VIA   -    MD0100PA00X+099212Y+107453X0200Y    R090 S0      
317P12V_AUX         VIA   -    MD0100PA00X+098912Y+106498X0200Y    R090 S0      
317P12V_AUX         VIA   -    MD0100PA00X+098912Y+106798X0200Y    R090 S0      
317P12V_AUX         VIA   -    MD0100PA00X+099212Y+106798X0200Y    R090 S0      
317P12V_AUX         VIA   -    MD0100PA00X+099212Y+106498X0200Y    R090 S0      
317P12V_AUX         VIA   -    MD0100PA00X+098312Y+106143X0200Y    R090 S0      
317P12V_AUX         VIA   -    MD0100PA00X+098612Y+106143X0200Y    R090 S0      
317P12V_AUX         VIA   -    MD0100PA00X+098912Y+106143X0200Y    R090 S0      
317P12V_AUX         VIA   -    MD0100PA00X+099212Y+106143X0200Y    R090 S0      
317P12V_AUX         VIA   -    MD0100PA00X+087358Y+106198X0200Y    R270 S0      
317P12V_AUX         VIA   -    MD0100PA00X+087358Y+107153X0200Y    R270 S0      
317P12V_AUX         VIA   -    MD0100PA00X+087358Y+106853X0200Y    R270 S0      
317P12V_AUX         VIA   -    MD0100PA00X+087358Y+106553X0200Y    R270 S0      
317P12V_AUX         VIA   -    MD0100PA00X+087658Y+106553X0200Y    R270 S0      
317P12V_AUX         VIA   -    MD0100PA00X+087658Y+106853X0200Y    R270 S0      
317P12V_AUX         VIA   -    MD0100PA00X+087658Y+107153X0200Y    R270 S0      
317P12V_AUX         VIA   -    MD0100PA00X+087658Y+106198X0200Y    R270 S0      
317P12V_AUX         VIA   -    MD0100PA00X+087958Y+106198X0200Y    R270 S0      
317P12V_AUX         VIA   -    MD0100PA00X+088258Y+106198X0200Y    R270 S0      
317P12V_AUX         VIA   -    MD0100PA00X+087358Y+107508X0200Y    R270 S0      
317P12V_AUX         VIA   -    MD0100PA00X+087658Y+107508X0200Y    R270 S0      
317P12V_AUX         VIA   -    MD0100PA00X+087958Y+107508X0200Y    R270 S0      
317P12V_AUX         VIA   -    MD0100PA00X+088258Y+107508X0200Y    R270 S0      
317P12V_AUX         VIA   -    MD0100PA00X+080787Y+136668X0200Y    R180 S0      
317P12V_AUX         VIA   -    MD0100PA00X+080287Y+136709X0200Y    R180 S0      
317P12V_AUX         VIA   -    MD0100PA00X+080537Y+136709X0200Y    R180 S0      
317P12V_AUX         VIA   -    MD0100PA00X+080787Y+136918X0200Y    R180 S0      
317P12V_AUX         VIA   -    MD0100PA00X+020806Y+141606X0200Y    R180 S0      
317P12V_AUX         VIA   -    MD0100PA00X+018556Y+142856X0200Y    R180 S0      
317P12V_AUX         VIA   -    MD0100PA00X+018306Y+142856X0200Y    R180 S0      
317P12V_AUX         VIA   -    MD0100PA00X+018306Y+142356X0200Y    R180 S0      
317P12V_AUX         VIA   -    MD0100PA00X+018306Y+142606X0200Y    R180 S0      
317P12V_AUX         VIA   -    MD0100PA00X+018306Y+142106X0200Y    R180 S0      
317P12V_AUX         VIA   -    MD0100PA00X+018306Y+141606X0200Y    R180 S0      
317P12V_AUX         VIA   -    MD0100PA00X+018306Y+141856X0200Y    R180 S0      
317P12V_AUX         VIA   -    MD0100PA00X+177872Y+163689X0200Y    R090 S0      
317P12V_AUX         VIA   -    MD0100PA00X+177602Y+163689X0200Y    R090 S0      
327P12V_AUX         PL6504-2   M      A01X+177998Y+163324X0420Y0990R090 S1      
317P12V_AUX         VIA   -    MD0100PA00X+177602Y+163429X0200Y    R090 S0      
317P12V_AUX         VIA   -    MD0100PA00X+177872Y+163429X0200Y    R090 S0      
317P12V_AUX         VIA   -    MD0100PA00X+178662Y+163180X0200Y    R090 S0      
317P12V_AUX         VIA   -    MD0100PA00X+178405Y+163438X0200Y    R090 S0      
317P12V_AUX         VIA   -    MD0100PA00X+178405Y+163688X0200Y    R090 S0      
317P12V_AUX         VIA   -    MD0100PA00X+178142Y+163689X0200Y    R090 S0      
317P12V_AUX         VIA   -    MD0100PA00X+178142Y+163439X0200Y    R090 S0      
317P12V_AUX         VIA   -    MD0100PA00X+177065Y+163444X0200Y    R090 S0      
317P12V_AUX         VIA   -    MD0100PA00X+177065Y+163194X0200Y    R090 S0      
317P12V_AUX         VIA   -    MD0100PA00X+177335Y+163694X0200Y    R090 S0      
317P12V_AUX         VIA   -    MD0100PA00X+177335Y+163444X0200Y    R090 S0      
317P12V_AUX         VIA   -    MD0100PA00X+177335Y+163194X0200Y    R090 S0      
327P12V_AUX         PL8064-1          A01X+161496Y+052596X0280Y0320R270 S1      
327P12V_AUX         PC1648-1          A01X+161573Y+053074X0198Y0197     S1      
317P12V_AUX         VIA   -    MD0100PA00X+161317Y+053182X0200Y    R180 S0      
317P12V_AUX         VIA   -    MD0100PA00X+161178Y+052470X0200Y    R180 S0      
317P12V_AUX         VIA   -    MD0100PA00X+160917Y+052470X0200Y    R180 S0      
317P12V_AUX         VIA   -    MD0100PA00X+161178Y+052730X0200Y    R180 S0      
317P12V_AUX         VIA   -    MD0100PA00X+160917Y+052730X0200Y    R180 S0      
327P12V_AUX         PL26  -1          A01X+032989Y+059879X0280Y0320R090 S1      
327P12V_AUX         PC6002-1          A01X+033399Y+059688X0198Y0197R270 S1      
317P12V_AUX         VIA   -    MD0100PA00X+074033Y+169838X0200Y         S0      
317P12V_AUX         VIA   -    MD0100PA00X+091985Y+156513X0200Y         S0      
317P12V_AUX         VIA   -    MD0100PA00X+091985Y+156213X0200Y         S0      
317P12V_AUX         VIA   -    MD0100PA00X+091985Y+155913X0200Y         S0      
317P12V_AUX         VIA   -    MD0100PA00X+092285Y+156513X0200Y         S0      
317P12V_AUX         VIA   -    MD0100PA00X+092285Y+156213X0200Y         S0      
317P12V_AUX         VIA   -    MD0100PA00X+092285Y+155913X0200Y         S0      
317P12V_AUX         VIA   -    MD0100PA00X+091985Y+157113X0200Y         S0      
317P12V_AUX         VIA   -    MD0100PA00X+091985Y+156813X0200Y         S0      
317P12V_AUX         VIA   -    MD0100PA00X+091985Y+155613X0200Y         S0      
317P12V_AUX         VIA   -    MD0100PA00X+092285Y+155613X0200Y         S0      
317P12V_AUX         VIA   -    MD0100PA00X+091685Y+156513X0200Y         S0      
317P12V_AUX         VIA   -    MD0100PA00X+091685Y+156213X0200Y         S0      
317P12V_AUX         VIA   -    MD0100PA00X+091685Y+155913X0200Y         S0      
317P12V_AUX         VIA   -    MD0100PA00X+091385Y+156513X0200Y         S0      
317P12V_AUX         VIA   -    MD0100PA00X+091385Y+156213X0200Y         S0      
317P12V_AUX         VIA   -    MD0100PA00X+091385Y+155913X0200Y         S0      
317P12V_AUX         VIA   -    MD0100PA00X+091685Y+157113X0200Y         S0      
317P12V_AUX         VIA   -    MD0100PA00X+091685Y+156813X0200Y         S0      
317P12V_AUX         VIA   -    MD0100PA00X+091385Y+157113X0200Y         S0      
317P12V_AUX         VIA   -    MD0100PA00X+091385Y+156813X0200Y         S0      
317P12V_AUX         VIA   -    MD0100PA00X+090485Y+156513X0200Y         S0      
317P12V_AUX         VIA   -    MD0100PA00X+090485Y+156213X0200Y         S0      
317P12V_AUX         VIA   -    MD0100PA00X+090485Y+155913X0200Y         S0      
317P12V_AUX         VIA   -    MD0100PA00X+091085Y+156513X0200Y         S0      
317P12V_AUX         VIA   -    MD0100PA00X+090785Y+156513X0200Y         S0      
317P12V_AUX         VIA   -    MD0100PA00X+091085Y+156213X0200Y         S0      
317P12V_AUX         VIA   -    MD0100PA00X+091085Y+155913X0200Y         S0      
317P12V_AUX         VIA   -    MD0100PA00X+090785Y+156213X0200Y         S0      
317P12V_AUX         VIA   -    MD0100PA00X+090785Y+155913X0200Y         S0      
317P12V_AUX         VIA   -    MD0100PA00X+090485Y+157113X0200Y         S0      
317P12V_AUX         VIA   -    MD0100PA00X+090485Y+156813X0200Y         S0      
317P12V_AUX         VIA   -    MD0100PA00X+091085Y+157113X0200Y         S0      
317P12V_AUX         VIA   -    MD0100PA00X+091085Y+156813X0200Y         S0      
317P12V_AUX         VIA   -    MD0100PA00X+090785Y+157113X0200Y         S0      
317P12V_AUX         VIA   -    MD0100PA00X+090785Y+156813X0200Y         S0      
317P12V_AUX         VIA   -    MD0100PA00X+091385Y+155613X0200Y         S0      
317P12V_AUX         VIA   -    MD0100PA00X+091685Y+155613X0200Y         S0      
317P12V_AUX         VIA   -    MD0100PA00X+090785Y+155613X0200Y         S0      
317P12V_AUX         VIA   -    MD0100PA00X+091085Y+155613X0200Y         S0      
317P12V_AUX         VIA   -    M      A01X+090485Y+155613X0300Y         S1      
017P12V_AUX         VIA   -    M      A18X+090485Y+155613X0200Y         S1      
017P12V_AUX               -    MD0100PA00X+090485Y+155613                       
317P12V_AUX         VIA   -    MD0100PA00X+087785Y+156813X0200Y         S0      
317P12V_AUX         VIA   -    MD0100PA00X+087485Y+156813X0200Y         S0      
317P12V_AUX         VIA   -    MD0100PA00X+087785Y+157113X0200Y         S0      
317P12V_AUX         VIA   -    MD0100PA00X+087485Y+157113X0200Y         S0      
317P12V_AUX         VIA   -    MD0100PA00X+088085Y+155913X0200Y         S0      
317P12V_AUX         VIA   -    MD0100PA00X+087785Y+155913X0200Y         S0      
317P12V_AUX         VIA   -    MD0100PA00X+087485Y+155913X0200Y         S0      
317P12V_AUX         VIA   -    MD0100PA00X+088085Y+156213X0200Y         S0      
317P12V_AUX         VIA   -    MD0100PA00X+087785Y+156213X0200Y         S0      
317P12V_AUX         VIA   -    MD0100PA00X+087485Y+156213X0200Y         S0      
317P12V_AUX         VIA   -    MD0100PA00X+088085Y+156513X0200Y         S0      
317P12V_AUX         VIA   -    MD0100PA00X+087785Y+156513X0200Y         S0      
317P12V_AUX         VIA   -    MD0100PA00X+087485Y+156513X0200Y         S0      
317P12V_AUX         VIA   -    MD0100PA00X+088085Y+155613X0200Y         S0      
317P12V_AUX         VIA   -    MD0100PA00X+087485Y+155613X0200Y         S0      
317P12V_AUX         VIA   -    MD0100PA00X+087785Y+155613X0200Y         S0      
317P12V_AUX         VIA   -    MD0100PA00X+087185Y+156813X0200Y         S0      
317P12V_AUX         VIA   -    MD0100PA00X+086885Y+156813X0200Y         S0      
317P12V_AUX         VIA   -    MD0100PA00X+087185Y+157113X0200Y         S0      
317P12V_AUX         VIA   -    MD0100PA00X+086885Y+157113X0200Y         S0      
317P12V_AUX         VIA   -    MD0100PA00X+086285Y+156813X0200Y         S0      
317P12V_AUX         VIA   -    MD0100PA00X+086285Y+157113X0200Y         S0      
317P12V_AUX         VIA   -    MD0100PA00X+086585Y+156813X0200Y         S0      
317P12V_AUX         VIA   -    MD0100PA00X+086585Y+157113X0200Y         S0      
317P12V_AUX         VIA   -    MD0100PA00X+087185Y+155913X0200Y         S0      
317P12V_AUX         VIA   -    MD0100PA00X+086885Y+155913X0200Y         S0      
317P12V_AUX         VIA   -    MD0100PA00X+087185Y+156213X0200Y         S0      
317P12V_AUX         VIA   -    MD0100PA00X+086885Y+156213X0200Y         S0      
317P12V_AUX         VIA   -    MD0100PA00X+087185Y+156513X0200Y         S0      
317P12V_AUX         VIA   -    MD0100PA00X+086885Y+156513X0200Y         S0      
317P12V_AUX         VIA   -    MD0100PA00X+086285Y+155913X0200Y         S0      
317P12V_AUX         VIA   -    MD0100PA00X+086285Y+156213X0200Y         S0      
317P12V_AUX         VIA   -    MD0100PA00X+086285Y+156513X0200Y         S0      
317P12V_AUX         VIA   -    MD0100PA00X+086585Y+155913X0200Y         S0      
317P12V_AUX         VIA   -    MD0100PA00X+086585Y+156213X0200Y         S0      
317P12V_AUX         VIA   -    MD0100PA00X+086585Y+156513X0200Y         S0      
317P12V_AUX         VIA   -    MD0100PA00X+086885Y+155613X0200Y         S0      
317P12V_AUX         VIA   -    M      A01X+086285Y+155613X0300Y         S1      
017P12V_AUX         VIA   -    M      A18X+086285Y+155613X0200Y         S1      
017P12V_AUX               -    MD0100PA00X+086285Y+155613                       
317P12V_AUX         VIA   -    MD0100PA00X+087185Y+155613X0200Y         S0      
317P12V_AUX         VIA   -    MD0100PA00X+086585Y+155613X0200Y         S0      
317P12V_AUX         VIA   -    MD0100PA00X+082985Y+156813X0200Y         S0      
317P12V_AUX         VIA   -    MD0100PA00X+082985Y+157113X0200Y         S0      
317P12V_AUX         VIA   -    MD0100PA00X+083585Y+156813X0200Y         S0      
317P12V_AUX         VIA   -    MD0100PA00X+083285Y+156813X0200Y         S0      
317P12V_AUX         VIA   -    MD0100PA00X+083585Y+157113X0200Y         S0      
317P12V_AUX         VIA   -    MD0100PA00X+083285Y+157113X0200Y         S0      
317P12V_AUX         VIA   -    MD0100PA00X+083885Y+155913X0200Y         S0      
317P12V_AUX         VIA   -    MD0100PA00X+083885Y+156213X0200Y         S0      
317P12V_AUX         VIA   -    MD0100PA00X+083885Y+156513X0200Y         S0      
317P12V_AUX         VIA   -    MD0100PA00X+082985Y+155913X0200Y         S0      
317P12V_AUX         VIA   -    MD0100PA00X+082985Y+156213X0200Y         S0      
317P12V_AUX         VIA   -    MD0100PA00X+082985Y+156513X0200Y         S0      
317P12V_AUX         VIA   -    MD0100PA00X+083585Y+155913X0200Y         S0      
317P12V_AUX         VIA   -    MD0100PA00X+083285Y+155913X0200Y         S0      
317P12V_AUX         VIA   -    MD0100PA00X+083585Y+156213X0200Y         S0      
317P12V_AUX         VIA   -    MD0100PA00X+083285Y+156213X0200Y         S0      
317P12V_AUX         VIA   -    MD0100PA00X+083585Y+156513X0200Y         S0      
317P12V_AUX         VIA   -    MD0100PA00X+083285Y+156513X0200Y         S0      
317P12V_AUX         VIA   -    MD0100PA00X+083885Y+155613X0200Y         S0      
317P12V_AUX         VIA   -    MD0100PA00X+083285Y+155613X0200Y         S0      
317P12V_AUX         VIA   -    MD0100PA00X+082985Y+155613X0200Y         S0      
317P12V_AUX         VIA   -    MD0100PA00X+083585Y+155613X0200Y         S0      
317P12V_AUX         VIA   -    MD0100PA00X+082385Y+156813X0200Y         S0      
317P12V_AUX         VIA   -    MD0100PA00X+082385Y+157113X0200Y         S0      
317P12V_AUX         VIA   -    MD0100PA00X+082685Y+156813X0200Y         S0      
317P12V_AUX         VIA   -    MD0100PA00X+082685Y+157113X0200Y         S0      
317P12V_AUX         VIA   -    MD0100PA00X+082085Y+156813X0200Y         S0      
317P12V_AUX         VIA   -    MD0100PA00X+082085Y+157113X0200Y         S0      
317P12V_AUX         VIA   -    MD0100PA00X+082385Y+155913X0200Y         S0      
317P12V_AUX         VIA   -    MD0100PA00X+082385Y+156213X0200Y         S0      
317P12V_AUX         VIA   -    MD0100PA00X+082685Y+155913X0200Y         S0      
317P12V_AUX         VIA   -    MD0100PA00X+082685Y+156213X0200Y         S0      
317P12V_AUX         VIA   -    MD0100PA00X+082385Y+156513X0200Y         S0      
317P12V_AUX         VIA   -    MD0100PA00X+082685Y+156513X0200Y         S0      
317P12V_AUX         VIA   -    MD0100PA00X+082085Y+155913X0200Y         S0      
317P12V_AUX         VIA   -    MD0100PA00X+082085Y+156213X0200Y         S0      
317P12V_AUX         VIA   -    MD0100PA00X+082085Y+156513X0200Y         S0      
317P12V_AUX         VIA   -    MD0100PA00X+082685Y+155613X0200Y         S0      
317P12V_AUX         VIA   -    M      A01X+082085Y+155613X0300Y         S1      
017P12V_AUX         VIA   -    M      A18X+082085Y+155613X0200Y         S1      
017P12V_AUX               -    MD0100PA00X+082085Y+155613                       
317P12V_AUX         VIA   -    MD0100PA00X+082385Y+155613X0200Y         S0      
317P12V_AUX         VIA   -    MD0100PA00X+079085Y+156513X0200Y         S0      
317P12V_AUX         VIA   -    MD0100PA00X+079385Y+156513X0200Y         S0      
317P12V_AUX         VIA   -    MD0100PA00X+079085Y+156213X0200Y         S0      
317P12V_AUX         VIA   -    MD0100PA00X+079385Y+156213X0200Y         S0      
317P12V_AUX         VIA   -    MD0100PA00X+079085Y+155913X0200Y         S0      
317P12V_AUX         VIA   -    MD0100PA00X+079385Y+155913X0200Y         S0      
317P12V_AUX         VIA   -    MD0100PA00X+078785Y+156513X0200Y         S0      
317P12V_AUX         VIA   -    MD0100PA00X+078785Y+156213X0200Y         S0      
317P12V_AUX         VIA   -    MD0100PA00X+078785Y+155913X0200Y         S0      
317P12V_AUX         VIA   -    MD0100PA00X+079685Y+156513X0200Y         S0      
317P12V_AUX         VIA   -    MD0100PA00X+079685Y+156213X0200Y         S0      
317P12V_AUX         VIA   -    MD0100PA00X+079685Y+155913X0200Y         S0      
317P12V_AUX         VIA   -    MD0100PA00X+079085Y+157113X0200Y         S0      
317P12V_AUX         VIA   -    MD0100PA00X+079385Y+157113X0200Y         S0      
317P12V_AUX         VIA   -    MD0100PA00X+079085Y+156813X0200Y         S0      
317P12V_AUX         VIA   -    MD0100PA00X+079385Y+156813X0200Y         S0      
317P12V_AUX         VIA   -    MD0100PA00X+078785Y+157113X0200Y         S0      
317P12V_AUX         VIA   -    MD0100PA00X+078785Y+156813X0200Y         S0      
317P12V_AUX         VIA   -    MD0100PA00X+078485Y+156513X0200Y         S0      
317P12V_AUX         VIA   -    MD0100PA00X+078485Y+156213X0200Y         S0      
317P12V_AUX         VIA   -    MD0100PA00X+078485Y+155913X0200Y         S0      
317P12V_AUX         VIA   -    MD0100PA00X+078485Y+157113X0200Y         S0      
317P12V_AUX         VIA   -    MD0100PA00X+078485Y+156813X0200Y         S0      
317P12V_AUX         VIA   -    MD0100PA00X+079385Y+155613X0200Y         S0      
317P12V_AUX         VIA   -    MD0100PA00X+078785Y+155613X0200Y         S0      
317P12V_AUX         VIA   -    MD0100PA00X+079085Y+155613X0200Y         S0      
317P12V_AUX         VIA   -    MD0100PA00X+079685Y+155613X0200Y         S0      
317P12V_AUX         VIA   -    MD0100PA00X+078485Y+155613X0200Y         S0      
317P12V_AUX         VIA   -    MD0100PA00X+077885Y+156513X0200Y         S0      
317P12V_AUX         VIA   -    MD0100PA00X+077885Y+156213X0200Y         S0      
317P12V_AUX         VIA   -    MD0100PA00X+077885Y+155913X0200Y         S0      
317P12V_AUX         VIA   -    MD0100PA00X+078185Y+156513X0200Y         S0      
317P12V_AUX         VIA   -    MD0100PA00X+078185Y+156213X0200Y         S0      
317P12V_AUX         VIA   -    MD0100PA00X+078185Y+155913X0200Y         S0      
317P12V_AUX         VIA   -    MD0100PA00X+077885Y+157113X0200Y         S0      
317P12V_AUX         VIA   -    MD0100PA00X+077885Y+156813X0200Y         S0      
317P12V_AUX         VIA   -    MD0100PA00X+078185Y+157113X0200Y         S0      
317P12V_AUX         VIA   -    MD0100PA00X+078185Y+156813X0200Y         S0      
317P12V_AUX         VIA   -    MD0100PA00X+078185Y+155613X0200Y         S0      
317P12V_AUX         VIA   -    M      A01X+077885Y+155613X0300Y         S1      
017P12V_AUX         VIA   -    M      A18X+077885Y+155613X0200Y         S1      
017P12V_AUX               -    MD0100PA00X+077885Y+155613                       
317P12V_AUX         VIA   -    MD0100PA00X+074878Y+156450X0200Y         S0      
317P12V_AUX         VIA   -    MD0100PA00X+074878Y+156150X0200Y         S0      
317P12V_AUX         VIA   -    MD0100PA00X+074878Y+155850X0200Y         S0      
317P12V_AUX         VIA   -    MD0100PA00X+074278Y+157050X0200Y         S0      
317P12V_AUX         VIA   -    MD0100PA00X+074278Y+156750X0200Y         S0      
317P12V_AUX         VIA   -    MD0100PA00X+073978Y+156750X0200Y         S0      
317P12V_AUX         VIA   -    MD0100PA00X+073978Y+157050X0200Y         S0      
317P12V_AUX         VIA   -    MD0100PA00X+074278Y+156450X0200Y         S0      
317P12V_AUX         VIA   -    MD0100PA00X+074578Y+156450X0200Y         S0      
317P12V_AUX         VIA   -    MD0100PA00X+074278Y+156150X0200Y         S0      
317P12V_AUX         VIA   -    MD0100PA00X+074578Y+156150X0200Y         S0      
317P12V_AUX         VIA   -    MD0100PA00X+074278Y+155850X0200Y         S0      
317P12V_AUX         VIA   -    MD0100PA00X+074578Y+155850X0200Y         S0      
317P12V_AUX         VIA   -    MD0100PA00X+073978Y+156450X0200Y         S0      
317P12V_AUX         VIA   -    MD0100PA00X+073978Y+156150X0200Y         S0      
317P12V_AUX         VIA   -    MD0100PA00X+073978Y+155850X0200Y         S0      
317P12V_AUX         VIA   -    MD0100PA00X+074578Y+155550X0200Y         S0      
317P12V_AUX         VIA   -    MD0100PA00X+073978Y+155550X0200Y         S0      
317P12V_AUX         VIA   -    MD0100PA00X+074278Y+155550X0200Y         S0      
317P12V_AUX         VIA   -    MD0100PA00X+074878Y+155550X0200Y         S0      
317P12V_AUX         VIA   -    MD0100PA00X+073078Y+156450X0200Y         S0      
317P12V_AUX         VIA   -    MD0100PA00X+073078Y+156150X0200Y         S0      
317P12V_AUX         VIA   -    MD0100PA00X+073078Y+155850X0200Y         S0      
317P12V_AUX         VIA   -    MD0100PA00X+073678Y+156450X0200Y         S0      
317P12V_AUX         VIA   -    MD0100PA00X+073378Y+156450X0200Y         S0      
317P12V_AUX         VIA   -    MD0100PA00X+073678Y+156150X0200Y         S0      
317P12V_AUX         VIA   -    MD0100PA00X+073678Y+155850X0200Y         S0      
317P12V_AUX         VIA   -    MD0100PA00X+073378Y+156150X0200Y         S0      
317P12V_AUX         VIA   -    MD0100PA00X+073378Y+155850X0200Y         S0      
317P12V_AUX         VIA   -    MD0100PA00X+073078Y+156750X0200Y         S0      
317P12V_AUX         VIA   -    MD0100PA00X+073678Y+156750X0200Y         S0      
317P12V_AUX         VIA   -    MD0100PA00X+073378Y+156750X0200Y         S0      
317P12V_AUX         VIA   -    MD0100PA00X+073378Y+157050X0200Y         S0      
317P12V_AUX         VIA   -    MD0100PA00X+073678Y+157050X0200Y         S0      
317P12V_AUX         VIA   -    MD0100PA00X+073078Y+157050X0200Y         S0      
317P12V_AUX         VIA   -    MD0100PA00X+072757Y+155535X0200Y    R090 S0      
317P12V_AUX         VIA   -    MD0100PA00X+073378Y+155550X0200Y         S0      
317P12V_AUX         VIA   -    M      A01X+073078Y+155550X0300Y         S1      
017P12V_AUX         VIA   -    M      A18X+073078Y+155550X0200Y         S1      
017P12V_AUX               -    MD0100PA00X+073078Y+155550                       
317P12V_AUX         VIA   -    MD0100PA00X+073678Y+155550X0200Y         S0      
317P12V_AUX         VIA   -    MD0100PA00X+072757Y+155835X0200Y    R090 S0      
327P12V_AUX         PC438 -1          A01X+021050Y+141919X0198Y0197     S1      
327P12V_AUX         PR388 -1          A18X+066274Y+138084X0198Y0197     S2      
317P12V_AUX         VIA   -    MD0100PA00X+066517Y+138084X0200Y         S0      
317P12V_AUX         VIA   -    MD0100PA00X+018556Y+142606X0200Y    R180 S0      
317P12V_AUX         VIA   -    MD0100PA00X+018556Y+142356X0200Y    R180 S0      
317P12V_AUX         VIA   -    MD0100PA00X+018806Y+142606X0200Y    R180 S0      
317P12V_AUX         VIA   -    MD0100PA00X+018556Y+141606X0200Y    R180 S0      
317P12V_AUX         VIA   -    MD0100PA00X+018556Y+141856X0200Y    R180 S0      
317P12V_AUX         VIA   -    MD0100PA00X+018556Y+142106X0200Y    R180 S0      
317P12V_AUX         VIA   -    MD0100PA00X+019798Y+142007X0200Y    R180 S0      
317P12V_AUX         VIA   -    MD0100PA00X+019548Y+141757X0200Y    R180 S0      
317P12V_AUX         VIA   -    MD0100PA00X+019798Y+141757X0200Y    R180 S0      
317P12V_AUX         VIA   -    MD0100PA00X+019048Y+142257X0200Y    R180 S0      
317P12V_AUX         VIA   -    MD0100PA00X+019048Y+142007X0200Y    R180 S0      
317P12V_AUX         VIA   -    MD0100PA00X+019048Y+141757X0200Y    R180 S0      
317P12V_AUX         VIA   -    MD0100PA00X+018806Y+142356X0200Y    R180 S0      
317P12V_AUX         VIA   -    MD0100PA00X+018806Y+141856X0200Y    R180 S0      
317P12V_AUX         VIA   -    MD0100PA00X+018806Y+142106X0200Y    R180 S0      
317P12V_AUX         VIA   -    MD0100PA00X+018806Y+141606X0200Y    R180 S0      
317P12V_AUX         VIA   -    MD0100PA00X+019298Y+142257X0200Y    R180 S0      
317P12V_AUX         VIA   -    MD0100PA00X+019798Y+142257X0200Y    R180 S0      
317P12V_AUX         VIA   -    MD0100PA00X+019548Y+142257X0200Y    R180 S0      
317P12V_AUX         VIA   -    MD0100PA00X+019298Y+142007X0200Y    R180 S0      
317P12V_AUX         VIA   -    MD0100PA00X+019298Y+141757X0200Y    R180 S0      
317P12V_AUX         VIA   -    MD0100PA00X+019548Y+142007X0200Y    R180 S0      
317P12V_AUX         VIA   -    MD0100PA00X+020041Y+141875X0200Y    R180 S0      
317P12V_AUX         VIA   -    MD0100PA00X+020041Y+141625X0200Y    R180 S0      
327P12V_AUX         PL49  -2          A01X+019534Y+142736X0650Y1030R090 S1      
317P12V_AUX         VIA   -    MD0100PA00X+020294Y+141841X0200Y    R180 S0      
317P12V_AUX         VIA   -    MD0100PA00X+020294Y+141591X0200Y    R180 S0      
317P12V_AUX         VIA   -    MD0100PA00X+020556Y+141606X0200Y    R180 S0      
317P12V_AUX         VIA   -    MD0100PA00X+020556Y+141856X0200Y    R180 S0      
317P12V_AUX         VIA   -    MD0100PA00X+020056Y+142155X0200Y    R180 S0      
317P12V_AUX         VIA   -    MD0100PA00X+057508Y+045126X0200Y         S0      
317P12V_AUX         VIA   -    MD0100PA00X+083180Y+051531X0200Y         S0      
317P12V_AUX         VIA   -    MD0100PA00X+080594Y+053450X0200Y         S0      
327P12V_AUX         PL56  -2          A01X+071435Y+142362X0420Y0990R180 S1      
327P12V_AUX         PL24  -2          A01X+173552Y+141971X0420Y0990     S1      
327P12V_AUX         PC148 -1          A01X+114731Y+143658X0198Y0197     S1      
317P12V_AUX         VIA   -    MD0100PA00X+112984Y+143106X0200Y    R180 S0      
317P12V_AUX         VIA   -    MD0100PA00X+112982Y+142682X0200Y    R180 S0      
317P12V_AUX         VIA   -    MD0100PA00X+112692Y+143117X0200Y    R180 S0      
317P12V_AUX         VIA   -    MD0100PA00X+112692Y+143367X0200Y    R180 S0      
317P12V_AUX         VIA   -    MD0100PA00X+112982Y+143367X0200Y    R180 S0      
317P12V_AUX         VIA   -    MD0100PA00X+112692Y+142617X0200Y    R180 S0      
317P12V_AUX         VIA   -    MD0100PA00X+112692Y+142867X0200Y    R180 S0      
317P12V_AUX         VIA   -    MD0100PA00X+112442Y+143367X0200Y    R180 S0      
317P12V_AUX         VIA   -    MD0100PA00X+112442Y+143117X0200Y    R180 S0      
317P12V_AUX         VIA   -    MD0100PA00X+112442Y+142867X0200Y    R180 S0      
317P12V_AUX         VIA   -    MD0100PA00X+112442Y+142617X0200Y    R180 S0      
317P12V_AUX         VIA   -    MD0100PA00X+113234Y+143106X0200Y    R180 S0      
317P12V_AUX         VIA   -    MD0100PA00X+113232Y+142682X0200Y    R180 S0      
317P12V_AUX         VIA   -    MD0100PA00X+113484Y+143106X0200Y    R180 S0      
317P12V_AUX         VIA   -    MD0100PA00X+113734Y+143106X0200Y    R180 S0      
317P12V_AUX         VIA   -    MD0100PA00X+113482Y+142682X0200Y    R180 S0      
317P12V_AUX         VIA   -    MD0100PA00X+113732Y+142682X0200Y    R180 S0      
327P12V_AUX         PL19  -2   M      A01X+113356Y+142892X0650Y1030R090 S1      
317P12V_AUX         VIA   -    MD0100PA00X+113232Y+143367X0200Y    R180 S0      
317P12V_AUX         VIA   -    MD0100PA00X+114272Y+143367X0200Y    R180 S0      
317P12V_AUX         VIA   -    MD0100PA00X+114272Y+143117X0200Y    R180 S0      
317P12V_AUX         VIA   -    MD0100PA00X+114272Y+142867X0200Y    R180 S0      
317P12V_AUX         VIA   -    MD0100PA00X+114272Y+142617X0200Y    R180 S0      
317P12V_AUX         VIA   -    MD0100PA00X+114022Y+143117X0200Y    R180 S0      
317P12V_AUX         VIA   -    MD0100PA00X+114022Y+143367X0200Y    R180 S0      
317P12V_AUX         VIA   -    MD0100PA00X+113732Y+143367X0200Y    R180 S0      
317P12V_AUX         VIA   -    MD0100PA00X+113482Y+143367X0200Y    R180 S0      
317P12V_AUX         VIA   -    MD0100PA00X+114022Y+142617X0200Y    R180 S0      
317P12V_AUX         VIA   -    MD0100PA00X+114022Y+142867X0200Y    R180 S0      
317P12V_AUX         VIA   -    MD0100PA00X+114576Y+143374X0200Y    R180 S0      
317P12V_AUX         VIA   -    MD0100PA00X+114576Y+143124X0200Y    R180 S0      
317P12V_AUX         VIA   -    MD0100PA00X+114576Y+142874X0200Y    R180 S0      
317P12V_AUX         VIA   -    MD0100PA00X+114576Y+142624X0200Y    R180 S0      
317P12V_AUX         VIA   -    MD0100PA00X+114572Y+142356X0200Y    R180 S0      
317P12V_AUX         VIA   -    MD0100PA00X+114018Y+142349X0200Y    R180 S0      
317P12V_AUX         VIA   -    MD0100PA00X+114268Y+142349X0200Y    R180 S0      
317P12V_AUX         VIA   -    MD0100PA00X+112978Y+142414X0200Y    R180 S0      
317P12V_AUX         VIA   -    MD0100PA00X+112688Y+142349X0200Y    R180 S0      
317P12V_AUX         VIA   -    MD0100PA00X+112438Y+142349X0200Y    R180 S0      
317P12V_AUX         VIA   -    MD0100PA00X+113228Y+142414X0200Y    R180 S0      
317P12V_AUX         VIA   -    MD0100PA00X+113478Y+142414X0200Y    R180 S0      
317P12V_AUX         VIA   -    MD0100PA00X+113728Y+142414X0200Y    R180 S0      
327P12V_AUX         PC6003-1          A01X+173992Y+143500X0198Y0197     S1      
317P12V_AUX         VIA   -    MD0100PA00X+173527Y+141306X0200Y    R180 S0      
317P12V_AUX         VIA   -    MD0100PA00X+173527Y+141056X0200Y    R180 S0      
317P12V_AUX         VIA   -    MD0100PA00X+173277Y+141306X0200Y    R180 S0      
317P12V_AUX         VIA   -    MD0100PA00X+173277Y+141056X0200Y    R180 S0      
317P12V_AUX         VIA   -    MD0100PA00X+173527Y+142886X0200Y    R180 S0      
317P12V_AUX         VIA   -    MD0100PA00X+173527Y+142636X0200Y    R180 S0      
317P12V_AUX         VIA   -    MD0100PA00X+173277Y+142886X0200Y    R180 S0      
317P12V_AUX         VIA   -    MD0100PA00X+173277Y+142636X0200Y    R180 S0      
317P12V_AUX         VIA   -    MD0100PA00X+174027Y+141846X0200Y    R180 S0      
317P12V_AUX         VIA   -    MD0100PA00X+174027Y+141596X0200Y    R180 S0      
317P12V_AUX         VIA   -    MD0100PA00X+174277Y+142096X0200Y    R180 S0      
317P12V_AUX         VIA   -    MD0100PA00X+174027Y+142096X0200Y    R180 S0      
317P12V_AUX         VIA   -    MD0100PA00X+174027Y+142346X0200Y    R180 S0      
317P12V_AUX         VIA   -    MD0100PA00X+174027Y+142636X0200Y    R180 S0      
317P12V_AUX         VIA   -    MD0100PA00X+174277Y+142346X0200Y    R180 S0      
317P12V_AUX         VIA   -    MD0100PA00X+173777Y+142886X0200Y    R180 S0      
317P12V_AUX         VIA   -    MD0100PA00X+173777Y+142636X0200Y    R180 S0      
317P12V_AUX         VIA   -    MD0100PA00X+174277Y+141056X0200Y    R180 S0      
317P12V_AUX         VIA   -    MD0100PA00X+174277Y+141306X0200Y    R180 S0      
317P12V_AUX         VIA   -    MD0100PA00X+174027Y+141306X0200Y    R180 S0      
317P12V_AUX         VIA   -    MD0100PA00X+174027Y+141056X0200Y    R180 S0      
317P12V_AUX         VIA   -    MD0100PA00X+173777Y+141306X0200Y    R180 S0      
317P12V_AUX         VIA   -    MD0100PA00X+173777Y+141056X0200Y    R180 S0      
317P12V_AUX         VIA   -    MD0100PA00X+174277Y+141596X0200Y    R180 S0      
317P12V_AUX         VIA   -    MD0100PA00X+174277Y+141846X0200Y    R180 S0      
327P12V_AUX         PC85  -1          A01X+132151Y+140828X0198Y0197R180 S1      
317P12V_AUX         VIA   -    MD0100PA00X+134051Y+141649X0200Y    R180 S0      
317P12V_AUX         VIA   -    MD0100PA00X+133151Y+141132X0200Y    R180 S0      
317P12V_AUX         VIA   -    MD0100PA00X+133147Y+141383X0200Y    R180 S0      
317P12V_AUX         VIA   -    MD0100PA00X+133751Y+140882X0200Y    R180 S0      
317P12V_AUX         VIA   -    MD0100PA00X+133451Y+140882X0200Y    R180 S0      
317P12V_AUX         VIA   -    MD0100PA00X+133447Y+141383X0200Y    R180 S0      
317P12V_AUX         VIA   -    MD0100PA00X+133747Y+141383X0200Y    R180 S0      
317P12V_AUX         VIA   -    MD0100PA00X+133751Y+141132X0200Y    R180 S0      
317P12V_AUX         VIA   -    MD0100PA00X+133451Y+141132X0200Y    R180 S0      
317P12V_AUX         VIA   -    MD0100PA00X+133151Y+140882X0200Y    R180 S0      
317P12V_AUX         VIA   -    MD0100PA00X+133451Y+141649X0200Y    R180 S0      
317P12V_AUX         VIA   -    MD0100PA00X+133751Y+141649X0200Y    R180 S0      
317P12V_AUX         VIA   -    MD0100PA00X+133151Y+141649X0200Y    R180 S0      
317P12V_AUX         VIA   -    MD0100PA00X+134135Y+141387X0200Y    R180 S0      
317P12V_AUX         VIA   -    MD0100PA00X+134132Y+140963X0200Y    R180 S0      
317P12V_AUX         VIA   -    MD0100PA00X+134055Y+141902X0200Y    R180 S0      
317P12V_AUX         VIA   -    MD0100PA00X+134058Y+142154X0200Y    R180 S0      
317P12V_AUX         VIA   -    MD0100PA00X+133755Y+141902X0200Y    R180 S0      
317P12V_AUX         VIA   -    MD0100PA00X+133455Y+141902X0200Y    R180 S0      
317P12V_AUX         VIA   -    MD0100PA00X+133458Y+142154X0200Y    R180 S0      
317P12V_AUX         VIA   -    MD0100PA00X+133758Y+142154X0200Y    R180 S0      
317P12V_AUX         VIA   -    MD0100PA00X+133155Y+141902X0200Y    R180 S0      
317P12V_AUX         VIA   -    MD0100PA00X+133158Y+142154X0200Y    R180 S0      
317P12V_AUX         VIA   -    MD0100PA00X+135555Y+141902X0200Y    R180 S0      
317P12V_AUX         VIA   -    MD0100PA00X+134358Y+142154X0200Y    R180 S0      
317P12V_AUX         VIA   -    MD0100PA00X+134355Y+141902X0200Y    R180 S0      
317P12V_AUX         VIA   -    MD0100PA00X+134655Y+141902X0200Y    R180 S0      
317P12V_AUX         VIA   -    MD0100PA00X+134658Y+142154X0200Y    R180 S0      
317P12V_AUX         VIA   -    MD0100PA00X+135255Y+141902X0200Y    R180 S0      
317P12V_AUX         VIA   -    MD0100PA00X+134955Y+141902X0200Y    R180 S0      
317P12V_AUX         VIA   -    MD0100PA00X+134958Y+142154X0200Y    R180 S0      
317P12V_AUX         VIA   -    MD0100PA00X+135258Y+142154X0200Y    R180 S0      
317P12V_AUX         VIA   -    MD0100PA00X+135551Y+140882X0200Y    R180 S0      
317P12V_AUX         VIA   -    MD0100PA00X+135551Y+141382X0200Y    R180 S0      
317P12V_AUX         VIA   -    MD0100PA00X+135551Y+141132X0200Y    R180 S0      
317P12V_AUX         VIA   -    MD0100PA00X+135551Y+141649X0200Y    R180 S0      
317P12V_AUX         VIA   -    MD0100PA00X+135251Y+140882X0200Y    R180 S0      
317P12V_AUX         VIA   -    MD0100PA00X+135251Y+141382X0200Y    R180 S0      
317P12V_AUX         VIA   -    MD0100PA00X+135251Y+141132X0200Y    R180 S0      
317P12V_AUX         VIA   -    MD0100PA00X+134351Y+141649X0200Y    R180 S0      
317P12V_AUX         VIA   -    MD0100PA00X+135251Y+141649X0200Y    R180 S0      
317P12V_AUX         VIA   -    MD0100PA00X+134951Y+141649X0200Y    R180 S0      
317P12V_AUX         VIA   -    MD0100PA00X+134651Y+141649X0200Y    R180 S0      
317P12V_AUX         VIA   -    MD0100PA00X+134385Y+141387X0200Y    R180 S0      
317P12V_AUX         VIA   -    MD0100PA00X+134382Y+140963X0200Y    R180 S0      
317P12V_AUX         VIA   -    MD0100PA00X+134635Y+141387X0200Y    R180 S0      
317P12V_AUX         VIA   -    MD0100PA00X+134632Y+140963X0200Y    R180 S0      
317P12V_AUX         VIA   -    MD0100PA00X+134885Y+141387X0200Y    R180 S0      
317P12V_AUX         VIA   -    MD0100PA00X+134882Y+140963X0200Y    R180 S0      
327P12V_AUX         PL12  -2   M      A01X+134507Y+141173X0650Y1030R090 S1      
317P12V_AUX         VIA   -    MD0100PA00X+135851Y+140882X0200Y    R180 S0      
317P12V_AUX         VIA   -    MD0100PA00X+135851Y+141132X0200Y    R180 S0      
317P12V_AUX         VIA   -    MD0100PA00X+135851Y+141382X0200Y    R180 S0      
317P12V_AUX         VIA   -    MD0100PA00X+135851Y+141649X0200Y    R180 S0      
317P12V_AUX         VIA   -    MD0100PA00X+132861Y+142150X0200Y    R180 S0      
317P12V_AUX         VIA   -    MD0100PA00X+132854Y+141645X0200Y    R180 S0      
317P12V_AUX         VIA   -    MD0100PA00X+132858Y+141898X0200Y    R180 S0      
317P12V_AUX         VIA   -    MD0100PA00X+132850Y+141379X0200Y    R180 S0      
317P12V_AUX         VIA   -    MD0100PA00X+132854Y+141128X0200Y    R180 S0      
317P12V_AUX         VIA   -    MD0100PA00X+132261Y+142150X0200Y    R180 S0      
317P12V_AUX         VIA   -    MD0100PA00X+132561Y+142150X0200Y    R180 S0      
317P12V_AUX         VIA   -    MD0100PA00X+132258Y+141898X0200Y    R180 S0      
317P12V_AUX         VIA   -    MD0100PA00X+132254Y+141645X0200Y    R180 S0      
317P12V_AUX         VIA   -    MD0100PA00X+132558Y+141898X0200Y    R180 S0      
317P12V_AUX         VIA   -    MD0100PA00X+132554Y+141645X0200Y    R180 S0      
317P12V_AUX         VIA   -    MD0100PA00X+132554Y+141128X0200Y    R180 S0      
317P12V_AUX         VIA   -    MD0100PA00X+132550Y+141379X0200Y    R180 S0      
317P12V_AUX         VIA   -    MD0100PA00X+132250Y+141379X0200Y    R180 S0      
317P12V_AUX         VIA   -    MD0100PA00X+132254Y+141128X0200Y    R180 S0      
327P12V_AUX         PC511 -1          A01X+071022Y+143566X0198Y0197R090 S1      
317P12V_AUX         VIA   -    MD0100PA00X+070960Y+141447X0200Y         S0      
317P12V_AUX         VIA   -    MD0100PA00X+070960Y+141697X0200Y         S0      
317P12V_AUX         VIA   -    MD0100PA00X+071710Y+141447X0200Y         S0      
317P12V_AUX         VIA   -    MD0100PA00X+071460Y+141447X0200Y         S0      
317P12V_AUX         VIA   -    MD0100PA00X+071210Y+141447X0200Y         S0      
317P12V_AUX         VIA   -    MD0100PA00X+071710Y+141697X0200Y         S0      
317P12V_AUX         VIA   -    MD0100PA00X+071460Y+141697X0200Y         S0      
317P12V_AUX         VIA   -    MD0100PA00X+071210Y+141697X0200Y         S0      
317P12V_AUX         VIA   -    MD0100PA00X+070960Y+142237X0200Y         S0      
317P12V_AUX         VIA   -    MD0100PA00X+070960Y+141987X0200Y         S0      
317P12V_AUX         VIA   -    MD0100PA00X+070960Y+143027X0200Y         S0      
317P12V_AUX         VIA   -    MD0100PA00X+070960Y+142487X0200Y         S0      
317P12V_AUX         VIA   -    MD0100PA00X+070960Y+142737X0200Y         S0      
317P12V_AUX         VIA   -    MD0100PA00X+070960Y+143277X0200Y         S0      
317P12V_AUX         VIA   -    MD0100PA00X+071460Y+143027X0200Y         S0      
317P12V_AUX         VIA   -    MD0100PA00X+071210Y+143027X0200Y         S0      
317P12V_AUX         VIA   -    MD0100PA00X+071710Y+143027X0200Y         S0      
317P12V_AUX         VIA   -    MD0100PA00X+071460Y+143277X0200Y         S0      
317P12V_AUX         VIA   -    MD0100PA00X+071210Y+143277X0200Y         S0      
317P12V_AUX         VIA   -    MD0100PA00X+071710Y+143277X0200Y         S0      
317P12V_AUX         VIA   -    MD0100PA00X+094140Y+149120X0200Y         S0      
317P12V_AUX         VIA   -    MD0100PA00X+093890Y+149120X0200Y         S0      
317P12V_AUX         VIA   -    MD0100PA00X+093640Y+149120X0200Y         S0      
317P12V_AUX         VIA   -    MD0100PA00X+094390Y+149120X0200Y         S0      
317P12V_AUX         VIA   -    MD0100PA00X+094640Y+149120X0200Y         S0      
317P12V_AUX         VIA   -    MD0100PA00X+094140Y+150120X0200Y         S0      
317P12V_AUX         VIA   -    MD0100PA00X+094140Y+149870X0200Y         S0      
317P12V_AUX         VIA   -    MD0100PA00X+094140Y+149620X0200Y         S0      
317P12V_AUX         VIA   -    MD0100PA00X+094140Y+149370X0200Y         S0      
317P12V_AUX         VIA   -    MD0100PA00X+093890Y+150120X0200Y         S0      
317P12V_AUX         VIA   -    MD0100PA00X+093890Y+149870X0200Y         S0      
317P12V_AUX         VIA   -    MD0100PA00X+093890Y+149620X0200Y         S0      
317P12V_AUX         VIA   -    MD0100PA00X+093890Y+149370X0200Y         S0      
317P12V_AUX         VIA   -    MD0100PA00X+093640Y+150120X0200Y         S0      
317P12V_AUX         VIA   -    MD0100PA00X+093640Y+149870X0200Y         S0      
317P12V_AUX         VIA   -    MD0100PA00X+093640Y+149620X0200Y         S0      
317P12V_AUX         VIA   -    MD0100PA00X+093640Y+149370X0200Y         S0      
317P12V_AUX         VIA   -    MD0100PA00X+094390Y+150120X0200Y         S0      
317P12V_AUX         VIA   -    MD0100PA00X+094390Y+149870X0200Y         S0      
317P12V_AUX         VIA   -    MD0100PA00X+094390Y+149620X0200Y         S0      
317P12V_AUX         VIA   -    MD0100PA00X+094390Y+149370X0200Y         S0      
317P12V_AUX         VIA   -    MD0100PA00X+094640Y+149370X0200Y         S0      
317P12V_AUX         VIA   -    MD0100PA00X+094640Y+149620X0200Y         S0      
317P12V_AUX         VIA   -    MD0100PA00X+094640Y+149870X0200Y         S0      
317P12V_AUX         VIA   -    MD0100PA00X+094640Y+150120X0200Y         S0      
317P12V_AUX         VIA   -    MD0100PA00X+096140Y+149120X0200Y         S0      
317P12V_AUX         VIA   -    MD0100PA00X+095890Y+149120X0200Y         S0      
317P12V_AUX         VIA   -    MD0100PA00X+095640Y+149120X0200Y         S0      
317P12V_AUX         VIA   -    MD0100PA00X+094890Y+149120X0200Y         S0      
317P12V_AUX         VIA   -    MD0100PA00X+095140Y+149120X0200Y         S0      
317P12V_AUX         VIA   -    MD0100PA00X+095390Y+149120X0200Y         S0      
317P12V_AUX         VIA   -    MD0100PA00X+096140Y+149370X0200Y         S0      
317P12V_AUX         VIA   -    MD0100PA00X+095890Y+149370X0200Y         S0      
317P12V_AUX         VIA   -    MD0100PA00X+095640Y+149370X0200Y         S0      
317P12V_AUX         VIA   -    MD0100PA00X+094890Y+149370X0200Y         S0      
317P12V_AUX         VIA   -    MD0100PA00X+094890Y+149620X0200Y         S0      
317P12V_AUX         VIA   -    MD0100PA00X+094890Y+149870X0200Y         S0      
317P12V_AUX         VIA   -    MD0100PA00X+094890Y+150120X0200Y         S0      
317P12V_AUX         VIA   -    MD0100PA00X+095140Y+149370X0200Y         S0      
317P12V_AUX         VIA   -    MD0100PA00X+095140Y+149620X0200Y         S0      
317P12V_AUX         VIA   -    MD0100PA00X+095140Y+149870X0200Y         S0      
317P12V_AUX         VIA   -    MD0100PA00X+095140Y+150120X0200Y         S0      
317P12V_AUX         VIA   -    MD0100PA00X+095390Y+149370X0200Y         S0      
317P12V_AUX         VIA   -    MD0100PA00X+095390Y+149620X0200Y         S0      
317P12V_AUX         VIA   -    MD0100PA00X+095390Y+149870X0200Y         S0      
317P12V_AUX         VIA   -    MD0100PA00X+095390Y+150120X0200Y         S0      
317P12V_AUX         VIA   -    MD0100PA00X+096390Y+149120X0200Y         S0      
317P12V_AUX         VIA   -    MD0100PA00X+097727Y+149120X0200Y         S0      
317P12V_AUX         VIA   -    MD0100PA00X+097477Y+149120X0200Y         S0      
317P12V_AUX         VIA   -    MD0100PA00X+097227Y+149120X0200Y         S0      
317P12V_AUX         VIA   -    MD0100PA00X+096977Y+149120X0200Y         S0      
317P12V_AUX         VIA   -    MD0100PA00X+096727Y+149120X0200Y         S0      
317P12V_AUX         VIA   -    MD0100PA00X+096390Y+149370X0200Y         S0      
317P12V_AUX         VIA   -    MD0100PA00X+097727Y+150120X0200Y         S0      
317P12V_AUX         VIA   -    MD0100PA00X+097727Y+149870X0200Y         S0      
317P12V_AUX         VIA   -    MD0100PA00X+097727Y+149620X0200Y         S0      
317P12V_AUX         VIA   -    MD0100PA00X+097727Y+149370X0200Y         S0      
317P12V_AUX         VIA   -    MD0100PA00X+097477Y+150120X0200Y         S0      
317P12V_AUX         VIA   -    MD0100PA00X+097477Y+149870X0200Y         S0      
317P12V_AUX         VIA   -    MD0100PA00X+097477Y+149620X0200Y         S0      
317P12V_AUX         VIA   -    MD0100PA00X+097477Y+149370X0200Y         S0      
317P12V_AUX         VIA   -    MD0100PA00X+097227Y+150120X0200Y         S0      
317P12V_AUX         VIA   -    MD0100PA00X+097227Y+149870X0200Y         S0      
317P12V_AUX         VIA   -    MD0100PA00X+097227Y+149620X0200Y         S0      
317P12V_AUX         VIA   -    MD0100PA00X+097227Y+149370X0200Y         S0      
317P12V_AUX         VIA   -    MD0100PA00X+096977Y+150120X0200Y         S0      
317P12V_AUX         VIA   -    MD0100PA00X+096977Y+149870X0200Y         S0      
317P12V_AUX         VIA   -    MD0100PA00X+096977Y+149620X0200Y         S0      
317P12V_AUX         VIA   -    MD0100PA00X+096977Y+149370X0200Y         S0      
317P12V_AUX         VIA   -    MD0100PA00X+096727Y+149370X0200Y         S0      
317P12V_AUX         VIA   -    MD0100PA00X+096727Y+149620X0200Y         S0      
317P12V_AUX         VIA   -    MD0100PA00X+096727Y+149870X0200Y         S0      
317P12V_AUX         VIA   -    MD0100PA00X+096727Y+150120X0200Y         S0      
317P12V_AUX         VIA   -    MD0100PA00X+098727Y+149120X0200Y         S0      
317P12V_AUX         VIA   -    MD0100PA00X+098477Y+149120X0200Y         S0      
317P12V_AUX         VIA   -    MD0100PA00X+098227Y+149120X0200Y         S0      
317P12V_AUX         VIA   -    MD0100PA00X+097977Y+149120X0200Y         S0      
317P12V_AUX         VIA   -    MD0100PA00X+099063Y+149120X0200Y         S0      
317P12V_AUX         VIA   -    MD0100PA00X+098727Y+149370X0200Y         S0      
317P12V_AUX         VIA   -    MD0100PA00X+098477Y+149370X0200Y         S0      
317P12V_AUX         VIA   -    MD0100PA00X+098227Y+149370X0200Y         S0      
317P12V_AUX         VIA   -    MD0100PA00X+097977Y+149370X0200Y         S0      
317P12V_AUX         VIA   -    MD0100PA00X+099063Y+150120X0200Y         S0      
317P12V_AUX         VIA   -    MD0100PA00X+099063Y+149870X0200Y         S0      
317P12V_AUX         VIA   -    MD0100PA00X+099063Y+149620X0200Y         S0      
317P12V_AUX         VIA   -    MD0100PA00X+099063Y+149370X0200Y         S0      
317P12V_AUX         VIA   -    MD0100PA00X+100563Y+149120X0200Y         S0      
317P12V_AUX         VIA   -    MD0100PA00X+100313Y+149120X0200Y         S0      
317P12V_AUX         VIA   -    MD0100PA00X+099313Y+149120X0200Y         S0      
317P12V_AUX         VIA   -    MD0100PA00X+099563Y+149120X0200Y         S0      
317P12V_AUX         VIA   -    MD0100PA00X+099813Y+149120X0200Y         S0      
317P12V_AUX         VIA   -    MD0100PA00X+100063Y+149120X0200Y         S0      
317P12V_AUX         VIA   -    MD0100PA00X+099313Y+149870X0200Y         S0      
317P12V_AUX         VIA   -    MD0100PA00X+099313Y+150120X0200Y         S0      
317P12V_AUX         VIA   -    MD0100PA00X+099563Y+149370X0200Y         S0      
317P12V_AUX         VIA   -    MD0100PA00X+099563Y+149620X0200Y         S0      
317P12V_AUX         VIA   -    MD0100PA00X+099563Y+149870X0200Y         S0      
317P12V_AUX         VIA   -    MD0100PA00X+099563Y+150120X0200Y         S0      
317P12V_AUX         VIA   -    MD0100PA00X+099813Y+149370X0200Y         S0      
317P12V_AUX         VIA   -    MD0100PA00X+099813Y+149620X0200Y         S0      
317P12V_AUX         VIA   -    MD0100PA00X+099813Y+149870X0200Y         S0      
317P12V_AUX         VIA   -    MD0100PA00X+099813Y+150120X0200Y         S0      
317P12V_AUX         VIA   -    MD0100PA00X+100063Y+149370X0200Y         S0      
317P12V_AUX         VIA   -    MD0100PA00X+100063Y+149620X0200Y         S0      
317P12V_AUX         VIA   -    MD0100PA00X+100063Y+149870X0200Y         S0      
317P12V_AUX         VIA   -    MD0100PA00X+100063Y+150120X0200Y         S0      
317P12V_AUX         VIA   -    MD0100PA00X+100563Y+149370X0200Y         S0      
317P12V_AUX         VIA   -    MD0100PA00X+100313Y+149370X0200Y         S0      
317P12V_AUX         VIA   -    MD0100PA00X+099313Y+149370X0200Y         S0      
317P12V_AUX         VIA   -    MD0100PA00X+099313Y+149620X0200Y         S0      
317P12V_AUX         VIA   -    MD0100PA00X+101063Y+149120X0200Y         S0      
317P12V_AUX         VIA   -    MD0100PA00X+100813Y+149120X0200Y         S0      
317P12V_AUX         VIA   -    MD0100PA00X+101400Y+149120X0200Y         S0      
317P12V_AUX         VIA   -    MD0100PA00X+101650Y+149120X0200Y         S0      
317P12V_AUX         VIA   -    MD0100PA00X+101900Y+149120X0200Y         S0      
317P12V_AUX         VIA   -    MD0100PA00X+102150Y+149120X0200Y         S0      
317P12V_AUX         VIA   -    MD0100PA00X+101063Y+149370X0200Y         S0      
317P12V_AUX         VIA   -    MD0100PA00X+100813Y+149370X0200Y         S0      
317P12V_AUX         VIA   -    MD0100PA00X+101400Y+150120X0200Y         S0      
317P12V_AUX         VIA   -    MD0100PA00X+101400Y+149870X0200Y         S0      
317P12V_AUX         VIA   -    MD0100PA00X+101400Y+149620X0200Y         S0      
317P12V_AUX         VIA   -    MD0100PA00X+101400Y+149370X0200Y         S0      
317P12V_AUX         VIA   -    MD0100PA00X+101650Y+149370X0200Y         S0      
317P12V_AUX         VIA   -    MD0100PA00X+101650Y+149620X0200Y         S0      
317P12V_AUX         VIA   -    MD0100PA00X+101650Y+149870X0200Y         S0      
317P12V_AUX         VIA   -    MD0100PA00X+101650Y+150120X0200Y         S0      
317P12V_AUX         VIA   -    MD0100PA00X+101900Y+149370X0200Y         S0      
317P12V_AUX         VIA   -    MD0100PA00X+101900Y+149620X0200Y         S0      
317P12V_AUX         VIA   -    MD0100PA00X+101900Y+149870X0200Y         S0      
317P12V_AUX         VIA   -    MD0100PA00X+101900Y+150120X0200Y         S0      
317P12V_AUX         VIA   -    MD0100PA00X+102150Y+149370X0200Y         S0      
317P12V_AUX         VIA   -    MD0100PA00X+102150Y+149620X0200Y         S0      
317P12V_AUX         VIA   -    MD0100PA00X+102150Y+149870X0200Y         S0      
317P12V_AUX         VIA   -    MD0100PA00X+102150Y+150120X0200Y         S0      
317P12V_AUX         VIA   -    MD0100PA00X+103400Y+149370X0200Y         S0      
317P12V_AUX         VIA   -    MD0100PA00X+103150Y+149370X0200Y         S0      
317P12V_AUX         VIA   -    MD0100PA00X+102900Y+149370X0200Y         S0      
317P12V_AUX         VIA   -    MD0100PA00X+102650Y+149370X0200Y         S0      
317P12V_AUX         VIA   -    MD0100PA00X+102400Y+149370X0200Y         S0      
317P12V_AUX         VIA   -    MD0100PA00X+102400Y+149620X0200Y         S0      
317P12V_AUX         VIA   -    MD0100PA00X+102400Y+149870X0200Y         S0      
317P12V_AUX         VIA   -    MD0100PA00X+102400Y+150120X0200Y         S0      
317P12V_AUX         VIA   -    MD0100PA00X+103400Y+149120X0200Y         S0      
317P12V_AUX         VIA   -    MD0100PA00X+103150Y+149120X0200Y         S0      
317P12V_AUX         VIA   -    MD0100PA00X+102900Y+149120X0200Y         S0      
317P12V_AUX         VIA   -    MD0100PA00X+102650Y+149120X0200Y         S0      
317P12V_AUX         VIA   -    MD0100PA00X+102400Y+149120X0200Y         S0      
317P12V_AUX         VIA   -    MD0100PA00X+104987Y+149120X0200Y         S0      
317P12V_AUX         VIA   -    MD0100PA00X+103987Y+149120X0200Y         S0      
317P12V_AUX         VIA   -    MD0100PA00X+104237Y+149120X0200Y         S0      
317P12V_AUX         VIA   -    MD0100PA00X+103737Y+149120X0200Y         S0      
317P12V_AUX         VIA   -    MD0100PA00X+104487Y+149120X0200Y         S0      
317P12V_AUX         VIA   -    MD0100PA00X+104737Y+149120X0200Y         S0      
317P12V_AUX         VIA   -    MD0100PA00X+104987Y+149370X0200Y         S0      
317P12V_AUX         VIA   -    MD0100PA00X+103737Y+150120X0200Y         S0      
317P12V_AUX         VIA   -    MD0100PA00X+103987Y+149370X0200Y         S0      
317P12V_AUX         VIA   -    MD0100PA00X+103987Y+149620X0200Y         S0      
317P12V_AUX         VIA   -    MD0100PA00X+103987Y+149870X0200Y         S0      
317P12V_AUX         VIA   -    MD0100PA00X+103987Y+150120X0200Y         S0      
317P12V_AUX         VIA   -    MD0100PA00X+104237Y+149370X0200Y         S0      
317P12V_AUX         VIA   -    MD0100PA00X+104237Y+149620X0200Y         S0      
317P12V_AUX         VIA   -    MD0100PA00X+104237Y+149870X0200Y         S0      
317P12V_AUX         VIA   -    MD0100PA00X+104237Y+150120X0200Y         S0      
317P12V_AUX         VIA   -    MD0100PA00X+104487Y+149870X0200Y         S0      
317P12V_AUX         VIA   -    MD0100PA00X+104487Y+150120X0200Y         S0      
317P12V_AUX         VIA   -    MD0100PA00X+104737Y+150120X0200Y         S0      
317P12V_AUX         VIA   -    MD0100PA00X+103737Y+149870X0200Y         S0      
317P12V_AUX         VIA   -    MD0100PA00X+103737Y+149620X0200Y         S0      
317P12V_AUX         VIA   -    MD0100PA00X+103737Y+149370X0200Y         S0      
317P12V_AUX         VIA   -    MD0100PA00X+104487Y+149370X0200Y         S0      
317P12V_AUX         VIA   -    MD0100PA00X+104487Y+149620X0200Y         S0      
317P12V_AUX         VIA   -    MD0100PA00X+104737Y+149370X0200Y         S0      
317P12V_AUX         VIA   -    MD0100PA00X+104737Y+149620X0200Y         S0      
317P12V_AUX         VIA   -    MD0100PA00X+104737Y+149870X0200Y         S0      
317P12V_AUX         VIA   -    MD0100PA00X+105737Y+149120X0200Y         S0      
317P12V_AUX         VIA   -    MD0100PA00X+105487Y+149120X0200Y         S0      
317P12V_AUX         VIA   -    MD0100PA00X+105237Y+149120X0200Y         S0      
317P12V_AUX         VIA   -    MD0100PA00X+106073Y+149120X0200Y         S0      
317P12V_AUX         VIA   -    MD0100PA00X+106323Y+149120X0200Y         S0      
317P12V_AUX         VIA   -    MD0100PA00X+106573Y+149120X0200Y         S0      
317P12V_AUX         VIA   -    MD0100PA00X+105737Y+149370X0200Y         S0      
317P12V_AUX         VIA   -    MD0100PA00X+105487Y+149370X0200Y         S0      
317P12V_AUX         VIA   -    MD0100PA00X+105237Y+149370X0200Y         S0      
317P12V_AUX         VIA   -    MD0100PA00X+106073Y+150120X0200Y         S0      
317P12V_AUX         VIA   -    MD0100PA00X+106073Y+149870X0200Y         S0      
317P12V_AUX         VIA   -    MD0100PA00X+106073Y+149620X0200Y         S0      
317P12V_AUX         VIA   -    MD0100PA00X+106073Y+149370X0200Y         S0      
317P12V_AUX         VIA   -    MD0100PA00X+106323Y+149370X0200Y         S0      
317P12V_AUX         VIA   -    MD0100PA00X+106323Y+149620X0200Y         S0      
317P12V_AUX         VIA   -    MD0100PA00X+106323Y+149870X0200Y         S0      
317P12V_AUX         VIA   -    MD0100PA00X+106323Y+150120X0200Y         S0      
317P12V_AUX         VIA   -    MD0100PA00X+106573Y+149370X0200Y         S0      
317P12V_AUX         VIA   -    MD0100PA00X+106573Y+149620X0200Y         S0      
317P12V_AUX         VIA   -    MD0100PA00X+106573Y+149870X0200Y         S0      
317P12V_AUX         VIA   -    MD0100PA00X+106573Y+150120X0200Y         S0      
317P12V_AUX         VIA   -    MD0100PA00X+108073Y+149370X0200Y         S0      
317P12V_AUX         VIA   -    MD0100PA00X+107823Y+149370X0200Y         S0      
317P12V_AUX         VIA   -    MD0100PA00X+107573Y+149370X0200Y         S0      
317P12V_AUX         VIA   -    MD0100PA00X+107323Y+149370X0200Y         S0      
317P12V_AUX         VIA   -    MD0100PA00X+106823Y+149370X0200Y         S0      
317P12V_AUX         VIA   -    MD0100PA00X+106823Y+149620X0200Y         S0      
317P12V_AUX         VIA   -    MD0100PA00X+106823Y+149870X0200Y         S0      
317P12V_AUX         VIA   -    MD0100PA00X+106823Y+150120X0200Y         S0      
317P12V_AUX         VIA   -    MD0100PA00X+107073Y+149370X0200Y         S0      
317P12V_AUX         VIA   -    MD0100PA00X+107073Y+149620X0200Y         S0      
317P12V_AUX         VIA   -    MD0100PA00X+107073Y+149870X0200Y         S0      
317P12V_AUX         VIA   -    MD0100PA00X+107073Y+150120X0200Y         S0      
317P12V_AUX         VIA   -    MD0100PA00X+108073Y+149120X0200Y         S0      
317P12V_AUX         VIA   -    MD0100PA00X+107823Y+149120X0200Y         S0      
317P12V_AUX         VIA   -    MD0100PA00X+107573Y+149120X0200Y         S0      
317P12V_AUX         VIA   -    MD0100PA00X+107323Y+149120X0200Y         S0      
317P12V_AUX         VIA   -    MD0100PA00X+106823Y+149120X0200Y         S0      
317P12V_AUX         VIA   -    MD0100PA00X+107073Y+149120X0200Y         S0      
317P12V_AUX         VIA   -    MD0100PA00X+108410Y+149120X0200Y         S0      
317P12V_AUX         VIA   -    MD0100PA00X+108660Y+149120X0200Y         S0      
317P12V_AUX         VIA   -    MD0100PA00X+108910Y+149120X0200Y         S0      
317P12V_AUX         VIA   -    MD0100PA00X+109160Y+149120X0200Y         S0      
317P12V_AUX         VIA   -    MD0100PA00X+108410Y+149620X0200Y    R180 S0      
317P12V_AUX         VIA   -    MD0100PA00X+108410Y+150120X0200Y         S0      
317P12V_AUX         VIA   -    MD0100PA00X+108410Y+149870X0200Y         S0      
317P12V_AUX         VIA   -    MD0100PA00X+108410Y+149370X0200Y         S0      
317P12V_AUX         VIA   -    MD0100PA00X+108660Y+149370X0200Y         S0      
317P12V_AUX         VIA   -    MD0100PA00X+108660Y+149620X0200Y         S0      
317P12V_AUX         VIA   -    MD0100PA00X+108660Y+149870X0200Y         S0      
317P12V_AUX         VIA   -    MD0100PA00X+108660Y+150120X0200Y         S0      
317P12V_AUX         VIA   -    MD0100PA00X+108910Y+149370X0200Y         S0      
317P12V_AUX         VIA   -    MD0100PA00X+108910Y+149620X0200Y         S0      
317P12V_AUX         VIA   -    MD0100PA00X+108910Y+149870X0200Y         S0      
317P12V_AUX         VIA   -    MD0100PA00X+108910Y+150120X0200Y         S0      
317P12V_AUX         VIA   -    MD0100PA00X+109160Y+149370X0200Y         S0      
317P12V_AUX         VIA   -    MD0100PA00X+109160Y+149620X0200Y         S0      
317P12V_AUX         VIA   -    MD0100PA00X+109160Y+149870X0200Y         S0      
317P12V_AUX         VIA   -    MD0100PA00X+109160Y+150120X0200Y         S0      
327P12V_AUX         R1837 -1          A01X+005077Y+077979X1260Y0591R180 S1      
317P12V_AUX         VIA   -    MD0100PA00X+005875Y+077522X0200Y         S0      
317P12V_AUX         VIA   -    MD0100PA00X+006125Y+077522X0200Y         S0      
317P12V_AUX         VIA   -    MD0100PA00X+006125Y+077772X0200Y         S0      
317P12V_AUX         VIA   -    MD0100PA00X+005875Y+077772X0200Y         S0      
317P12V_AUX         VIA   -    MD0100PA00X+005875Y+078772X0200Y         S0      
317P12V_AUX         VIA   -    MD0100PA00X+005875Y+078522X0200Y         S0      
317P12V_AUX         VIA   -    MD0100PA00X+005875Y+078272X0200Y         S0      
317P12V_AUX         VIA   -    MD0100PA00X+005606Y+078275X0200Y         S0      
317P12V_AUX         VIA   -    MD0100PA00X+006125Y+078272X0200Y         S0      
317P12V_AUX         VIA   -    MD0100PA00X+006125Y+078522X0200Y         S0      
317P12V_AUX         VIA   -    MD0100PA00X+005606Y+078525X0200Y         S0      
317P12V_AUX         VIA   -    MD0100PA00X+006125Y+078772X0200Y         S0      
317P12V_AUX         VIA   -    MD0100PA00X+005606Y+078775X0200Y         S0      
317P12V_AUX         VIA   -    MD0100PA00X+005606Y+079025X0200Y         S0      
317P12V_AUX         VIA   -    MD0100PA00X+006125Y+079022X0200Y         S0      
317P12V_AUX         VIA   -    MD0100PA00X+006125Y+079272X0200Y         S0      
317P12V_AUX         VIA   -    MD0100PA00X+005606Y+079275X0200Y         S0      
317P12V_AUX         VIA   -    MD0100PA00X+006125Y+078022X0200Y         S0      
317P12V_AUX         VIA   -    MD0100PA00X+005875Y+078022X0200Y         S0      
317P12V_AUX         VIA   -    MD0100PA00X+005875Y+079272X0200Y         S0      
317P12V_AUX         VIA   -    MD0100PA00X+005875Y+079022X0200Y         S0      
327P12V_AUX         R1838 -1          A01X+178960Y+070908X1260Y0591R090 S1      
317P12V_AUX         VIA   -    MD0100PA00X+180205Y+071094X0200Y    R180 S0      
317P12V_AUX         VIA   -    MD0100PA00X+181250Y+071594X0200Y    R180 S0      
317P12V_AUX         VIA   -    MD0100PA00X+181250Y+071344X0200Y    R180 S0      
317P12V_AUX         VIA   -    MD0100PA00X+181250Y+071094X0200Y    R180 S0      
317P12V_AUX         VIA   -    MD0100PA00X+180550Y+071594X0200Y    R180 S0      
317P12V_AUX         VIA   -    MD0100PA00X+180550Y+071344X0200Y    R180 S0      
317P12V_AUX         VIA   -    MD0100PA00X+180550Y+071094X0200Y    R180 S0      
317P12V_AUX         VIA   -    MD0100PA00X+180900Y+071594X0200Y    R180 S0      
317P12V_AUX         VIA   -    MD0100PA00X+180900Y+071344X0200Y    R180 S0      
317P12V_AUX         VIA   -    MD0100PA00X+180900Y+071094X0200Y    R180 S0      
317P12V_AUX         VIA   -    MD0100PA00X+180546Y+070806X0200Y    R180 S0      
317P12V_AUX         VIA   -    MD0100PA00X+180196Y+070806X0200Y    R180 S0      
317P12V_AUX         VIA   -    MD0100PA00X+179846Y+070806X0200Y    R180 S0      
317P12V_AUX         VIA   -    MD0100PA00X+180546Y+070556X0200Y    R180 S0      
317P12V_AUX         VIA   -    MD0100PA00X+180196Y+070556X0200Y    R180 S0      
317P12V_AUX         VIA   -    MD0100PA00X+179846Y+070556X0200Y    R180 S0      
317P12V_AUX         VIA   -    MD0100PA00X+179846Y+070306X0200Y    R180 S0      
317P12V_AUX         VIA   -    MD0100PA00X+180196Y+070306X0200Y    R180 S0      
317P12V_AUX         VIA   -    MD0100PA00X+180546Y+070306X0200Y    R180 S0      
317P12V_AUX         VIA   -    MD0100PA00X+179846Y+070056X0200Y    R180 S0      
317P12V_AUX         VIA   -    MD0100PA00X+180196Y+070056X0200Y    R180 S0      
317P12V_AUX         VIA   -    MD0100PA00X+180546Y+070056X0200Y    R180 S0      
317P12V_AUX         VIA   -    MD0100PA00X+180546Y+069806X0200Y    R180 S0      
317P12V_AUX         VIA   -    MD0100PA00X+180196Y+069806X0200Y    R180 S0      
317P12V_AUX         VIA   -    MD0100PA00X+179846Y+069806X0200Y    R180 S0      
317P12V_AUX         VIA   -    MD0100PA00X+181246Y+070806X0200Y    R180 S0      
317P12V_AUX         VIA   -    MD0100PA00X+180896Y+070806X0200Y    R180 S0      
317P12V_AUX         VIA   -    MD0100PA00X+181246Y+070556X0200Y    R180 S0      
317P12V_AUX         VIA   -    MD0100PA00X+180896Y+070556X0200Y    R180 S0      
317P12V_AUX         VIA   -    MD0100PA00X+180896Y+070306X0200Y    R180 S0      
317P12V_AUX         VIA   -    MD0100PA00X+181246Y+070306X0200Y    R180 S0      
317P12V_AUX         VIA   -    MD0100PA00X+180896Y+070056X0200Y    R180 S0      
317P12V_AUX         VIA   -    MD0100PA00X+181246Y+070056X0200Y    R180 S0      
317P12V_AUX         VIA   -    MD0100PA00X+181246Y+069806X0200Y    R180 S0      
317P12V_AUX         VIA   -    MD0100PA00X+180896Y+069806X0200Y    R180 S0      
327P12V_AUX         PC479 -1          A01X+144174Y+059944X0198Y0197R270 S1      
327P12V_AUX         PL65  -2   M      A01X+150013Y+060934X0650Y1030R180 S1      
317P12V_AUX         VIA   -    MD0100PA00X+149799Y+061034X0200Y    R090 S0      
317P12V_AUX         VIA   -    MD0100PA00X+149799Y+060784X0200Y    R090 S0      
317P12V_AUX         VIA   -    MD0100PA00X+149799Y+060534X0200Y    R090 S0      
317P12V_AUX         VIA   -    MD0100PA00X+149799Y+061284X0200Y    R090 S0      
317P12V_AUX         VIA   -    MD0100PA00X+150249Y+061284X0200Y    R090 S0      
317P12V_AUX         VIA   -    MD0100PA00X+150249Y+061034X0200Y    R090 S0      
317P12V_AUX         VIA   -    MD0100PA00X+150249Y+060784X0200Y    R090 S0      
317P12V_AUX         VIA   -    MD0100PA00X+150249Y+060534X0200Y    R090 S0      
327P12V_AUX         PL53  -2   M      A01X+145406Y+061962X0650Y1030R270 S1      
317P12V_AUX         VIA   -    MD0100PA00X+145040Y+062184X0200Y    R180 S0      
317P12V_AUX         VIA   -    MD0100PA00X+145290Y+062184X0200Y    R180 S0      
317P12V_AUX         VIA   -    MD0100PA00X+145044Y+061736X0200Y    R180 S0      
317P12V_AUX         VIA   -    MD0100PA00X+145294Y+061736X0200Y    R180 S0      
317P12V_AUX         VIA   -    MD0100PA00X+145790Y+062184X0200Y    R180 S0      
317P12V_AUX         VIA   -    MD0100PA00X+145540Y+062184X0200Y    R180 S0      
317P12V_AUX         VIA   -    MD0100PA00X+145794Y+061736X0200Y    R180 S0      
317P12V_AUX         VIA   -    MD0100PA00X+145544Y+061736X0200Y    R180 S0      
317P12V_AUX         VIA   -    MD0100PA00X+144371Y+060795X0200Y    R180 S0      
317P12V_AUX         VIA   -    MD0100PA00X+144071Y+060795X0200Y    R180 S0      
317P12V_AUX         VIA   -    MD0100PA00X+144371Y+061095X0200Y    R180 S0      
317P12V_AUX         VIA   -    MD0100PA00X+144071Y+061095X0200Y    R180 S0      
317P12V_AUX         VIA   -    MD0100PA00X+144971Y+060795X0200Y    R180 S0      
317P12V_AUX         VIA   -    MD0100PA00X+144671Y+060795X0200Y    R180 S0      
317P12V_AUX         VIA   -    MD0100PA00X+144671Y+061095X0200Y    R180 S0      
317P12V_AUX         VIA   -    MD0100PA00X+144971Y+061095X0200Y    R180 S0      
317P12V_AUX         VIA   -    MD0100PA00X+145271Y+060795X0200Y    R180 S0      
317P12V_AUX         VIA   -    MD0100PA00X+145271Y+061095X0200Y    R180 S0      
317P12V_AUX         VIA   -    MD0100PA00X+145871Y+060795X0200Y    R180 S0      
317P12V_AUX         VIA   -    MD0100PA00X+145571Y+060795X0200Y    R180 S0      
317P12V_AUX         VIA   -    MD0100PA00X+146171Y+060795X0200Y    R180 S0      
317P12V_AUX         VIA   -    MD0100PA00X+146171Y+061095X0200Y    R180 S0      
317P12V_AUX         VIA   -    MD0100PA00X+145571Y+061095X0200Y    R180 S0      
317P12V_AUX         VIA   -    MD0100PA00X+145871Y+061095X0200Y    R180 S0      
317P12V_AUX         VIA   -    MD0100PA00X+146471Y+060795X0200Y    R180 S0      
317P12V_AUX         VIA   -    MD0100PA00X+146471Y+061095X0200Y    R180 S0      
317P12V_AUX         VIA   -    MD0100PA00X+146771Y+060795X0200Y    R180 S0      
317P12V_AUX         VIA   -    MD0100PA00X+146771Y+061095X0200Y    R180 S0      
317P12V_AUX         VIA   -    MD0100PA00X+149264Y+061276X0200Y    R090 S0      
317P12V_AUX         VIA   -    MD0100PA00X+149264Y+061026X0200Y    R090 S0      
317P12V_AUX         VIA   -    MD0100PA00X+149264Y+060776X0200Y    R090 S0      
317P12V_AUX         VIA   -    MD0100PA00X+149264Y+060526X0200Y    R090 S0      
317P12V_AUX         VIA   -    MD0100PA00X+149524Y+061034X0200Y    R090 S0      
317P12V_AUX         VIA   -    MD0100PA00X+149524Y+060784X0200Y    R090 S0      
317P12V_AUX         VIA   -    MD0100PA00X+149549Y+060244X0200Y    R090 S0      
317P12V_AUX         VIA   -    MD0100PA00X+149524Y+060534X0200Y    R090 S0      
317P12V_AUX         VIA   -    MD0100PA00X+149799Y+059994X0200Y    R090 S0      
317P12V_AUX         VIA   -    MD0100PA00X+149799Y+060244X0200Y    R090 S0      
317P12V_AUX         VIA   -    MD0100PA00X+149549Y+059994X0200Y    R090 S0      
317P12V_AUX         VIA   -    MD0100PA00X+149524Y+061284X0200Y    R090 S0      
317P12V_AUX         VIA   -    MD0100PA00X+150049Y+059994X0200Y    R090 S0      
317P12V_AUX         VIA   -    MD0100PA00X+150049Y+060244X0200Y    R090 S0      
317P12V_AUX         VIA   -    MD0100PA00X+150299Y+059994X0200Y    R090 S0      
317P12V_AUX         VIA   -    MD0100PA00X+150299Y+060244X0200Y    R090 S0      
317P12V_AUX         VIA   -    MD0100PA00X+144371Y+062295X0200Y    R180 S0      
317P12V_AUX         VIA   -    MD0100PA00X+144071Y+062295X0200Y    R180 S0      
317P12V_AUX         VIA   -    MD0100PA00X+144671Y+062295X0200Y    R180 S0      
317P12V_AUX         VIA   -    MD0100PA00X+144371Y+061395X0200Y    R180 S0      
317P12V_AUX         VIA   -    MD0100PA00X+144071Y+061395X0200Y    R180 S0      
317P12V_AUX         VIA   -    MD0100PA00X+144671Y+061395X0200Y    R180 S0      
317P12V_AUX         VIA   -    MD0100PA00X+144971Y+061395X0200Y    R180 S0      
317P12V_AUX         VIA   -    MD0100PA00X+144371Y+061995X0200Y    R180 S0      
317P12V_AUX         VIA   -    MD0100PA00X+144371Y+061695X0200Y    R180 S0      
317P12V_AUX         VIA   -    MD0100PA00X+144071Y+061695X0200Y    R180 S0      
317P12V_AUX         VIA   -    MD0100PA00X+144071Y+061995X0200Y    R180 S0      
317P12V_AUX         VIA   -    MD0100PA00X+144671Y+061995X0200Y    R180 S0      
317P12V_AUX         VIA   -    MD0100PA00X+144671Y+061695X0200Y    R180 S0      
317P12V_AUX         VIA   -    MD0100PA00X+145271Y+061395X0200Y    R180 S0      
317P12V_AUX         VIA   -    MD0100PA00X+146471Y+062295X0200Y    R180 S0      
317P12V_AUX         VIA   -    MD0100PA00X+146171Y+062295X0200Y    R180 S0      
317P12V_AUX         VIA   -    MD0100PA00X+146771Y+062295X0200Y    R180 S0      
317P12V_AUX         VIA   -    MD0100PA00X+146171Y+061395X0200Y    R180 S0      
317P12V_AUX         VIA   -    MD0100PA00X+145571Y+061395X0200Y    R180 S0      
317P12V_AUX         VIA   -    MD0100PA00X+145871Y+061395X0200Y    R180 S0      
317P12V_AUX         VIA   -    MD0100PA00X+146471Y+061395X0200Y    R180 S0      
317P12V_AUX         VIA   -    MD0100PA00X+146471Y+061995X0200Y    R180 S0      
317P12V_AUX         VIA   -    MD0100PA00X+146471Y+061695X0200Y    R180 S0      
317P12V_AUX         VIA   -    MD0100PA00X+146171Y+061995X0200Y    R180 S0      
317P12V_AUX         VIA   -    MD0100PA00X+146171Y+061695X0200Y    R180 S0      
317P12V_AUX         VIA   -    MD0100PA00X+146771Y+061395X0200Y    R180 S0      
317P12V_AUX         VIA   -    MD0100PA00X+146771Y+061995X0200Y    R180 S0      
317P12V_AUX         VIA   -    MD0100PA00X+146771Y+061695X0200Y    R180 S0      
317P12V_AUX         VIA   -    MD0100PA00X+149289Y+061591X0200Y    R090 S0      
317P12V_AUX         VIA   -    MD0100PA00X+149289Y+061841X0200Y    R090 S0      
317P12V_AUX         VIA   -    MD0100PA00X+149799Y+061849X0200Y    R090 S0      
317P12V_AUX         VIA   -    MD0100PA00X+149799Y+061599X0200Y    R090 S0      
317P12V_AUX         VIA   -    MD0100PA00X+149549Y+061849X0200Y    R090 S0      
317P12V_AUX         VIA   -    MD0100PA00X+149549Y+061599X0200Y    R090 S0      
317P12V_AUX         VIA   -    MD0100PA00X+150299Y+061849X0200Y    R090 S0      
317P12V_AUX         VIA   -    MD0100PA00X+150299Y+061599X0200Y    R090 S0      
317P12V_AUX         VIA   -    MD0100PA00X+150049Y+061849X0200Y    R090 S0      
317P12V_AUX         VIA   -    MD0100PA00X+150049Y+061599X0200Y    R090 S0      
327P12V_AUX         PC583 -1          A01X+149156Y+059761X0198Y0197R270 S1      
327P12V_AUX         PC6004-1          A01X+036456Y+061744X0198Y0197     S1      
317P12V_AUX         VIA   -    MD0100PA00X+036103Y+061650X0200Y    R180 S0      
317P12V_AUX         VIA   -    MD0100PA00X+036103Y+061940X0200Y    R180 S0      
317P12V_AUX         VIA   -    MD0100PA00X+035503Y+061650X0200Y    R180 S0      
317P12V_AUX         VIA   -    MD0100PA00X+035503Y+061940X0200Y    R180 S0      
317P12V_AUX         VIA   -    MD0100PA00X+035803Y+061650X0200Y    R180 S0      
317P12V_AUX         VIA   -    MD0100PA00X+035803Y+061940X0200Y    R180 S0      
317P12V_AUX         VIA   -    MD0100PA00X+033703Y+061650X0200Y    R180 S0      
317P12V_AUX         VIA   -    MD0100PA00X+033703Y+061940X0200Y    R180 S0      
317P12V_AUX         VIA   -    MD0100PA00X+034003Y+061650X0200Y    R180 S0      
317P12V_AUX         VIA   -    MD0100PA00X+034003Y+061940X0200Y    R180 S0      
317P12V_AUX         VIA   -    MD0100PA00X+033139Y+061940X0200Y    R180 S0      
317P12V_AUX         VIA   -    MD0100PA00X+033139Y+061650X0200Y    R180 S0      
317P12V_AUX         VIA   -    MD0100PA00X+033403Y+061650X0200Y    R180 S0      
317P12V_AUX         VIA   -    MD0100PA00X+033403Y+061940X0200Y    R180 S0      
317P12V_AUX         VIA   -    MD0100PA00X+035803Y+060450X0200Y    R180 S0      
317P12V_AUX         VIA   -    MD0100PA00X+035803Y+061050X0200Y    R180 S0      
317P12V_AUX         VIA   -    MD0100PA00X+035803Y+061350X0200Y    R180 S0      
317P12V_AUX         VIA   -    MD0100PA00X+035803Y+060750X0200Y    R180 S0      
317P12V_AUX         VIA   -    MD0100PA00X+036103Y+061050X0200Y    R180 S0      
317P12V_AUX         VIA   -    MD0100PA00X+036103Y+061350X0200Y    R180 S0      
317P12V_AUX         VIA   -    MD0100PA00X+036103Y+060750X0200Y    R180 S0      
317P12V_AUX         VIA   -    MD0100PA00X+035503Y+060450X0200Y    R180 S0      
317P12V_AUX         VIA   -    MD0100PA00X+035203Y+060450X0200Y    R180 S0      
317P12V_AUX         VIA   -    MD0100PA00X+035503Y+061050X0200Y    R180 S0      
317P12V_AUX         VIA   -    MD0100PA00X+035503Y+061350X0200Y    R180 S0      
317P12V_AUX         VIA   -    MD0100PA00X+035503Y+060750X0200Y    R180 S0      
317P12V_AUX         VIA   -    MD0100PA00X+035203Y+061050X0200Y    R180 S0      
317P12V_AUX         VIA   -    MD0100PA00X+035203Y+060750X0200Y    R180 S0      
317P12V_AUX         VIA   -    MD0100PA00X+034003Y+060450X0200Y    R180 S0      
317P12V_AUX         VIA   -    MD0100PA00X+034903Y+060450X0200Y    R180 S0      
317P12V_AUX         VIA   -    MD0100PA00X+034303Y+060450X0200Y    R180 S0      
317P12V_AUX         VIA   -    MD0100PA00X+034603Y+060450X0200Y    R180 S0      
317P12V_AUX         VIA   -    MD0100PA00X+034003Y+061350X0200Y    R180 S0      
317P12V_AUX         VIA   -    MD0100PA00X+034003Y+061050X0200Y    R180 S0      
317P12V_AUX         VIA   -    MD0100PA00X+034003Y+060750X0200Y    R180 S0      
317P12V_AUX         VIA   -    MD0100PA00X+034903Y+061050X0200Y    R180 S0      
317P12V_AUX         VIA   -    MD0100PA00X+034303Y+061050X0200Y    R180 S0      
317P12V_AUX         VIA   -    MD0100PA00X+034603Y+061050X0200Y    R180 S0      
317P12V_AUX         VIA   -    MD0100PA00X+034903Y+060750X0200Y    R180 S0      
317P12V_AUX         VIA   -    MD0100PA00X+034303Y+060750X0200Y    R180 S0      
317P12V_AUX         VIA   -    MD0100PA00X+034603Y+060750X0200Y    R180 S0      
317P12V_AUX         VIA   -    MD0100PA00X+033703Y+061050X0200Y    R180 S0      
317P12V_AUX         VIA   -    MD0100PA00X+033703Y+061350X0200Y    R180 S0      
317P12V_AUX         VIA   -    MD0100PA00X+033703Y+060750X0200Y    R180 S0      
317P12V_AUX         VIA   -    MD0100PA00X+033139Y+061350X0200Y    R180 S0      
317P12V_AUX         VIA   -    MD0100PA00X+033139Y+061050X0200Y    R180 S0      
317P12V_AUX         VIA   -    MD0100PA00X+033403Y+061050X0200Y    R180 S0      
317P12V_AUX         VIA   -    MD0100PA00X+033403Y+061350X0200Y    R180 S0      
317P12V_AUX         VIA   -    MD0100PA00X+035122Y+061835X0200Y    R180 S0      
317P12V_AUX         VIA   -    MD0100PA00X+035119Y+061402X0200Y    R180 S0      
317P12V_AUX         VIA   -    MD0100PA00X+034872Y+061835X0200Y    R180 S0      
317P12V_AUX         VIA   -    MD0100PA00X+034622Y+061835X0200Y    R180 S0      
317P12V_AUX         VIA   -    MD0100PA00X+034372Y+061835X0200Y    R180 S0      
317P12V_AUX         VIA   -    MD0100PA00X+034869Y+061402X0200Y    R180 S0      
317P12V_AUX         VIA   -    MD0100PA00X+034619Y+061402X0200Y    R180 S0      
317P12V_AUX         VIA   -    MD0100PA00X+034369Y+061402X0200Y    R180 S0      
327P12V_AUX         PL30  -2   M      A01X+034738Y+061616X0650Y1030R270 S1      
317P12V_AUX         VIA   -    MD0100PA00X+082520Y+058030X0200Y         S0      
327P12V_AUX         R2528 -1          A01X+080813Y+054145X0198Y0197     S1      
327P12V_AUX         R2530 -1          A01X+083475Y+056930X0198Y0197R270 S1      
317P12V_AUX         VIA   -    MD0100PA00X+046533Y+056913X0200Y         S0      
317P12V_AUX         VIA   -    MD0100PA00X+045993Y+056913X0200Y         S0      
317P12V_AUX         VIA   -    MD0100PA00X+045743Y+056913X0200Y         S0      
317P12V_AUX         VIA   -    MD0100PA00X+046283Y+056913X0200Y         S0      
317P12V_AUX         VIA   -    MD0100PA00X+045743Y+056663X0200Y         S0      
317P12V_AUX         VIA   -    MD0100PA00X+045993Y+056663X0200Y         S0      
317P12V_AUX         VIA   -    MD0100PA00X+045993Y+057663X0200Y         S0      
317P12V_AUX         VIA   -    MD0100PA00X+045743Y+057663X0200Y         S0      
317P12V_AUX         VIA   -    MD0100PA00X+045993Y+057413X0200Y         S0      
317P12V_AUX         VIA   -    MD0100PA00X+045993Y+057163X0200Y         S0      
317P12V_AUX         VIA   -    MD0100PA00X+045743Y+057413X0200Y         S0      
317P12V_AUX         VIA   -    MD0100PA00X+045743Y+057163X0200Y         S0      
317P12V_AUX         VIA   -    MD0100PA00X+047033Y+056913X0200Y         S0      
317P12V_AUX         VIA   -    MD0100PA00X+046783Y+056913X0200Y         S0      
317P12V_AUX         VIA   -    MD0100PA00X+047573Y+056913X0200Y         S0      
317P12V_AUX         VIA   -    MD0100PA00X+047323Y+056913X0200Y         S0      
317P12V_AUX         VIA   -    MD0100PA00X+047323Y+057663X0200Y         S0      
317P12V_AUX         VIA   -    MD0100PA00X+047573Y+057663X0200Y         S0      
317P12V_AUX         VIA   -    MD0100PA00X+047323Y+057163X0200Y         S0      
317P12V_AUX         VIA   -    MD0100PA00X+047323Y+057413X0200Y         S0      
317P12V_AUX         VIA   -    MD0100PA00X+047573Y+057163X0200Y         S0      
317P12V_AUX         VIA   -    MD0100PA00X+047573Y+057413X0200Y         S0      
327P12V_AUX         PC6007-1          A01X+048189Y+057857X0198Y0197     S1      
317P12V_AUX         VIA   -    MD0100PA00X+046283Y+056663X0200Y         S0      
317P12V_AUX         VIA   -    MD0100PA00X+046783Y+056663X0200Y         S0      
317P12V_AUX         VIA   -    MD0100PA00X+046533Y+056663X0200Y         S0      
317P12V_AUX         VIA   -    MD0100PA00X+047033Y+056663X0200Y         S0      
317P12V_AUX         VIA   -    MD0100PA00X+047323Y+056663X0200Y         S0      
317P12V_AUX         VIA   -    MD0100PA00X+047573Y+056663X0200Y         S0      
327P12V_AUX         PL37  -2   M      A01X+046658Y+057388X0650Y1030R270 S1      
317P12V_AUX         VIA   -    MD0100PA00X+046283Y+057613X0200Y         S0      
317P12V_AUX         VIA   -    MD0100PA00X+046283Y+057163X0200Y         S0      
317P12V_AUX         VIA   -    MD0100PA00X+047033Y+057163X0200Y         S0      
317P12V_AUX         VIA   -    MD0100PA00X+046533Y+057613X0200Y         S0      
317P12V_AUX         VIA   -    MD0100PA00X+046783Y+057613X0200Y         S0      
317P12V_AUX         VIA   -    MD0100PA00X+046533Y+057163X0200Y         S0      
317P12V_AUX         VIA   -    MD0100PA00X+046783Y+057163X0200Y         S0      
317P12V_AUX         VIA   -    MD0100PA00X+047033Y+057613X0200Y         S0      
327P12V_AUX         PR181 -1          A01X+040295Y+055592X0198Y0197R180 S1      
317P12V_AUX         VIA   -    MD0100PA00X+040855Y+055785X0200Y         S0      
317P12V_AUX         VIA   -    MD0100PA00X+151626Y+054798X0200Y         S0      
327P12V_AUX         PR314 -1          A01X+151383Y+054798X0198Y0197R180 S1      
317P12V_AUX         VIA   -    MD0100PA00X+130682Y+052273X0200Y    R180 S0      
317P12V_AUX         VIA   -    MD0100PA00X+130893Y+052411X0200Y    R180 S0      
317P12V_AUX         VIA   -    MD0100PA00X+130435Y+052324X0200Y    R180 S0      
317P12V_AUX         VIA   -    MD0100PA00X+130457Y+052574X0200Y    R180 S0      
317P12V_AUX         VIA   -    MD0100PA00X+130216Y+052492X0200Y    R180 S0      
317P12V_AUX         VIA   -    MD0100PA00X+130712Y+052590X0200Y    R180 S0      
327P12V_AUX         PC6001-1          A01X+130223Y+052742X0198Y0197R180 S1      
327P12V_AUX         R336  -1          A01X+055310Y+042395X0198Y0197     S1      
317P12V_AUX         VIA   -    MD0100PA00X+054753Y+042541X0200Y    R270 S0      
317P12V_AUX         VIA   -    MD0100PA00X+060889Y+049440X0200Y         S0      
317P12V_AUX         VIA   -    MD0100PA00X+034889Y+041162X0200Y         S0      
317P12V_AUX         VIA   -    MD0100PA00X+034889Y+040912X0200Y         S0      
317P12V_AUX         VIA   -    MD0100PA00X+035139Y+041162X0200Y         S0      
317P12V_AUX         VIA   -    MD0100PA00X+035389Y+041162X0200Y         S0      
317P12V_AUX         VIA   -    MD0100PA00X+035389Y+040912X0200Y         S0      
317P12V_AUX         VIA   -    MD0100PA00X+035139Y+040912X0200Y         S0      
327P12V_AUX         PC6023-1          A01X+045443Y+028332X0198Y0197R180 S1      
317P12V_AUX         VIA   -    MD0100PA00X+045725Y+028264X0200Y    R270 S0      
317P12V_AUX         VIA   -    MD0100PA00X+045725Y+028014X0200Y    R270 S0      
317P12V_AUX         VIA   -    MD0100PA00X+045452Y+028079X0200Y    R270 S0      
317P12V_AUX         VIA   -    MD0100PA00X+054463Y+028913X0200Y    R270 S0      
317P12V_AUX         VIA   -    MD0100PA00X+054463Y+029163X0200Y    R270 S0      
327P12V_AUX         PL6002-1          A01X+054321Y+029727X0280Y0320     S1      
317P12V_AUX         VIA   -    MD0100PA00X+054181Y+028974X0200Y    R270 S0      
327P12V_AUX         PC6020-1          A01X+054172Y+029227X0198Y0197R180 S1      
317P12V_AUX         VIA   -    MD0100PA00X+045672Y+028516X0200Y    R270 S0      
317P12V_AUX         VIA   -    MD0100PA00X+054378Y+029417X0200Y    R270 S0      
327P12V_AUX         PL6003-1          A01X+045597Y+028826X0280Y0320     S1      
317P12V_AUX         VIA   -    MD0100PA00X+130158Y+018405X0200Y         S0      
327P12V_AUX         R1799 -1          A01X+129918Y+018405X0198Y0197R180 S1      
317P12V_AUX         VIA   -    MD0100PA00X+181720Y+015995X0200Y    R270 S0      
327P12V_AUX         R4068 -1          A01X+181970Y+015995X0198Y0197R270 S1      
317P12V_AUX         VIA   -    MD0100PA00X+181720Y+016380X0200Y    R270 S0      
327P12V_AUX         R4070 -1          A01X+181970Y+016380X0198Y0197R090 S1      
327P12V_AUX         PC1649-1          A01X+173036Y+017138X0198Y0197R090 S1      
327P12V_AUX         PL8045-1          A01X+171578Y+017008X0420Y0990R090 S1      
317P12V_AUX         VIA   -    MD0100PA00X+171949Y+016648X0200Y    R090 S0      
317P12V_AUX         VIA   -    MD0100PA00X+171689Y+016648X0200Y    R090 S0      
317P12V_AUX         VIA   -    MD0100PA00X+171689Y+016398X0200Y    R090 S0      
317P12V_AUX         VIA   -    MD0100PA00X+171949Y+016398X0200Y    R090 S0      
317P12V_AUX         VIA   -    MD0100PA00X+171689Y+016148X0200Y    R090 S0      
317P12V_AUX         VIA   -    MD0100PA00X+171949Y+016148X0200Y    R090 S0      
317P12V_AUX         VIA   -    MD0100PA00X+172209Y+016648X0200Y    R090 S0      
317P12V_AUX         VIA   -    MD0100PA00X+172209Y+016398X0200Y    R090 S0      
317P12V_AUX         VIA   -    MD0100PA00X+172209Y+016148X0200Y    R090 S0      
317P12V_AUX         VIA   -    MD0100PA00X+171689Y+015888X0200Y    R090 S0      
317P12V_AUX         VIA   -    MD0100PA00X+171949Y+015888X0200Y    R090 S0      
317P12V_AUX         VIA   -    MD0100PA00X+172209Y+015888X0200Y    R090 S0      
317P12V_AUX         VIA   -    MD0100PA00X+172509Y+016648X0200Y    R090 S0      
317P12V_AUX         VIA   -    MD0100PA00X+172509Y+016398X0200Y    R090 S0      
317P12V_AUX         VIA   -    MD0100PA00X+172509Y+016148X0200Y    R090 S0      
317P12V_AUX         VIA   -    MD0100PA00X+172509Y+015888X0200Y    R090 S0      
317P12V_AUX         VIA   -    MD0100PA00X+171429Y+016648X0200Y    R090 S0      
317P12V_AUX         VIA   -    MD0100PA00X+171129Y+016648X0200Y    R090 S0      
317P12V_AUX         VIA   -    MD0100PA00X+171429Y+016398X0200Y    R090 S0      
317P12V_AUX         VIA   -    MD0100PA00X+171129Y+016398X0200Y    R090 S0      
317P12V_AUX         VIA   -    MD0100PA00X+171429Y+016148X0200Y    R090 S0      
317P12V_AUX         VIA   -    MD0100PA00X+171129Y+016148X0200Y    R090 S0      
317P12V_AUX         VIA   -    MD0100PA00X+171429Y+015888X0200Y    R090 S0      
317P12V_AUX         VIA   -    MD0100PA00X+171129Y+015888X0200Y    R090 S0      
317P12V_AUX         VIA   -    MD0100PA00X+172209Y+015628X0200Y    R090 S0      
317P12V_AUX         VIA   -    MD0100PA00X+171949Y+015628X0200Y    R090 S0      
317P12V_AUX         VIA   -    MD0100PA00X+171689Y+015628X0200Y    R090 S0      
317P12V_AUX         VIA   -    MD0100PA00X+172509Y+015628X0200Y    R090 S0      
317P12V_AUX         VIA   -    MD0100PA00X+171129Y+015628X0200Y    R090 S0      
317P12V_AUX         VIA   -    MD0100PA00X+171429Y+015628X0200Y    R090 S0      
327P12V_AUX         PC8008-1   M      A01X+181217Y+019160X0280Y0320R180 S1      
317P12V_AUX         VIA   -    MD0100PA00X+181322Y+019470X0200Y    R270 S0      
327P12V_AUX         PU9   -3          A01X+180650Y+019613X0110Y0240R270 S1      
327P12V_AUX         R3117 -1          A18X+179799Y+017944X0198Y0197R270 S2      
317P12V_AUX         VIA   -    MD0100PA00X+180055Y+017723X0200Y    R270 S0      
327P12V_AUX         R4074 -1          A01X+101483Y+026169X0198Y0197R090 S1      
317P12V_AUX         VIA   -    MD0100PA00X+101483Y+025897X0200Y    R090 S0      
327P12V_AUX         R4072 -1          A01X+101483Y+027085X0198Y0197R090 S1      
317P12V_AUX         VIA   -    MD0100PA00X+101483Y+026843X0200Y    R090 S0      
317P12V_AUX         VIA   -    MD0100PA00X+098038Y+021574X0200Y    R270 S0      
317P12V_AUX         VIA   -    MD0100PA00X+098041Y+021828X0200Y    R270 S0      
327P12V_AUX         PR3957-1          A01X+098333Y+021723X0280Y0320R180 S1      
327P12V_AUX         PR3953-1          A01X+099434Y+022123X0198Y0197     S1      
327P12V_AUX         PU292 -24         A01X+099946Y+020151X0100Y0500R090 S1      
327P12V_AUX         PU292 -25         A01X+099946Y+020505X0100Y0500R090 S1      
327P12V_AUX         PU292 -26         A01X+099946Y+020859X0100Y0500R090 S1      
327P12V_AUX         PC2198-1          A01X+102322Y+018602X0198Y0197R090 S1      
327P12V_AUX         PU292 -23         A01X+099946Y+019796X0100Y0500R090 S1      
327P12V_AUX         PU292 -21_2       A01X+099749Y+019309X0364Y0492R090 S1      
327P12V_AUX         PR3966-1          A01X+101295Y+017128X0198Y0197R180 S1      
327P12V_AUX         PC2207-1          A01X+101295Y+017528X0198Y0197R180 S1      
327P12V_AUX         PD114 -C          A01X+102192Y+016222X0520Y0560R090 S1      
327P12V_AUX         PU294 -A3         A01X+099836Y+016754X0090Y    R270 S1      
327P12V_AUX         PU294 -A5         A01X+099836Y+016360X0090Y    R270 S1      
327P12V_AUX         PU294 -B3         A01X+099639Y+016754X0090Y    R270 S1      
327P12V_AUX         PU294 -B5         A01X+099639Y+016360X0090Y    R270 S1      
327P12V_AUX         PU294 -C3         A01X+099442Y+016754X0090Y    R270 S1      
327P12V_AUX         PU294 -C5         A01X+099442Y+016360X0090Y    R270 S1      
327P12V_AUX         PU294 -D5         A01X+099245Y+016360X0090Y    R270 S1      
317P12V_AUX         VIA   -    MD0100PA00X+100071Y+020328X0180Y         S0      
317P12V_AUX         VIA   -    MD0100PA00X+099821Y+020328X0180Y         S0      
317P12V_AUX         VIA   -    MD0100PA00X+100071Y+020682X0180Y         S0      
317P12V_AUX         VIA   -    MD0100PA00X+099821Y+020682X0180Y         S0      
317P12V_AUX         VIA   -    MD0100PA00X+101770Y+018906X0200Y         S0      
317P12V_AUX         VIA   -    MD0100PA00X+101490Y+018930X0200Y         S0      
317P12V_AUX         VIA   -    MD0100PA00X+101199Y+018902X0200Y         S0      
317P12V_AUX         VIA   -    MD0100PA00X+100616Y+018902X0200Y         S0      
317P12V_AUX         VIA   -    MD0100PA00X+100272Y+018930X0200Y         S0      
317P12V_AUX         VIA   -    MD0100PA00X+099922Y+018930X0200Y         S0      
317P12V_AUX         VIA   -    MD0100PA00X+100071Y+019619X0180Y         S0      
317P12V_AUX         VIA   -    MD0100PA00X+100071Y+019974X0180Y         S0      
317P12V_AUX         VIA   -    MD0100PA00X+099821Y+019619X0180Y         S0      
317P12V_AUX         VIA   -    MD0100PA00X+099821Y+019974X0180Y         S0      
317P12V_AUX         VIA   -    MD0100PA00X+102280Y+017980X0200Y         S0      
317P12V_AUX         VIA   -    MD0100PA00X+101990Y+017980X0200Y         S0      
317P12V_AUX         VIA   -    MD0100PA00X+101720Y+017970X0200Y         S0      
317P12V_AUX         VIA   -    MD0100PA00X+101430Y+017970X0200Y         S0      
317P12V_AUX         VIA   -    MD0100PA00X+101322Y+016480X0200Y         S0      
317P12V_AUX         VIA   -    MD0100PA00X+100972Y+016480X0200Y         S0      
317P12V_AUX         VIA   -    MD0100PA00X+100272Y+016480X0200Y         S0      
317P12V_AUX         VIA   -    MD0100PA00X+100622Y+016480X0200Y         S0      
327P12V_AUX         PD115 -C          A01X+074652Y+012642X0520Y0560R180 S1      
327P12V_AUX         PC2231-1          A01X+072393Y+013541X0198Y0197R090 S1      
317P12V_AUX         VIA   -    MD0100PA00X+072873Y+012639X0200Y    R180 S0      
317P12V_AUX         VIA   -    MD0100PA00X+072873Y+012929X0200Y    R180 S0      
317P12V_AUX         VIA   -    MD0100PA00X+072873Y+013209X0200Y    R180 S0      
317P12V_AUX         VIA   -    MD0100PA00X+072313Y+012449X0200Y    R180 S0      
317P12V_AUX         VIA   -    MD0100PA00X+071993Y+012449X0200Y    R180 S0      
317P12V_AUX         VIA   -    MD0100PA00X+071743Y+013509X0200Y    R180 S0      
317P12V_AUX         VIA   -    MD0100PA00X+072043Y+013509X0200Y    R180 S0      
327P12V_AUX         PR4003-1          A01X+074127Y+011873X0198Y0197R270 S1      
317P12V_AUX         VIA   -    MD0100PA00X+074826Y+011255X0200Y         S0      
317P12V_AUX         VIA   -    MD0100PA00X+074803Y+011629X0200Y         S0      
327P12V_AUX         PC2230-1          A01X+073734Y+011881X0198Y0197R270 S1      
317P12V_AUX         VIA   -    MD0100PA00X+071273Y+011459X0200Y    R180 S0      
317P12V_AUX         VIA   -    MD0100PA00X+071273Y+011749X0200Y    R180 S0      
317P12V_AUX         VIA   -    MD0100PA00X+071593Y+011459X0200Y    R180 S0      
317P12V_AUX         VIA   -    MD0100PA00X+071593Y+011749X0200Y    R180 S0      
327P12V_AUX         PU299 -23         A01X+070391Y+011393X0100Y0500R180 S1      
327P12V_AUX         PU299 -24         A01X+070037Y+011393X0100Y0500R180 S1      
327P12V_AUX         PU299 -25         A01X+069683Y+011393X0100Y0500R180 S1      
327P12V_AUX         PU299 -21_2       A01X+070879Y+011196X0364Y0492R180 S1      
317P12V_AUX         VIA   -    MD0100PA00X+069506Y+011518X0180Y         S0      
317P12V_AUX         VIA   -    MD0100PA00X+069506Y+011268X0180Y         S0      
317P12V_AUX         VIA   -    MD0100PA00X+070214Y+011268X0180Y         S0      
317P12V_AUX         VIA   -    MD0100PA00X+070569Y+011268X0180Y         S0      
317P12V_AUX         VIA   -    MD0100PA00X+069860Y+011268X0180Y         S0      
317P12V_AUX         VIA   -    MD0100PA00X+070214Y+011518X0180Y         S0      
317P12V_AUX         VIA   -    MD0100PA00X+070569Y+011518X0180Y         S0      
317P12V_AUX         VIA   -    MD0100PA00X+069860Y+011518X0180Y         S0      
327P12V_AUX         PU299 -26         A01X+069328Y+011393X0100Y0500R180 S1      
327P12V_AUX         PU300 -A3         A01X+074504Y+010391X0090Y         S1      
327P12V_AUX         PU300 -A5         A01X+074897Y+010391X0090Y         S1      
327P12V_AUX         PU300 -B3         A01X+074504Y+010194X0090Y         S1      
327P12V_AUX         PU300 -B5         A01X+074897Y+010194X0090Y         S1      
327P12V_AUX         PU300 -C3         A01X+074504Y+009997X0090Y         S1      
327P12V_AUX         PU300 -C5         A01X+074897Y+009997X0090Y         S1      
327P12V_AUX         PU300 -D5         A01X+074897Y+009800X0090Y         S1      
327P12V_AUX         R4071 -1          A01X+074812Y+016754X0198Y0197     S1      
317P12V_AUX         VIA   -    MD0100PA00X+074812Y+017062X0200Y         S0      
327P12V_AUX         PR4010-1          A01X+068062Y+010881X0198Y0197R090 S1      
327P12V_AUX         PR4014-1          A01X+068464Y+009686X0280Y0320R270 S1      
317P12V_AUX         VIA   -    MD0100PA00X+068105Y+010467X0200Y         S0      
317P12V_AUX         VIA   -    MD0100PA00X+177820Y+009098X0200Y         S0      
327P12V_AUX         PU203 -D5         A01X+177952Y+007964X0090Y         S1      
327P12V_AUX         PU203 -C5         A01X+177952Y+008161X0090Y         S1      
327P12V_AUX         PU203 -C3         A01X+177558Y+008161X0090Y         S1      
327P12V_AUX         PU203 -B5         A01X+177952Y+008358X0090Y         S1      
327P12V_AUX         PU203 -B3         A01X+177558Y+008358X0090Y         S1      
327P12V_AUX         PU203 -A5         A01X+177952Y+008555X0090Y         S1      
327P12V_AUX         PU203 -A3         A01X+177558Y+008555X0090Y         S1      
317P12V_AUX         VIA   -    MD0100PA00X+176364Y+010617X0200Y    R180 S0      
317P12V_AUX         VIA   -    MD0100PA00X+176044Y+010617X0200Y    R180 S0      
317P12V_AUX         VIA   -    MD0100PA00X+177854Y+009797X0200Y         S0      
327P12V_AUX         PC2079-1          A01X+176789Y+010040X0198Y0197R270 S1      
327P12V_AUX         PR3792-1          A01X+177189Y+010040X0198Y0197R270 S1      
317P12V_AUX         VIA   -    MD0100PA00X+173699Y+011222X0180Y         S0      
317P12V_AUX         VIA   -    MD0100PA00X+173699Y+010972X0180Y         S0      
327P12V_AUX         PU204 -26         A01X+173525Y+011093X0100Y0500R180 S1      
317P12V_AUX         VIA   -    MD0100PA00X+174762Y+010972X0180Y         S0      
317P12V_AUX         VIA   -    MD0100PA00X+174762Y+011222X0180Y         S0      
317P12V_AUX         VIA   -    MD0100PA00X+174407Y+010972X0180Y         S0      
317P12V_AUX         VIA   -    MD0100PA00X+174407Y+011222X0180Y         S0      
317P12V_AUX         VIA   -    MD0100PA00X+174053Y+010972X0180Y         S0      
317P12V_AUX         VIA   -    MD0100PA00X+174053Y+011222X0180Y         S0      
327P12V_AUX         PU204 -21_2       A01X+175075Y+010896X0364Y0492R180 S1      
327P12V_AUX         PU204 -25         A01X+173879Y+011093X0100Y0500R180 S1      
327P12V_AUX         PU204 -24         A01X+174234Y+011093X0100Y0500R180 S1      
327P12V_AUX         PU204 -23         A01X+174588Y+011093X0100Y0500R180 S1      
317P12V_AUX         VIA   -    MD0100PA00X+175794Y+011677X0200Y    R180 S0      
317P12V_AUX         VIA   -    MD0100PA00X+176094Y+011677X0200Y    R180 S0      
317P12V_AUX         VIA   -    MD0100PA00X+175594Y+010847X0200Y    R180 S0      
317P12V_AUX         VIA   -    MD0100PA00X+175594Y+011107X0200Y    R180 S0      
327P12V_AUX         PC2154-1          A01X+176448Y+011705X0198Y0197R090 S1      
317P12V_AUX         VIA   -    MD0100PA00X+176924Y+010807X0200Y    R180 S0      
317P12V_AUX         VIA   -    MD0100PA00X+176924Y+011097X0200Y    R180 S0      
317P12V_AUX         VIA   -    MD0100PA00X+176924Y+011377X0200Y    R180 S0      
327P12V_AUX         PD101 -C          A01X+177688Y+011397X0520Y0560R270 S1      
317P12V_AUX         VIA   -    MD0100PA00X+178414Y+010827X0200Y    R180 S0      
317P12V_AUX         VIA   -    MD0100PA00X+178414Y+011117X0200Y    R180 S0      
317P12V_AUX         VIA   -    MD0100PA00X+178414Y+011397X0200Y    R180 S0      
317P12V_AUX         VIA   -    MD0100PA00X+072992Y+009100X0200Y         S0      
327P12V_AUX         PR4000-1          A01X+072992Y+009100X0198Y0197     S1      
317P12V_AUX         VIA   -    MD0100PA00X+175792Y+007264X0200Y         S0      
327P12V_AUX         PR3786-1          A01X+176046Y+007264X0198Y0197     S1      
317P12V_AUX         VIA   -    MD0100PA00X+023999Y+014199X0200Y         S0      
327P12V_AUX         R4065 -1          A01X+023728Y+014206X0198Y0197R180 S1      
317P12V_AUX         VIA   -    MD0100PA00X+025725Y+015673X0200Y    R270 S0      
327P12V_AUX         R4067 -1          A01X+025476Y+015673X0198Y0197R090 S1      
317P12V_AUX         VIA   -    MD0100PA00X+031105Y+010711X0200Y    R180 S0      
317P12V_AUX         VIA   -    MD0100PA00X+031105Y+011001X0200Y    R180 S0      
317P12V_AUX         VIA   -    MD0100PA00X+031105Y+011281X0200Y    R180 S0      
317P12V_AUX         VIA   -    MD0100PA00X+030118Y+010711X0200Y    R180 S0      
317P12V_AUX         VIA   -    MD0100PA00X+030118Y+011001X0200Y    R180 S0      
317P12V_AUX         VIA   -    MD0100PA00X+030118Y+011281X0200Y    R180 S0      
327P12V_AUX         PD107 -C          A01X+030675Y+011284X0520Y0560R270 S1      
317P12V_AUX         VIA   -    MD0100PA00X+028085Y+010731X0200Y    R180 S0      
317P12V_AUX         VIA   -    MD0100PA00X+028585Y+011561X0200Y    R180 S0      
317P12V_AUX         VIA   -    MD0100PA00X+028285Y+011561X0200Y    R180 S0      
317P12V_AUX         VIA   -    MD0100PA00X+028085Y+010991X0200Y    R180 S0      
327P12V_AUX         PC2165-1          A01X+028936Y+011593X0198Y0197R090 S1      
317P12V_AUX         VIA   -    MD0100PA00X+027252Y+011106X0180Y         S0      
317P12V_AUX         VIA   -    MD0100PA00X+026544Y+011106X0180Y         S0      
317P12V_AUX         VIA   -    MD0100PA00X+026190Y+011106X0180Y         S0      
317P12V_AUX         VIA   -    MD0100PA00X+026190Y+010856X0180Y         S0      
317P12V_AUX         VIA   -    MD0100PA00X+026544Y+010856X0180Y         S0      
317P12V_AUX         VIA   -    MD0100PA00X+026898Y+011106X0180Y         S0      
317P12V_AUX         VIA   -    MD0100PA00X+026898Y+010856X0180Y         S0      
317P12V_AUX         VIA   -    MD0100PA00X+027252Y+010856X0180Y         S0      
327P12V_AUX         PU206 -23         A01X+027076Y+010980X0100Y0500R180 S1      
327P12V_AUX         PU206 -24         A01X+026721Y+010980X0100Y0500R180 S1      
327P12V_AUX         PU206 -25         A01X+026367Y+010980X0100Y0500R180 S1      
327P12V_AUX         PU206 -21_2       A01X+027563Y+010784X0364Y0492R180 S1      
327P12V_AUX         PU206 -26         A01X+026013Y+010980X0100Y0500R180 S1      
327P12V_AUX         PR3830-1          A01X+030532Y+009887X0198Y0197R270 S1      
327P12V_AUX         PC2139-1          A01X+030132Y+009887X0198Y0197R270 S1      
317P12V_AUX         VIA   -    MD0100PA00X+028535Y+010501X0200Y    R180 S0      
317P12V_AUX         VIA   -    MD0100PA00X+028855Y+010501X0200Y    R180 S0      
317P12V_AUX         VIA   -    MD0100PA00X+031241Y+008906X0200Y         S0      
327P12V_AUX         PU201 -A3         A01X+031046Y+008443X0090Y         S1      
327P12V_AUX         PU201 -A5         A01X+031440Y+008443X0090Y         S1      
327P12V_AUX         PU201 -B3         A01X+031046Y+008246X0090Y         S1      
327P12V_AUX         PU201 -B5         A01X+031440Y+008246X0090Y         S1      
327P12V_AUX         PU201 -C3         A01X+031046Y+008049X0090Y         S1      
327P12V_AUX         PU201 -C5         A01X+031440Y+008049X0090Y         S1      
327P12V_AUX         PU201 -D5         A01X+031440Y+007852X0090Y         S1      
327P12V_AUX         U8008 -5          A01X+052982Y+044574X0240Y0420R270 S1      
327P12V_AUX         U8010 -5          A01X+055518Y+045876X0240Y0420R090 S1      
317P12V_AUX         VIA   -    MD0100PA00X+054317Y+043474X0200Y         S0      
327P12V_AUX         U8006 -5          A18X+074124Y+168332X0240Y0420     S2      
327P12V_AUX         R2219 -1          A01X+063298Y+046886X0198Y0197R180 S1      
317P12V_AUX         VIA   -    MD0100PA00X+063298Y+047146X0200Y         S0      
327P12V_AUX         R2221 -1          A01X+059043Y+046889X0198Y0197     S1      
317P12V_AUX         VIA   -    MD0100PA00X+058750Y+047031X0200Y         S0      
327P12V_AUX         R9021 -1          A01X+058650Y+046758X0198Y0197R270 S1      
317m4714            VIA   -    MD0100PA00X+074611Y+047497X0180Y    R090 S2      
317m4714            VIA   -    MD0100PA00X+076050Y+052119X0200Y    R180 S0      
327m4714            R372  -1          A01X+076050Y+052429X0198Y0197R090 S1      
327m4714            U18   -T18        A01X+074458Y+047344X0160Y    R090 S1      
327m4715            Q12   -D          A01X+137374Y+007487X0400Y0480R180 S1      
327m4715            VIA   -    M      A01X+137894Y+006814X0300Y    R270 S1      
327m4715            D46   -C          A01X+137375Y+006456X0240Y0280R090 S1      
317P12V_ALL_PWROK   VIA   -    MD0100PA00X+101340Y+028081X0200Y         S0      
327P12V_ALL_PWROK   Q12   -G          A01X+137768Y+008369X0400Y0480R180 S1      
317P12V_ALL_PWROK   VIA   -    M      A01X+137768Y+008759X0200Y    R180 S2      
017P12V_ALL_PWROK   VIA   -    M      A18X+137768Y+008759X0260Y    R180 S2      
017P12V_ALL_PWROK         -    MD0100PA00X+137768Y+008759                       
317P12V_ALL_PWROK   VIA   -    MD0100PA00X+098336Y+044903X0200Y         S0      
327P12V_ALL_PWROK   R372  -2          A01X+076050Y+052744X0198Y0197R090 S1      
317P12V_ALL_PWROK   VIA   -    MD0100PA00X+076050Y+052984X0200Y         S0      
317P12V_ALL_PWROK   VIA   -    MD0100PA00X+098744Y+050474X0200Y         S0      
327OC_ALERT_N       VIA   -    M      A01X+065088Y+044986X0300Y    R090 S1      
327OC_ALERT_N       R6039 -1          A01X+064608Y+044986X0198Y0197R180 S1      
327OC_ALERT_N       U18   -A10        A01X+069733Y+044824X0160Y    R090 S1      
327m4716            VIA   -    M      A01X+036584Y+016326X0300Y         S1      
327m4716            R3185 -2          A01X+037089Y+016317X0198Y0197R180 S1      
327m4716            U219  -2          A01X+037100Y+013890X0220Y0320R270 S1      
327m4717            R3185 -1          A01X+037404Y+016317X0198Y0197R180 S1      
327m4717            R3184 -2   M      A01X+037404Y+015803X0198Y0197     S1      
327m4717            U217  -4          A01X+038416Y+015794X0170Y0240R090 S1      
327m4717            VIA   -    M      A01X+037909Y+015794X0300Y    R180 S1      
327m4718            R3244 -1          A18X+079782Y+030806X0198Y0197R180 S2      
317m4718            VIA   -    MD0100PA00X+079592Y+031266X0200Y         S0      
327m4718            U246  -3          A01X+056591Y+038467X0140Y0440R270 S1      
317m4718            VIA   -    M      A01X+056221Y+038367X0200Y    R090 S2      
017m4718            VIA   -    M      A18X+056221Y+038367X0260Y    R090 S2      
017m4718                  -    MD0100PA00X+056221Y+038367                       
317m4718            VIA   -    MD0100PA00X+077988Y+028170X0200Y         S0      
327m4718            U223  -12         A18X+076990Y+028170X0140Y0590R090 S2      
327m4719            R3209 -1          A18X+080097Y+030406X0198Y0197     S2      
327m4719            VIA   -    M      A18X+080539Y+030767X0260Y         S2      
327m4719            U222  -12         A18X+081250Y+030675X0140Y0590R090 S2      
327m4719            R3244 -2   M      A18X+080097Y+030806X0198Y0197R180 S2      
317m4720            VIA   -    MD0100PA00X+079849Y+030138X0200Y         S0      
317m4720            VIA   -    M      A01X+056203Y+037287X0200Y         S2      
017m4720            VIA   -    M      A18X+056203Y+037287X0260Y         S2      
017m4720                  -    MD0100PA00X+056203Y+037287                       
327m4720            R3209 -2          A18X+079782Y+030406X0198Y0197     S2      
327m4720            U245  -3          A01X+056591Y+037387X0140Y0440R270 S1      
327m4721            J35   -A70        A01X+006593Y+003276X0150Y0570R180 S1      
317m4721            VIA   -    MD0100PA00X+006593Y+002841X0200Y         S0      
327m4721            R3191 -2          A01X+101713Y+042090X0198Y0197     S1      
317m4721            VIA   -    M      A01X+102075Y+042090X0200Y         S2      
017m4721            VIA   -    M      A18X+102075Y+042090X0260Y         S2      
017m4721                  -    MD0100PA00X+102075Y+042090                       
317m4721            VIA   -    MD0100PA00X+049042Y+036214X0200Y         S0      
327m4722            VIA   -    M      A01X+100811Y+042089X0300Y         S1      
327m4722            R3190 -2          A01X+101398Y+042590X0198Y0197R180 S1      
327m4722            U218  -4          A01X+100213Y+042089X0220Y0320R270 S1      
327m4722            R3191 -1   M      A01X+101398Y+042090X0198Y0197     S1      
327m4723            U242  -3          A01X+004469Y+029289X0160Y0340R270 S1      
317m4723            VIA   -    MD0100PA00X+004149Y+029289X0200Y    R270 S0      
317m4723            VIA   -    M      A01X+058558Y+037205X0200Y         S2      
017m4723            VIA   -    M      A18X+058558Y+037205X0260Y         S2      
017m4723                  -    MD0100PA00X+058558Y+037205                       
327m4723            R3306 -1   M      A01X+058558Y+037448X0198Y0197R090 S1      
327m4723            R3308 -1          A01X+058558Y+038723X0198Y0197R090 S1      
327m4724            R3306 -2          A01X+058558Y+037763X0198Y0197R090 S1      
327m4724            VIA   -    M      A01X+058558Y+038243X0300Y    R270 S1      
327m4724            U245  -6          A01X+057378Y+037899X0140Y0440R270 S1      
327m4725            VIA   -    M      A01X+058558Y+039518X0300Y    R090 S1      
327m4725            R3308 -2          A01X+058558Y+039038X0198Y0197R090 S1      
327m4725            U246  -6          A01X+057378Y+038979X0140Y0440R270 S1      
317m4726            VIA   -    M      A01X+004245Y+027780X0200Y    R090 S2      
017m4726            VIA   -    M      A18X+004245Y+027780X0260Y    R090 S2      
017m4726                  -    MD0100PA00X+004245Y+027780                       
327m4726            U59   -3          A01X+004730Y+027780X0170Y0240R270 S1      
327m4726            R3136 -2   M      A01X+003994Y+027780X0198Y0197     S1      
327m4726            U241  -6          A01X+002807Y+029289X0160Y0340R270 S1      
327m4726            J35   -B70        A01X+006593Y+004437X0150Y0570R180 S1      
317m4726            VIA   -    MD0100PA00X+006593Y+004872X0200Y         S0      
317m4727            VIA   -    MD0100PA00X+023334Y+001766X0200Y         S0      
327m4727            J35   -A12        A01X+023334Y+003276X0150Y0570R180 S1      
317m4727            VIA   -    M      A01X+004245Y+028292X0200Y    R090 S2      
017m4727            VIA   -    M      A18X+004245Y+028292X0260Y    R090 S2      
017m4727                  -    MD0100PA00X+004245Y+028292                       
327m4727            U241  -5          A01X+002807Y+029014X0200Y0340R270 S1      
327m4727            U59   -1          A01X+004730Y+028292X0170Y0240R270 S1      
327m4727            R3134 -2   M      A01X+003994Y+028292X0198Y0197     S1      
327m4728            R8016 -1          A01X+004392Y+030350X0198Y0197     S1      
327m4728            VIA   -    M      A01X+003894Y+030300X0300Y         S1      
327m4728            U241  -3          A01X+001409Y+029289X0160Y0340R270 S1      
327m4729            U58   -3          A01X+004726Y+030854X0170Y0240R270 S1      
317m4729            VIA   -    M      A01X+004245Y+030780X0200Y    R090 S2      
017m4729            VIA   -    M      A18X+004245Y+030780X0260Y    R090 S2      
017m4729                  -    MD0100PA00X+004245Y+030780                       
327m4729            R3135 -2   M      A01X+003994Y+030780X0198Y0197     S1      
327m4729            U241  -2          A01X+001409Y+029545X0160Y0340R270 S1      
317m4729            VIA   -    MD0100PA00X+014792Y+002826X0200Y         S0      
327m4729            J35   -A42        A01X+014904Y+003276X0150Y0570R180 S1      
327m4730            U58   -1          A01X+004726Y+031366X0170Y0240R270 S1      
317m4730            VIA   -    M      A01X+004245Y+031292X0200Y    R090 S2      
017m4730            VIA   -    M      A18X+004245Y+031292X0260Y    R090 S2      
017m4730                  -    MD0100PA00X+004245Y+031292                       
327m4730            R3133 -2   M      A01X+003994Y+031292X0198Y0197     S1      
327m4730            U241  -1          A01X+001409Y+029821X0200Y0340R270 S1      
317m4730            VIA   -    MD0100PA00X+014878Y+004872X0200Y         S0      
327m4730            J35   -B42        A01X+014904Y+004437X0150Y0570R180 S1      
327m4731            R8015 -1          A01X+003492Y+028850X0198Y0197     S1      
327m4731            VIA   -    M      A01X+003418Y+029341X0300Y         S1      
327m4731            U241  -7          A01X+002807Y+029545X0160Y0340R270 S1      
327m4732            R1525 -1   M      A01X+024746Y+022437X0198Y0197     S1      
327m4732            U9051 -1          A01X+024071Y+021513X0220Y0320R270 S1      
327m4732            R1169 -1   M      A01X+031460Y+027102X0198Y0197R090 S1      
317m4732            VIA   -    MD0100PA00X+031908Y+026008X0200Y         S0      
327m4732            R8097 -2   M      A01X+031908Y+026300X0198Y0197     S1      
317m4732            VIA   -    M      A01X+034190Y+023398X0300Y         S1      
017m4732            VIA   -    M      A18X+034190Y+023398X0200Y         S1      
017m4732                  -    MD0100PA00X+034190Y+023398                       
327m4732            R3832 -2          A01X+034670Y+023398X0198Y0197R270 S1      
327m4732            R3826 -2          A01X+034310Y+022918X0198Y0197R180 S1      
327m4733            U245  -1          A01X+056591Y+037899X0140Y0440R270 S1      
327m4733            VIA   -    M      A01X+055625Y+038979X0300Y    R270 S1      
327m4733            U246  -1          A01X+056591Y+038979X0140Y0440R270 S1      
327m4734            R3168 -2          A18X+030372Y+004279X0198Y0197R090 S2      
327m4734            J35   -OB2        A01X+030497Y+004437X0150Y0570R180 S1      
317m4734            VIA   -    M      A01X+030325Y+003820X0200Y         S2      
017m4734            VIA   -    M      A18X+030325Y+003820X0260Y         S2      
017m4734                  -    MD0100PA00X+030325Y+003820                       
327m4735            VIA   -           A18X+069255Y+044673X0260Y    R090 S2      
327m4735            U18   -D9         A01X+070678Y+044509X0160Y    R090 S1      
317m4735            VIA   -    MD0100PA00X+070524Y+044356X0180Y    R090 S0      
317m4735            VIA   -    MD0100PA00X+065895Y+013984X0200Y         S0      
327m4735            R3165 -2   M      A18X+030772Y+004594X0198Y0197R270 S2      
327m4735            R3168 -1          A18X+030372Y+004594X0198Y0197R090 S2      
317m4735            VIA   -    MD0100PA00X+030657Y+005022X0200Y         S0      
327m4736            R3217 -1          A01X+024214Y+007186X0198Y0197     S1      
317m4736            VIA   -    M      A01X+023885Y+007298X0200Y         S2      
017m4736            VIA   -    M      A18X+023885Y+007298X0260Y         S2      
017m4736                  -    MD0100PA00X+023885Y+007298                       
327m4736            R3171 -1          A01X+024027Y+006544X0198Y0197R270 S1      
327m4737            R3216 -1          A18X+024179Y+006292X0198Y0197R090 S2      
327m4737            R3170 -1          A01X+024427Y+006544X0198Y0197R270 S1      
317m4737            VIA   -    M      A01X+024292Y+006792X0200Y         S2      
017m4737            VIA   -    M      A18X+024292Y+006792X0260Y         S2      
017m4737                  -    MD0100PA00X+024292Y+006792                       
327m4738            R3208 -1          A18X+024680Y+006292X0198Y0197R090 S2      
327m4738            R3169 -1          A01X+024827Y+006544X0198Y0197R270 S1      
317m4738            VIA   -    M      A01X+024849Y+006869X0200Y         S2      
017m4738            VIA   -    M      A18X+024849Y+006869X0260Y         S2      
017m4738                  -    MD0100PA00X+024849Y+006869                       
317m4739            VIA   -    M      A01X+029950Y+002286X0200Y         S2      
017m4739            VIA   -    M      A18X+029950Y+002286X0260Y         S2      
017m4739                  -    MD0100PA00X+029950Y+002286                       
327m4739            J35   -OA5        A01X+029788Y+003276X0150Y0570R180 S1      
317m4739            VIA   -    MD0100PA00X+077742Y+027796X0200Y         S0      
327m4739            U223  -11         A18X+076990Y+027915X0140Y0590R090 S2      
317m4739            VIA   -    MD0100PA00X+074892Y+015861X0200Y         S0      
327m4740            U222  -11         A18X+081250Y+030419X0140Y0590R090 S2      
317m4740            VIA   -    MD0100PA00X+080587Y+030481X0200Y         S0      
317m4740            VIA   -    MD0100PA00X+075630Y+015842X0200Y         S0      
317m4740            VIA   -    M      A01X+030024Y+002836X0200Y         S2      
017m4740            VIA   -    M      A18X+030024Y+002836X0260Y         S2      
017m4740                  -    MD0100PA00X+030024Y+002836                       
327m4740            J35   -OA4        A01X+030024Y+003276X0150Y0570R180 S1      
327OCP_V3_2_ID1     J35   -OA6        A01X+029552Y+003276X0150Y0570R180 S1      
317OCP_V3_2_ID1     VIA   -    M      A01X+029552Y+002636X0200Y         S2      
017OCP_V3_2_ID1     VIA   -    M      A18X+029552Y+002636X0260Y         S2      
017OCP_V3_2_ID1           -    MD0100PA00X+029552Y+002636                       
327OCP_V3_2_ID1     R3167 -1          A18X+029352Y+001831X0198Y0197R090 S2      
327OCP_V3_2_ID1     R3166 -2   M      A18X+029752Y+001831X0198Y0197R270 S2      
327OCP_V3_2_ID0     R3162 -2          A18X+028272Y+004594X0198Y0197R270 S2      
327OCP_V3_2_ID0     R3163 -1   M      A18X+028672Y+004594X0198Y0197R090 S2      
327OCP_V3_2_ID0     J35   -OB7        A01X+029316Y+004437X0150Y0570R180 S1      
317OCP_V3_2_ID0     VIA   -    M      A01X+029316Y+005052X0200Y         S2      
017OCP_V3_2_ID0     VIA   -    M      A18X+029316Y+005052X0260Y         S2      
017OCP_V3_2_ID0           -    MD0100PA00X+029316Y+005052                       
327m4741            R3171 -2          A01X+024027Y+006229X0198Y0197R270 S1      
327m4741            VIA   -    M      A01X+023973Y+005744X0300Y         S1      
327m4741            J35   -B9         A01X+024042Y+004437X0150Y0570R180 S1      
327m4742            J35   -B8         A01X+024278Y+004437X0150Y0570R180 S1      
327m4742            VIA   -    M      A01X+024533Y+005694X0300Y         S1      
327m4742            R3170 -2          A01X+024427Y+006229X0198Y0197R270 S1      
327m4743            J35   -B7         A01X+024515Y+004437X0150Y0570R180 S1      
327m4743            VIA   -    M      A01X+024991Y+005897X0300Y         S1      
327m4743            R3169 -2          A01X+024827Y+006229X0198Y0197R270 S1      
327m4744            R3234 -2          A01X+020818Y+010122X0198Y0197R090 S1      
327m4744            VIA   -    M      A01X+020818Y+010602X0300Y         S1      
327m4744            U225  -1          A01X+020306Y+011302X0170Y0240     S1      
327m4745            R3203 -2          A01X+019598Y+010122X0198Y0197R090 S1      
327m4745            VIA   -    M      A01X+019598Y+010602X0300Y         S1      
327m4745            U286  -1          A01X+019086Y+011302X0170Y0240     S1      
327m4746            J35   -B12        A01X+023334Y+004437X0150Y0570R180 S1      
327m4746            VIA   -    M      A01X+023334Y+005734X0300Y         S1      
327m4746            R3172 -2          A01X+023627Y+006229X0198Y0197R270 S1      
327m4747            R3172 -1          A01X+023627Y+006544X0198Y0197R270 S1      
327m4747            R3164 -2   M      A01X+024214Y+007586X0198Y0197R180 S1      
327m4747            R1175 -2          A01X+028008Y+021100X0198Y0197     S1      
327m4747            R1172 -2   M      A01X+028008Y+020700X0198Y0197     S1      
317m4747            VIA   -    MD0100PA00X+028800Y+020900X0200Y         S0      
317m4747            VIA   -    M      A01X+023519Y+009807X0200Y         S2      
017m4747            VIA   -    M      A18X+023519Y+009807X0260Y         S2      
017m4747                  -    MD0100PA00X+023519Y+009807                       
327m4747            R3203 -1          A01X+019598Y+009807X0198Y0197R090 S1      
327m4747            R3234 -1   M      A01X+020818Y+009807X0198Y0197R090 S1      
327m4748            R3180 -1          A18X+023806Y+003118X0198Y0197R270 S2      
327m4748            J35   -A10        A01X+023806Y+003276X0150Y0570R180 S1      
317m4748            VIA   -    M      A01X+023806Y+002624X0200Y         S2      
017m4748            VIA   -    M      A18X+023806Y+002624X0260Y         S2      
017m4748                  -    MD0100PA00X+023806Y+002624                       
327m4749            R1142 -1          A01X+066780Y+036326X0198Y0197R180 S1      
317m4749            VIA   -    MD0100PA00X+068083Y+036350X0200Y         S0      
317m4749            VIA   -    MD0100PA00X+086037Y+037520X0200Y         S0      
327m4749            R8094 -2          A01X+162500Y+038592X0198Y0197R270 S1      
317m4749            VIA   -    MD0100PA00X+162500Y+038340X0200Y         S0      
317m4749            VIA   -    M      A01X+169243Y+040398X0200Y    R270 S2      
017m4749            VIA   -    M      A18X+169243Y+040398X0260Y    R270 S2      
017m4749                  -    MD0100PA00X+169243Y+040398                       
327m4749            R3783 -2   M      A01X+169243Y+040148X0198Y0197R180 S1      
327m4749            R3794 -2          A01X+168850Y+040148X0198Y0197R270 S1      
327m4749            R1519 -2   M      A01X+086719Y+038784X0198Y0197R090 S1      
327m4749            U9050 -1          A01X+087086Y+040245X0220Y0320R090 S1      
317m4750            VIA   -    M      A01X+064575Y+013499X0200Y         S2      
017m4750            VIA   -    M      A18X+064575Y+013499X0260Y         S2      
017m4750                  -    MD0100PA00X+064575Y+013499                       
327m4750            U157  -2          A01X+063865Y+012805X0220Y0320     S1      
327m4750            R1594 -2          A01X+182516Y+014783X0198Y0197     S1      
317m4750            VIA   -    MD0100PA00X+183117Y+014999X0200Y    R090 S0      
327m4751            U8082 -4          A01X+181028Y+014672X0170Y0240R270 S1      
327m4751            VIA   -    M      A01X+181532Y+014572X0300Y    R090 S1      
327m4751            R2488 -2          A01X+182200Y+015183X0198Y0197R180 S1      
327m4751            R1594 -1   M      A01X+182200Y+014783X0198Y0197     S1      
327USB2_P11_DP      J38   -A69        A01X+154270Y+003276X0150Y0570R180 S1      
327USB2_P11_DP      R46   -1          A01X+153745Y+008815X0198Y0197R090 S1      
327USB2_P11_DN      R42   -1          A01X+153345Y+008815X0198Y0197R090 S1      
327USB2_P11_DN      J38   -A68        A01X+154507Y+003276X0150Y0570R180 S1      
327m4752            U7    -12         A18X+081858Y+027630X0140Y0590R090 S2      
317m4752            VIA   -    MD0100PA00X+082304Y+027630X0200Y         S0      
327m4752            R3237 -1          A18X+075304Y+030267X0198Y0197R270 S2      
317m4752            VIA   -    MD0100PA00X+076046Y+029566X0200Y         S0      
327m4752            U243  -3          A01X+060191Y+038467X0140Y0440R270 S1      
317m4752            VIA   -    M      A01X+059821Y+038367X0200Y    R090 S2      
017m4752            VIA   -    M      A18X+059821Y+038367X0260Y    R090 S2      
017m4752                  -    MD0100PA00X+059821Y+038367                       
327m4753            R3237 -2          A18X+075304Y+030582X0198Y0197R270 S2      
327m4753            R1290 -1   M      A18X+075304Y+030967X0198Y0197R270 S2      
327m4753            VIA   -    M      A18X+075794Y+030903X0260Y         S2      
327m4753            U67   -12         A18X+076498Y+030647X0140Y0590R090 S2      
327m4754            R3307 -2          A01X+057988Y+036683X0198Y0197R180 S1      
327m4754            VIA   -    M      A01X+057988Y+037163X0300Y    R180 S1      
327m4754            U245  -4          A01X+057378Y+037387X0140Y0440R270 S1      
317m4755            VIA   -    MD0100PA00X+058616Y+036683X0200Y         S0      
327m4755            R3307 -1          A01X+058304Y+036683X0198Y0197R180 S1      
327m4755            U243  -4          A01X+060978Y+038467X0140Y0440R270 S1      
317m4755            VIA   -    M      A01X+061348Y+038367X0200Y    R090 S2      
017m4755            VIA   -    M      A18X+061348Y+038367X0260Y    R090 S2      
017m4755                  -    MD0100PA00X+061348Y+038367                       
327m4756            U244  -4          A01X+060978Y+037387X0140Y0440R270 S1      
327m4756            VIA   -    M      A01X+061588Y+037163X0300Y    R180 S1      
327m4756            R3305 -2          A01X+061588Y+036683X0198Y0197R180 S1      
327m4757            U246  -4          A01X+057378Y+038467X0140Y0440R270 S1      
317m4757            VIA   -    M      A01X+057748Y+038367X0200Y    R090 S2      
017m4757            VIA   -    M      A18X+057748Y+038367X0260Y    R090 S2      
017m4757                  -    MD0100PA00X+057748Y+038367                       
327m4757            R3305 -1          A01X+061904Y+036683X0198Y0197R180 S1      
317m4757            VIA   -    MD0100PA00X+061904Y+036954X0200Y         S0      
327m4758            R1290 -2          A18X+075304Y+031282X0198Y0197R270 S2      
327m4758            VIA   -    M      A18X+074894Y+031359X0260Y         S2      
317m4758            VIA   -    MD0100PA00X+064101Y+032446X0200Y         S0      
327m4758            U244  -3          A01X+060191Y+037387X0140Y0440R270 S1      
317m4758            VIA   -    MD0100PA00X+059841Y+037236X0200Y         S0      
327m4759            R1595 -2          A01X+147498Y+006156X0198Y0197     S1      
317m4759            VIA   -    M      A01X+147213Y+005608X0200Y    R090 S2      
017m4759            VIA   -    M      A18X+147213Y+005608X0260Y    R090 S2      
017m4759                  -    MD0100PA00X+147213Y+005608                       
317m4759            VIA   -    MD0100PA00X+153834Y+002841X0200Y         S0      
327m4759            J38   -A70        A01X+154034Y+003276X0150Y0570R180 S1      
327m4760            R1595 -1          A01X+147183Y+006156X0198Y0197     S1      
327m4760            R53   -2   M      A01X+146798Y+006156X0198Y0197     S1      
327m4760            VIA   -    M      A01X+146082Y+005293X0300Y    R180 S1      
327m4760            U104  -4          A01X+145482Y+005293X0220Y0320R270 S1      
327m4761            U242  -7          A01X+005867Y+029545X0160Y0340R270 S1      
317m4761            VIA   -    MD0100PA00X+006257Y+029510X0200Y    R090 S0      
317m4761            VIA   -    M      A01X+062158Y+033136X0200Y         S2      
017m4761            VIA   -    M      A18X+062158Y+033136X0260Y         S2      
017m4761                  -    MD0100PA00X+062158Y+033136                       
327m4761            R3304 -1   M      A01X+062158Y+037448X0198Y0197R090 S1      
327m4761            R3303 -1          A01X+062158Y+038723X0198Y0197R090 S1      
327m4762            U244  -6          A01X+060978Y+037899X0140Y0440R270 S1      
327m4762            VIA   -    M      A01X+062158Y+038243X0300Y    R270 S1      
327m4762            R3304 -2          A01X+062158Y+037763X0198Y0197R090 S1      
327m4763            U243  -6          A01X+060978Y+038979X0140Y0440R270 S1      
327m4763            VIA   -    M      A01X+062158Y+039518X0300Y    R090 S1      
327m4763            R3303 -2          A01X+062158Y+039038X0198Y0197R090 S1      
327m4764            R1895 -1          A18X+171317Y+003117X0198Y0197R270 S2      
327m4764            J38   -A10        A01X+171247Y+003276X0150Y0570R180 S1      
317m4764            VIA   -    M      A01X+171715Y+001991X0200Y         S2      
017m4764            VIA   -    M      A18X+171715Y+001991X0260Y         S2      
017m4764                  -    MD0100PA00X+171715Y+001991                       
317m4765            VIA   -    MD0100PA00X+154034Y+004872X0200Y         S0      
327m4765            J38   -B70        A01X+154034Y+004437X0150Y0570R180 S1      
327m4765            U240  -6          A01X+164680Y+022460X0160Y0340R270 S1      
317m4765            VIA   -    MD0100PA00X+165442Y+022460X0200Y    R090 S0      
327m4765            U8    -3          A01X+179818Y+040550X0170Y0240R270 S1      
327m4765            R1908 -2          A01X+178787Y+040393X0198Y0197     S1      
317m4765            VIA   -    M      A01X+179251Y+040393X0200Y         S2      
017m4765            VIA   -    M      A18X+179251Y+040393X0260Y         S2      
017m4765                  -    MD0100PA00X+179251Y+040393                       
317m4766            VIA   -    MD0100PA00X+170719Y+001571X0200Y         S0      
327m4766            J38   -A12        A01X+170774Y+003276X0150Y0570R180 S1      
327m4766            U8    -1          A01X+179818Y+041062X0170Y0240R270 S1      
317m4766            VIA   -    M      A01X+179245Y+041062X0200Y         S2      
017m4766            VIA   -    M      A18X+179245Y+041062X0260Y         S2      
017m4766                  -    MD0100PA00X+179245Y+041062                       
327m4766            R1906 -2          A01X+178787Y+041043X0198Y0197     S1      
317m4766            VIA   -    MD0100PA00X+165002Y+022184X0200Y    R090 S0      
327m4766            U240  -5          A01X+164680Y+022184X0200Y0340R270 S1      
327m4767            R8014 -1          A18X+003300Y+032108X0198Y0197R090 S2      
327m4767            VIA   -    M      A18X+003672Y+032780X0260Y         S2      
327m4767            U240  -3          A01X+163282Y+022460X0160Y0340R270 S1      
317m4767            VIA   -    MD0100PA00X+163605Y+022460X0200Y    R270 S0      
317m4767            VIA   -    MD0100PA00X+070349Y+034551X0200Y         S0      
327m4768            J38   -A42        A01X+162345Y+003276X0150Y0570R180 S1      
317m4768            VIA   -    MD0100PA00X+162233Y+002826X0200Y         S0      
327m4768            U211  -3          A01X+179817Y+041878X0170Y0240R270 S1      
317m4768            VIA   -    M      A01X+179234Y+041878X0200Y         S2      
017m4768            VIA   -    M      A18X+179234Y+041878X0260Y         S2      
017m4768                  -    MD0100PA00X+179234Y+041878                       
327m4768            R1907 -2          A01X+178787Y+041893X0198Y0197     S1      
317m4768            VIA   -    MD0100PA00X+162960Y+022716X0200Y    R090 S0      
327m4768            U240  -2          A01X+163282Y+022716X0160Y0340R270 S1      
327m4769            J38   -B42        A01X+162345Y+004437X0150Y0570R180 S1      
317m4769            VIA   -    MD0100PA00X+162319Y+004872X0200Y         S0      
327m4769            R1905 -2          A01X+178787Y+042543X0198Y0197     S1      
317m4769            VIA   -    M      A01X+179222Y+042543X0200Y         S2      
017m4769            VIA   -    M      A18X+179222Y+042543X0260Y         S2      
017m4769                  -    MD0100PA00X+179222Y+042543                       
327m4769            U211  -1          A01X+179817Y+042389X0170Y0240R270 S1      
317m4769            VIA   -    MD0100PA00X+163605Y+022991X0200Y    R270 S0      
327m4769            U240  -1          A01X+163282Y+022991X0200Y0340R270 S1      
327m4770            R8013 -1          A18X+004350Y+032108X0198Y0197R090 S2      
327m4770            VIA   -    M      A18X+004699Y+032456X0260Y         S2      
327m4770            U240  -7          A01X+164680Y+022716X0160Y0340R270 S1      
317m4770            VIA   -    MD0100PA00X+165002Y+022716X0200Y    R090 S0      
317m4770            VIA   -    MD0100PA00X+070614Y+034560X0200Y         S0      
327m4771            U244  -1          A01X+060191Y+037899X0140Y0440R270 S1      
327m4771            VIA   -    M      A01X+059225Y+038979X0300Y    R270 S1      
327m4771            U243  -1          A01X+060191Y+038979X0140Y0440R270 S1      
327m4772            R38   -2          A18X+178592Y+004609X0198Y0197     S2      
327m4772            J38   -OB2        A01X+177938Y+004437X0150Y0570R180 S1      
317m4772            VIA   -    M      A01X+177938Y+005074X0200Y         S2      
017m4772            VIA   -    M      A18X+177938Y+005074X0260Y         S2      
017m4772                  -    MD0100PA00X+177938Y+005074                       
317m4773            VIA   -    M      A01X+100647Y+030186X0200Y         S2      
017m4773            VIA   -    M      A18X+100647Y+030186X0260Y         S2      
017m4773                  -    MD0100PA00X+100647Y+030186                       
317m4773            VIA   -    MD0100PA00X+099932Y+039448X0200Y         S0      
317m4773            VIA   -    MD0100PA00X+072363Y+038686X0200Y    R090 S0      
327m4773            R959  -1          A18X+072350Y+039329X0198Y0197R270 S2      
327m4773            R38   -1          A18X+178906Y+004609X0198Y0197     S2      
317m4773            VIA   -    MD0100PA00X+179410Y+005046X0200Y         S0      
327m4773            R1930 -2   M      A18X+179167Y+005001X0198Y0197R090 S2      
327m4774            R1898 -1          A18X+172046Y+007353X0198Y0197R270 S2      
327m4774            R41   -1          A01X+171656Y+006535X0198Y0197R270 S1      
317m4774            VIA   -    M      A01X+171656Y+006787X0200Y         S2      
017m4774            VIA   -    M      A18X+171656Y+006787X0260Y         S2      
017m4774                  -    MD0100PA00X+171656Y+006787                       
327m4775            R1897 -1          A18X+171280Y+010743X0198Y0197R090 S2      
327m4775            R40   -1          A01X+171693Y+007883X0198Y0197R270 S1      
317m4775            VIA   -    M      A01X+171269Y+011191X0200Y         S2      
017m4775            VIA   -    M      A18X+171269Y+011191X0260Y         S2      
017m4775                  -    MD0100PA00X+171269Y+011191                       
327m4776            R1896 -1          A18X+172446Y+007353X0198Y0197R270 S2      
327m4776            R39   -1          A01X+172134Y+006553X0198Y0197R270 S1      
317m4776            VIA   -    M      A01X+172165Y+006812X0200Y         S2      
017m4776            VIA   -    M      A18X+172165Y+006812X0260Y         S2      
017m4776                  -    MD0100PA00X+172165Y+006812                       
327m4777            U7    -11         A18X+081858Y+027374X0140Y0590R090 S2      
317m4777            VIA   -    MD0100PA00X+082307Y+027322X0200Y         S0      
327m4777            J38   -OA5        A01X+177229Y+003276X0150Y0570R180 S1      
317m4777            VIA   -    M      A01X+177092Y+001703X0200Y         S2      
017m4777            VIA   -    M      A18X+177092Y+001703X0260Y         S2      
017m4777                  -    MD0100PA00X+177092Y+001703                       
317m4778            VIA   -    M      A01X+075794Y+030391X0200Y         S2      
017m4778            VIA   -    M      A18X+075794Y+030391X0260Y         S2      
017m4778                  -    MD0100PA00X+075794Y+030391                       
327m4778            U67   -11         A18X+076498Y+030391X0140Y0590R090 S2      
327m4778            J38   -OA4        A01X+177465Y+003276X0150Y0570R180 S1      
317m4778            VIA   -    MD0100PA00X+177592Y+001703X0200Y         S0      
327OCP_SFF_ID1      J38   -OA6        A01X+176993Y+003276X0150Y0570R180 S1      
317OCP_SFF_ID1      VIA   -    M      A01X+177092Y+002203X0200Y         S2      
017OCP_SFF_ID1      VIA   -    M      A18X+177092Y+002203X0260Y         S2      
017OCP_SFF_ID1            -    MD0100PA00X+177092Y+002203                       
327OCP_SFF_ID1      R33   -2          A18X+177376Y+003132X0198Y0197R090 S2      
327OCP_SFF_ID1      R34   -1   M      A18X+176976Y+003132X0198Y0197R270 S2      
327OCP_SFF_ID0      J38   -OB7        A01X+176757Y+004437X0150Y0570R180 S1      
317OCP_SFF_ID0      VIA   -    M      A01X+176727Y+004875X0200Y         S2      
017OCP_SFF_ID0      VIA   -    M      A18X+176727Y+004875X0260Y         S2      
017OCP_SFF_ID0            -    MD0100PA00X+176727Y+004875                       
327OCP_SFF_ID0      R31   -2   M      A18X+176606Y+004318X0198Y0197R270 S2      
327OCP_SFF_ID0      R32   -1          A18X+176206Y+004318X0198Y0197R090 S2      
327m4779            R41   -2          A01X+171656Y+006220X0198Y0197R270 S1      
327m4779            J38   -B9         A01X+171483Y+004437X0150Y0570R180 S1      
327m4779            VIA   -    M      A01X+171257Y+005710X0300Y         S1      
327m4780            R40   -2          A01X+171693Y+007568X0198Y0197R270 S1      
327m4780            VIA   -    M      A01X+171757Y+005710X0300Y         S1      
327m4780            J38   -B8         A01X+171719Y+004437X0150Y0570R180 S1      
327m4781            J38   -B7         A01X+171956Y+004437X0150Y0570R180 S1      
327m4781            R39   -2          A01X+172134Y+006238X0198Y0197R270 S1      
327m4781            VIA   -    M      A01X+172257Y+005710X0300Y         S1      
327m4782            VIA   -    M      A01X+180021Y+039041X0300Y    R270 S1      
327m4782            U66   -1          A01X+180563Y+039041X0170Y0240R270 S1      
327m4782            R1719 -2          A01X+179535Y+039041X0198Y0197     S1      
327m4783            J38   -B12        A01X+170774Y+004437X0150Y0570R180 S1      
327m4783            VIA   -    M      A01X+170607Y+005710X0300Y         S1      
327m4783            R1671 -2          A01X+171180Y+006220X0198Y0197R270 S1      
327m4784            R1671 -1          A01X+171180Y+006535X0198Y0197R270 S1      
317m4784            VIA   -    MD0100PA00X+084226Y+035038X0200Y         S0      
327m4784            R1929 -2   M      A01X+171180Y+007569X0198Y0197R270 S1      
317m4784            VIA   -    MD0100PA00X+171249Y+011791X0200Y         S0      
327m4784            R3231 -1   M      A01X+179220Y+036787X0198Y0197     S1      
317m4784            VIA   -    M      A01X+178977Y+036787X0200Y    R180 S2      
017m4784            VIA   -    M      A18X+178977Y+036787X0260Y    R180 S2      
017m4784                  -    MD0100PA00X+178977Y+036787                       
327m4784            R1719 -1          A01X+179220Y+039041X0198Y0197     S1      
317m4784            VIA   -    MD0100PA00X+084842Y+037809X0200Y         S0      
327m4784            R9031 -2          A01X+084842Y+038500X0198Y0197R180 S1      
327m4784            R1145 -2   M      A01X+084842Y+038100X0198Y0197R180 S1      
327NC_U316_2Y       VIA   -           A01X+137926Y+171644X0300Y    R180 S1      
327NC_U316_2Y       U316  -4          A01X+138506Y+171644X0160Y0200R180 S1      
327NC_U257_2Y       VIA   -           A01X+046450Y+171150X0300Y    R090 S1      
327NC_U257_2Y       U257  -4          A01X+046742Y+172005X0170Y0240R180 S1      
327NC_U219_NC1      VIA   -           A01X+036540Y+014691X0300Y         S1      
327NC_U219_NC1      U219  -1          A01X+037100Y+014264X0220Y0320R270 S1      
327NC_U218_NC1      VIA   -           A01X+098670Y+042837X0300Y    R180 S1      
327NC_U218_NC1      U218  -1          A01X+099268Y+042837X0220Y0320R270 S1      
327NC_U157_NC1      VIA   -           A01X+063491Y+012128X0300Y    R180 S1      
327NC_U157_NC1      U157  -1          A01X+063491Y+012805X0220Y0320     S1      
327NC_U104_NC1      VIA   -           A01X+143995Y+006217X0300Y         S1      
327NC_U104_NC1      U104  -1          A01X+144537Y+006041X0220Y0320R270 S1      
327m4785            PU53  -41         A01X+010660Y+136406X0120Y0180R270 S1      
327m4786            PU52  -41         A01X+013920Y+136406X0120Y0180R270 S1      
327m4787            PU40  -41         A01X+017190Y+136406X0120Y0180R270 S1      
327m4788            PU39  -41         A01X+020480Y+136406X0120Y0180R270 S1      
327m4789            PU53  -6          A01X+010315Y+136514X0090Y0240R090 S1      
327m4790            PU52  -6          A01X+013575Y+136514X0090Y0240R090 S1      
327m4791            PU40  -6          A01X+016845Y+136514X0090Y0240R090 S1      
327m4792            PU39  -6          A01X+020135Y+136514X0090Y0240R090 S1      
327m4793            PU53  -31         A01X+011894Y+137646X0090Y0240     S1      
327m4794            PU52  -31         A01X+015154Y+137646X0090Y0240     S1      
327m4795            PU40  -31         A01X+018424Y+137646X0090Y0240     S1      
327m4796            PU39  -31         A01X+021714Y+137646X0090Y0240     S1      
327m4797            PU20  -41         A01X+107834Y+136404X0120Y0180R270 S1      
327m4798            PU19  -41         A01X+111094Y+136404X0120Y0180R270 S1      
327m4799            PU18  -41         A01X+114364Y+136404X0120Y0180R270 S1      
327m4800            PU17  -41         A01X+117654Y+136404X0120Y0180R270 S1      
327m4801            PU20  -6          A01X+107489Y+136512X0090Y0240R090 S1      
327m4802            PU19  -6          A01X+110749Y+136512X0090Y0240R090 S1      
327m4803            PU18  -6          A01X+114019Y+136512X0090Y0240R090 S1      
327m4804            PU17  -6          A01X+117309Y+136512X0090Y0240R090 S1      
327m4805            PU20  -31         A01X+109068Y+137644X0090Y0240     S1      
327m4806            PU19  -31         A01X+112328Y+137644X0090Y0240     S1      
327m4807            PU18  -31         A01X+115598Y+137644X0090Y0240     S1      
327m4808            PU17  -31         A01X+118888Y+137644X0090Y0240     S1      
327m4809            PU32  -41         A01X+052736Y+061725X0120Y0180R090 S1      
327m4810            PU31  -41         A01X+049406Y+065135X0120Y0180R090 S1      
327m4811            PU30  -41         A01X+046146Y+067785X0120Y0180R090 S1      
327m4812            PU32  -6          A01X+053080Y+061617X0090Y0240R270 S1      
327m4813            PU31  -6          A01X+049750Y+065027X0090Y0240R270 S1      
327m4814            PU30  -6          A01X+046490Y+067677X0090Y0240R270 S1      
327m4815            PU32  -31         A01X+051502Y+060485X0090Y0240R180 S1      
327m4816            PU31  -31         A01X+048172Y+063895X0090Y0240R180 S1      
327m4817            PU30  -31         A01X+044912Y+066545X0090Y0240R180 S1      
327m4818            PU51  -41         A01X+163801Y+064574X0120Y0180R090 S1      
327m4819            PU50  -41         A01X+160501Y+066474X0120Y0180R090 S1      
327m4820            PU49  -41         A01X+157224Y+069851X0120Y0180R090 S1      
327m4821            PU51  -6          A01X+164146Y+064466X0090Y0240R270 S1      
327m4822            PU50  -6          A01X+160846Y+066366X0090Y0240R270 S1      
327m4823            PU49  -6          A01X+157569Y+069743X0090Y0240R270 S1      
327m4824            PU51  -31         A01X+162567Y+063334X0090Y0240R180 S1      
327m4825            PU50  -31         A01X+159267Y+065234X0090Y0240R180 S1      
327m4826            PU49  -31         A01X+155990Y+068611X0090Y0240R180 S1      
327m4827            PU34  -5          A01X+012236Y+144482X0070Y0260R180 S1      
327m4828            PU34  -6          A01X+012079Y+144482X0070Y0260R180 S1      
327m4829            PU34  -34         A01X+012551Y+142218X0070Y0260R180 S1      
327m4829            PR12  -1          A18X+012450Y+142192X0198Y0197R270 S2      
317m4829            VIA   -    MD0100PA00X+012600Y+141800X0200Y         S0      
317m4830            VIA   -    M      A01X+012600Y+141400X0200Y         S2      
017m4830            VIA   -    M      A18X+012600Y+141400X0260Y         S2      
017m4830                  -    MD0100PA00X+012600Y+141400                       
327m4830            PR533 -1          A18X+013000Y+142192X0198Y0197R270 S2      
327m4830            PU34  -33         A01X+012394Y+142218X0070Y0260R180 S1      
327m4831            PU33  -41         A01X+040238Y+133736X0120Y0180R270 S1      
327m4832            PU38  -41         A01X+036980Y+131803X0120Y0180R270 S1      
327m4833            PU36  -41         A01X+023760Y+136406X0120Y0180R270 S1      
327m4834            PU37  -41         A01X+027120Y+131791X0120Y0180R270 S1      
327m4835            PU5   -41         A01X+030409Y+131789X0120Y0180R270 S1      
327m4836            PU35  -41         A01X+033700Y+131783X0120Y0180R270 S1      
327m4837            PU33  -6          A01X+039893Y+133844X0090Y0240R090 S1      
327m4838            PU38  -6          A01X+036635Y+131911X0090Y0240R090 S1      
327m4839            PU36  -6          A01X+023415Y+136514X0090Y0240R090 S1      
327m4840            PU37  -6          A01X+026775Y+131900X0090Y0240R090 S1      
327m4841            PU5   -6          A01X+030065Y+131897X0090Y0240R090 S1      
327m4842            PU35  -6          A01X+033355Y+131891X0090Y0240R090 S1      
327m4843            PU33  -31         A01X+041472Y+134976X0090Y0240     S1      
327m4844            PU38  -31         A01X+038214Y+133043X0090Y0240     S1      
327m4845            PU36  -31         A01X+024994Y+137646X0090Y0240     S1      
327m4846            PU37  -31         A01X+028354Y+133032X0090Y0240     S1      
327m4847            PU5   -31         A01X+031644Y+133029X0090Y0240     S1      
327m4848            PU35  -31         A01X+034934Y+133023X0090Y0240     S1      
327m4849            PU12  -5          A01X+122336Y+143132X0070Y0260R180 S1      
327m4850            PU12  -6          A01X+122179Y+143132X0070Y0260R180 S1      
327m4851            PR32  -1          A18X+122550Y+140842X0198Y0197R270 S2      
327m4851            PU12  -34         A01X+122651Y+140868X0070Y0260R180 S1      
317m4851            VIA   -    MD0100PA00X+122700Y+140450X0200Y         S0      
327m4852            PU12  -33         A01X+122494Y+140868X0070Y0260R180 S1      
327m4852            PR532 -1          A18X+123100Y+140842X0198Y0197R270 S2      
317m4852            VIA   -    MD0100PA00X+122700Y+140130X0200Y         S0      
327m4853            PU11  -41         A01X+137851Y+133734X0120Y0180R270 S1      
327m4854            PU16  -41         A01X+134593Y+131801X0120Y0180R270 S1      
327m4855            PU14  -41         A01X+120934Y+136404X0120Y0180R270 S1      
327m4856            PU15  -41         A01X+124733Y+131790X0120Y0180R270 S1      
327m4857            PU2   -41         A01X+128022Y+131787X0120Y0180R270 S1      
327m4858            PU13  -41         A01X+131313Y+131781X0120Y0180R270 S1      
327m4859            PU11  -6          A01X+137506Y+133842X0090Y0240R090 S1      
327m4860            PU16  -6          A01X+134248Y+131909X0090Y0240R090 S1      
327m4861            PU14  -6          A01X+120589Y+136512X0090Y0240R090 S1      
327m4862            PU15  -6          A01X+124388Y+131898X0090Y0240R090 S1      
327m4863            PU2   -6          A01X+127678Y+131895X0090Y0240R090 S1      
327m4864            PU13  -6          A01X+130968Y+131889X0090Y0240R090 S1      
327m4865            PU11  -31         A01X+139085Y+134974X0090Y0240     S1      
327m4866            PU16  -31         A01X+135827Y+133041X0090Y0240     S1      
327m4867            PU14  -31         A01X+122168Y+137644X0090Y0240     S1      
327m4868            PU15  -31         A01X+125967Y+133030X0090Y0240     S1      
327m4869            PU2   -31         A01X+129256Y+133027X0090Y0240     S1      
327m4870            PU13  -31         A01X+132547Y+133021X0090Y0240     S1      
327m4871            PU25  -4          A18X+038059Y+055860X0070Y0260     S2      
327m4872            PU25  -5          A18X+037902Y+055860X0070Y0260     S2      
327m4873            PU25  -6          A18X+037744Y+055860X0070Y0260     S2      
327m4874            VIA   -    M      A18X+038607Y+058714X0260Y    R180 S2      
327m4874            PU25  -35         A18X+038374Y+058123X0070Y0260     S2      
327m4874            PR437 -1          A18X+038944Y+059173X0198Y0197R270 S2      
327m4875            PR436 -1          A18X+038544Y+059173X0198Y0197R270 S2      
327m4875            PU25  -34         A18X+038217Y+058123X0070Y0260     S2      
327m4876            PR530 -1          A18X+038144Y+059173X0198Y0197R270 S2      
327m4876            PU25  -33         A18X+038059Y+058123X0070Y0260     S2      
327m4877            PU24  -41         A01X+026446Y+066606X0120Y0180R090 S1      
327m4878            PU29  -41         A01X+029719Y+070030X0120Y0180R090 S1      
327m4879            PU28  -41         A01X+042906Y+070245X0120Y0180R090 S1      
327m4880            PU27  -41         A01X+039606Y+072025X0120Y0180R090 S1      
327m4881            PU26  -41         A01X+036302Y+072018X0120Y0180R090 S1      
327m4882            PU4   -41         A01X+032996Y+072045X0120Y0180R090 S1      
327m4883            PU24  -6          A01X+026790Y+066498X0090Y0240R270 S1      
327m4884            PU29  -6          A01X+030063Y+069922X0090Y0240R270 S1      
327m4885            PU28  -6          A01X+043250Y+070137X0090Y0240R270 S1      
327m4886            PU27  -6          A01X+039950Y+071917X0090Y0240R270 S1      
327m4887            PU26  -6          A01X+036646Y+071910X0090Y0240R270 S1      
327m4888            PU4   -6          A01X+033340Y+071937X0090Y0240R270 S1      
327m4889            PU24  -31         A01X+025212Y+065366X0090Y0240R180 S1      
327m4890            PU29  -31         A01X+028485Y+068790X0090Y0240R180 S1      
327m4891            PU28  -31         A01X+041672Y+069005X0090Y0240R180 S1      
327m4892            PU27  -31         A01X+038372Y+070785X0090Y0240R180 S1      
327m4893            PU26  -31         A01X+035068Y+070778X0090Y0240R180 S1      
327m4894            PU4   -31         A01X+031762Y+070805X0090Y0240R180 S1      
327m4895            PU42  -4          A18X+149369Y+054916X0070Y0260     S2      
327m4896            PU42  -5          A18X+149212Y+054916X0070Y0260     S2      
327m4897            PU42  -6          A18X+149054Y+054916X0070Y0260     S2      
327m4898            PR441 -1          A18X+150254Y+058229X0198Y0197R270 S2      
327m4898            PU42  -35         A18X+149684Y+057180X0070Y0260     S2      
327m4899            PR440 -1          A18X+149854Y+058229X0198Y0197R270 S2      
327m4899            PU42  -34         A18X+149527Y+057180X0070Y0260     S2      
327m4900            PU42  -33         A18X+149369Y+057180X0070Y0260     S2      
327m4900            PR531 -1          A18X+149454Y+058229X0198Y0197R270 S2      
327m4901            PU10  -41         A01X+137501Y+063539X0120Y0180R090 S1      
327m4902            PU48  -41         A01X+140771Y+066829X0120Y0180R090 S1      
327m4903            PU47  -41         A01X+153911Y+072045X0120Y0180R090 S1      
327m4904            PU46  -41         A01X+150631Y+072062X0120Y0180R090 S1      
327m4905            PU43  -41         A01X+147323Y+072045X0120Y0180R090 S1      
327m4906            PU6   -41         A01X+144031Y+070087X0120Y0180R090 S1      
327m4907            PU10  -6          A01X+137846Y+063431X0090Y0240R270 S1      
327m4908            PU48  -6          A01X+141116Y+066721X0090Y0240R270 S1      
327m4909            PU47  -6          A01X+154256Y+071937X0090Y0240R270 S1      
327m4910            PU46  -6          A01X+150976Y+071953X0090Y0240R270 S1      
327m4911            PU43  -6          A01X+147667Y+071937X0090Y0240R270 S1      
327m4912            PU6   -6          A01X+144376Y+069979X0090Y0240R270 S1      
327m4913            PU10  -31         A01X+136267Y+062299X0090Y0240R180 S1      
327m4914            PU48  -31         A01X+139537Y+065589X0090Y0240R180 S1      
327m4915            PU47  -31         A01X+152677Y+070805X0090Y0240R180 S1      
327m4916            PU46  -31         A01X+149397Y+070822X0090Y0240R180 S1      
327m4917            PU43  -31         A01X+146089Y+070805X0090Y0240R180 S1      
327m4918            PU6   -31         A01X+142797Y+068847X0090Y0240R180 S1      
327m4919            PU54  -19         A01X+062925Y+136674X0070Y0240R270 S1      
327m4920            PU54  -1          A01X+064578Y+138171X0070Y0240R180 S1      
327m4921            PU54  -2          A01X+064421Y+138171X0070Y0240R180 S1      
327m4922            PU54  -3          A01X+064263Y+138171X0070Y0240R180 S1      
327m4923            PU54  -4          A01X+064106Y+138171X0070Y0240R180 S1      
327m4924            PU54  -5          A01X+063948Y+138171X0070Y0240R180 S1      
327m4925            PU54  -6          A01X+063791Y+138171X0070Y0240R180 S1      
327m4926            PU54  -16         A01X+062925Y+137147X0070Y0240R270 S1      
327m4927            PU54  -30         A01X+064578Y+136281X0070Y0240R180 S1      
327m4927            PR409 -1          A01X+065784Y+135651X0198Y0197R270 S1      
327m4928            PU54  -29         A01X+064421Y+136281X0070Y0240R180 S1      
327m4928            PR408 -1          A01X+065384Y+135651X0198Y0197R270 S1      
327m4929            PU54  -28         A01X+064263Y+136281X0070Y0240R180 S1      
327m4929            PR14  -1          A01X+065004Y+135651X0198Y0197R270 S1      
327m4930            PU54  -27         A01X+064106Y+136281X0070Y0240R180 S1      
327m4930            PR13  -1          A01X+064624Y+135651X0198Y0197R270 S1      
327m4931            PU54  -26         A01X+063948Y+136281X0070Y0240R180 S1      
327m4931            PR407 -1          A01X+064244Y+135651X0198Y0197R270 S1      
327m4932            PR406 -1          A01X+063844Y+135651X0198Y0197R270 S1      
327m4932            PU54  -25         A01X+063791Y+136281X0070Y0240R180 S1      
327m4933            PU45  -41         A01X+074694Y+138217X0120Y0180R270 S1      
327m4934            PU44  -41         A01X+071415Y+138207X0120Y0180R270 S1      
327m4935            PU45  -6          A01X+074349Y+138325X0090Y0240R090 S1      
327m4936            PU44  -6          A01X+071071Y+138315X0090Y0240R090 S1      
327m4937            PU45  -31         A01X+075928Y+139457X0090Y0240     S1      
327m4938            PU44  -31         A01X+072650Y+139447X0090Y0240     S1      
327m4939            PU21  -19         A01X+163983Y+142003X0070Y0240R270 S1      
327m4940            PU21  -1          A01X+165637Y+143499X0070Y0240R180 S1      
327m4941            PU21  -2          A01X+165480Y+143499X0070Y0240R180 S1      
327m4942            PU21  -3          A01X+165322Y+143499X0070Y0240R180 S1      
327m4943            PU21  -4          A01X+165164Y+143499X0070Y0240R180 S1      
327m4944            PU21  -5          A01X+165007Y+143499X0070Y0240R180 S1      
327m4945            PU21  -6          A01X+164850Y+143499X0070Y0240R180 S1      
327m4946            PU21  -16         A01X+163983Y+142475X0070Y0240R270 S1      
327m4947            VIA   -    M      A01X+166215Y+141496X0160Y0041     S1      
327m4947            PU21  -30         A01X+165637Y+141609X0070Y0240R180 S1      
327m4947            PR36  -1          A01X+166842Y+140980X0198Y0197R270 S1      
327m4948            PR419 -1          A01X+166442Y+140980X0198Y0197R270 S1      
327m4948            PU21  -29         A01X+165480Y+141609X0070Y0240R180 S1      
327m4949            PR35  -1          A01X+166062Y+140980X0198Y0197R270 S1      
327m4949            PU21  -28         A01X+165322Y+141609X0070Y0240R180 S1      
327m4950            PR34  -1          A01X+165682Y+140980X0198Y0197R270 S1      
327m4950            PU21  -27         A01X+165164Y+141609X0070Y0240R180 S1      
327m4951            PR33  -1          A01X+165302Y+140980X0198Y0197R270 S1      
327m4951            PU21  -26         A01X+165007Y+141609X0070Y0240R180 S1      
327m4952            PR37  -1          A01X+164902Y+140980X0198Y0197R270 S1      
327m4952            PU21  -25         A01X+164850Y+141609X0070Y0240R180 S1      
327m4953            PU23  -41         A01X+169467Y+138146X0120Y0180R270 S1      
327m4954            PU22  -41         A01X+166189Y+138136X0120Y0180R270 S1      
327m4955            PU23  -6          A01X+169122Y+138254X0090Y0240R090 S1      
327m4956            PU22  -6          A01X+165844Y+138244X0090Y0240R090 S1      
327m4957            PU23  -31         A01X+170701Y+139386X0090Y0240     S1      
327m4958            PU22  -31         A01X+167423Y+139376X0090Y0240     S1      
327NC_PU9_4         PU9   -37         A01X+180335Y+020164X0120Y0200R270 S1      
327NC_PU9_3         PU9   -6          A01X+180650Y+020204X0110Y0240R270 S1      
327NC_PU9_2         PU9   -34         A01X+180020Y+018973X0110Y0240R180 S1      
327NC_PU9_1         PU9   -33         A01X+179823Y+018973X0110Y0240R180 S1      
327NC_M2_0_SUSCLK   VIA   -           A01X+065139Y+013397X0300Y         S1      
327NC_M2_0_SUSCLK   J59   -68         A01X+066755Y+015571X0110Y0630R270 S1      
327NC_M2_0_NC9      VIA   -           A01X+062127Y+019296X0300Y    R180 S1      
327NC_M2_0_NC9      J59   -32         A01X+066755Y+019114X0110Y0630R270 S1      
327NC_M2_0_NC8      VIA   -           A01X+061627Y+019296X0300Y    R180 S1      
327NC_M2_0_NC8      J59   -30         A01X+066755Y+019311X0110Y0630R270 S1      
327NC_M2_0_NC7      VIA   -           A01X+062127Y+019796X0300Y    R180 S1      
327NC_M2_0_NC7      J59   -28         A01X+066755Y+019508X0110Y0630R270 S1      
327NC_M2_0_NC6      VIA   -           A01X+061627Y+019796X0300Y    R180 S1      
327NC_M2_0_NC6      J59   -26         A01X+066755Y+019705X0110Y0630R270 S1      
327NC_M2_0_NC5      VIA   -           A01X+062127Y+020296X0300Y         S1      
327NC_M2_0_NC5      J59   -24         A01X+066755Y+019902X0110Y0630R270 S1      
327NC_M2_0_NC4      VIA   -           A01X+061627Y+020296X0300Y         S1      
327NC_M2_0_NC4      J59   -22         A01X+066755Y+020098X0110Y0630R270 S1      
327NC_M2_0_NC3      VIA   -           A01X+062127Y+020796X0300Y         S1      
327NC_M2_0_NC3      J59   -20         A01X+066755Y+020295X0110Y0630R270 S1      
327NC_M2_0_NC2      J59   -8          A01X+066755Y+021476X0110Y0630R270 S1      
327NC_M2_0_NC2      VIA   -           A01X+065613Y+026349X0300Y         S1      
327NC_M2_0_NC19     VIA   -           A01X+071080Y+016301X0300Y    R180 S1      
327NC_M2_0_NC19     J59   -67         A01X+069728Y+015669X0110Y0630R270 S1      
327NC_M2_0_NC18     VIA   -           A01X+065439Y+015297X0300Y         S1      
327NC_M2_0_NC18     J59   -58         A01X+066755Y+016555X0110Y0630R270 S1      
327NC_M2_0_NC17     J59   -56         A01X+066755Y+016752X0110Y0630R270 S1      
327NC_M2_0_NC17     VIA   -           A01X+065437Y+015857X0300Y         S1      
327NC_M2_0_NC16     VIA   -           A01X+065139Y+014897X0300Y         S1      
327NC_M2_0_NC16     J59   -48         A01X+066755Y+017539X0110Y0630R270 S1      
327NC_M2_0_NC15     VIA   -           A01X+065139Y+014397X0300Y         S1      
327NC_M2_0_NC15     J59   -46         A01X+066755Y+017736X0110Y0630R270 S1      
327NC_M2_0_NC14     VIA   -           A01X+065139Y+013897X0300Y         S1      
327NC_M2_0_NC14     J59   -44         A01X+066755Y+017933X0110Y0630R270 S1      
327NC_M2_0_NC11     VIA   -           A01X+062127Y+018796X0300Y    R180 S1      
327NC_M2_0_NC11     J59   -36         A01X+066755Y+018720X0110Y0630R270 S1      
327NC_M2_0_NC10     VIA   -           A01X+061627Y+018796X0300Y    R180 S1      
327NC_M2_0_NC10     J59   -34         A01X+066755Y+018917X0110Y0630R270 S1      
327NC_M2_0_NC1      J59   -6          A01X+066755Y+021673X0110Y0630R270 S1      
327NC_M2_0_NC1      VIA   -           A01X+065632Y+025459X0300Y         S1      
317NC_J112_S5       J112  -S5   D0142PA00X+026240Y+164917X0302Y    R180 S3      
317NC_J112_R5       J112  -R5   D0142PA00X+026240Y+165390X0302Y    R180 S3      
317NC_J112_P5       J112  -P5   D0142PA00X+026240Y+166335X0302Y    R180 S3      
317NC_J112_O5       J112  -O5   D0142PA00X+026240Y+166807X0302Y    R180 S3      
317NC_J112_O2       J112  -O2   D0142PA00X+023878Y+166728X0302Y    R180 S3      
317NC_J112_N2       J112  -N2   D0142PA00X+023878Y+167201X0302Y    R180 S3      
317NC_J108_N6       J108  -N6   D0142PA00X+127815Y+167201X0302Y    R180 S3      
327NC_J108_N6       VIA   -           A18X+127664Y+166115X0260Y         S2      
317NC_J108_N4       J108  -N4   D0142PA00X+126240Y+167201X0302Y    R180 S3      
327NC_J108_N4       VIA   -           A18X+126377Y+166115X0260Y         S2      
317NC_J108_N2       J108  -N2   D0142PA00X+124665Y+167201X0302Y    R180 S3      
327NC_J108_N2       VIA   -           A18X+122417Y+167005X0260Y         S2      
317NC_J107_N6       J107  -N6   D0142PA00X+134508Y+167201X0302Y    R180 S3      
327NC_J107_N6       VIA   -           A18X+134797Y+166116X0260Y         S2      
317NC_J107_N4       J107  -N4   D0142PA00X+132933Y+167201X0302Y    R180 S3      
327NC_J107_N4       VIA   -           A18X+133047Y+166113X0260Y         S2      
327NC_J107_A5       VIA   -           A18X+133703Y+166113X0260Y         S2      
317NC_J107_A5       J107  -A5   D0142PA00X+133720Y+173421X0302Y    R180 S3      
327NC_J107_A3       VIA   -           A18X+132386Y+166118X0260Y         S2      
317NC_J107_A3       J107  -A3   D0142PA00X+132146Y+173421X0302Y    R180 S3      
327NC_J107_A1       VIA   -           A18X+130021Y+166289X0260Y         S2      
317NC_J107_A1       J107  -A1   D0142PA00X+130571Y+173421X0302Y0302R180 S3      
327NC_J106_A5       VIA   -           A18X+149587Y+166421X0260Y         S2      
317NC_J106_A5       J106  -A5   D0142PA00X+153445Y+173421X0302Y    R180 S3      
327NC_HICCUP        PU9   -35         A01X+180217Y+018973X0110Y0240R180 S1      
317m4959            VIA   -     D0080PA00X+036725Y+115880X0160Y         S0      
327m4959            U26   -DG58       A01X+036909Y+115776X0177Y    R180 S1      
317m4960            VIA   -     D0080PA00X+036540Y+116199X0160Y         S0      
327m4960            U26   -DH58       A01X+036724Y+116095X0177Y    R180 S1      
317m4961            VIA   -     D0080PA00X+035244Y+116518X0160Y         S0      
327m4961            U26   -DJ62       A01X+035428Y+116414X0177Y    R180 S1      
317m4962            VIA   -     D0080PA00X+035060Y+116199X0160Y         S0      
327m4962            U26   -DH62       A01X+035243Y+116095X0177Y    R180 S1      
317m4963            VIA   -     D0080PA00X+032469Y+116199X0160Y         S0      
327m4963            U26   -DH69       A01X+032653Y+116095X0177Y    R180 S1      
317m4964            VIA   -     D0080PA00X+032654Y+116518X0160Y         S0      
327m4964            U26   -DJ69       A01X+032838Y+116414X0177Y    R180 S1      
317m4965            VIA   -     D0080PA00X+034134Y+116518X0160Y         S0      
327m4965            U26   -DJ65       A01X+034318Y+116414X0177Y    R180 S1      
317m4966            VIA   -     D0080PA00X+033949Y+116199X0160Y         S0      
327m4966            U26   -DH65       A01X+034133Y+116095X0177Y    R180 S1      
317m4967            VIA   -     D0080PA00X+046966Y+088600X0160Y    R180 S0      
327m4967            U26   -E30        A01X+046783Y+088705X0177Y    R180 S1      
317m4968            VIA   -     D0080PA00X+047336Y+088600X0160Y    R180 S0      
327m4968            U26   -E29        A01X+047153Y+088705X0177Y    R180 S1      
317m4969            VIA   -     D0080PA00X+047336Y+087962X0160Y    R180 S0      
327m4969            U26   -C29        A01X+047153Y+088067X0177Y    R180 S1      
317m4970            VIA   -     D0080PA00X+047707Y+087962X0160Y    R180 S0      
327m4970            U26   -C28        A01X+047523Y+088067X0177Y    R180 S1      
317m4971            VIA   -     D0080PA00X+048447Y+087962X0160Y    R180 S0      
327m4971            U26   -C26        A01X+048263Y+088067X0177Y    R180 S1      
317m4972            VIA   -     D0080PA00X+048817Y+087962X0160Y    R180 S0      
327m4972            U26   -C25        A01X+048633Y+088067X0177Y    R180 S1      
317m4973            VIA   -     D0080PA00X+048077Y+088600X0160Y    R180 S0      
327m4973            U26   -E27        A01X+047893Y+088705X0177Y    R180 S1      
317m4974            VIA   -     D0080PA00X+048447Y+088600X0160Y    R180 S0      
327m4974            U26   -E26        A01X+048263Y+088705X0177Y    R180 S1      
317m4975            VIA   -     D0080PA00X+035800Y+116199X0160Y         S0      
327m4975            U26   -DH60       A01X+035983Y+116095X0177Y    R180 S1      
317m4976            VIA   -     D0080PA00X+035985Y+116518X0160Y         S0      
327m4976            U26   -DJ60       A01X+036168Y+116414X0177Y    R180 S1      
317m4977            VIA   -     D0080PA00X+033394Y+116518X0160Y         S0      
327m4977            U26   -DJ67       A01X+033578Y+116414X0177Y    R180 S1      
317m4978            VIA   -     D0080PA00X+033209Y+116199X0160Y         S0      
327m4978            U26   -DH67       A01X+033393Y+116095X0177Y    R180 S1      
317m4979            VIA   -     D0080PA00X+047707Y+087325X0160Y    R180 S0      
327m4979            U26   -A28        A01X+047523Y+087429X0177Y    R180 S1      
317m4980            VIA   -     D0080PA00X+047336Y+087325X0160Y    R180 S0      
327m4980            U26   -A29        A01X+047153Y+087429X0177Y    R180 S1      
317m4981            VIA   -     D0080PA00X+048447Y+087325X0160Y    R180 S0      
327m4981            U26   -A26        A01X+048263Y+087429X0177Y    R180 S1      
317m4982            VIA   -     D0080PA00X+048817Y+087325X0160Y    R180 S0      
327m4982            U26   -A25        A01X+048633Y+087429X0177Y    R180 S1      
317m4983            VIA   -     D0080PA00X+043201Y+116199X0160Y         S0      
327m4983            U26   -DH40       A01X+043385Y+116095X0177Y    R180 S1      
317m4984            VIA   -     D0080PA00X+043386Y+115880X0160Y         S0      
327m4984            U26   -DG40       A01X+043570Y+115776X0177Y    R180 S1      
317m4985            VIA   -     D0080PA00X+049187Y+088600X0160Y    R180 S0      
327m4985            U26   -E24        A01X+049003Y+088705X0177Y    R180 S1      
317m4986            VIA   -     D0080PA00X+049557Y+088600X0160Y    R180 S0      
327m4986            U26   -E23        A01X+049373Y+088705X0177Y    R180 S1      
317m4987            VIA   -     D0080PA00X+055781Y+116199X0160Y         S0      
327m4987            U26   -DH7        A01X+055598Y+116095X0177Y    R180 S1      
317m4988            VIA   -     D0080PA00X+046411Y+088281X0160Y    R180 S0      
327m4988            U26   -D32        A01X+046228Y+088386X0177Y    R180 S1      
317m4989            VIA   -     D0080PA00X+046226Y+087325X0160Y    R180 S0      
327m4989            U26   -A32        A01X+046042Y+087429X0177Y    R180 S1      
317m4990            VIA   -     D0080PA00X+045856Y+087325X0160Y    R180 S0      
327m4990            U26   -A33        A01X+045672Y+087429X0177Y    R180 S1      
317m4991            VIA   -     D0080PA00X+046041Y+088281X0160Y    R180 S0      
327m4991            U26   -D33        A01X+045857Y+088386X0177Y    R180 S1      
317m4992            VIA   -     D0080PA00X+045856Y+087962X0160Y    R180 S0      
327m4992            U26   -C33        A01X+045672Y+088067X0177Y    R180 S1      
317m4993            VIA   -     D0080PA00X+045486Y+087325X0160Y    R180 S0      
327m4993            U26   -A34        A01X+045302Y+087429X0177Y    R180 S1      
317m4994            VIA   -     D0080PA00X+046226Y+087962X0160Y    R180 S0      
327m4994            U26   -C32        A01X+046042Y+088067X0177Y    R180 S1      
327m4995            U25   -DH27       A01X+145810Y+116094X0177Y    R180 S1      
317m4996            VIA   -     D0080PA00X+144026Y+088281X0160Y    R180 S0      
327m4996            U25   -D32        A01X+143842Y+088386X0177Y    R180 S1      
317m4997            VIA   -     D0080PA00X+143840Y+087324X0160Y    R180 S0      
327m4997            U25   -A32        A01X+143657Y+087429X0177Y    R180 S1      
317m4998            VIA   -     D0080PA00X+143470Y+087324X0160Y    R180 S0      
327m4998            U25   -A33        A01X+143287Y+087429X0177Y    R180 S1      
317m4999            VIA   -     D0080PA00X+143655Y+088281X0160Y    R180 S0      
327m4999            U25   -D33        A01X+143472Y+088386X0177Y    R180 S1      
317m5000            VIA   -     D0080PA00X+143470Y+087962X0160Y    R180 S0      
327m5000            U25   -C33        A01X+143287Y+088067X0177Y    R180 S1      
317m5001            VIA   -     D0080PA00X+143100Y+087324X0160Y    R180 S0      
327m5001            U25   -A34        A01X+142916Y+087429X0177Y    R180 S1      
317m5002            VIA   -     D0080PA00X+143840Y+087962X0160Y    R180 S0      
327m5002            U25   -C32        A01X+143657Y+088067X0177Y    R180 S1      
327m5003            U223  -8          A18X+076990Y+027147X0140Y0590R090 S2      
327m5003            VIA   -    M      A18X+075056Y+026863X0260Y         S2      
327m5003            J35   -OA7        A01X+029316Y+003276X0150Y0570R180 S1      
317m5003            VIA   -    MD0100PA00X+029206Y+002448X0200Y         S0      
327m5004            J35   -OA8        A01X+029080Y+003276X0150Y0570R180 S1      
317m5004            VIA   -    M      A01X+029080Y+002836X0200Y         S2      
017m5004            VIA   -    M      A18X+029080Y+002836X0260Y         S2      
017m5004                  -    MD0100PA00X+029080Y+002836                       
327m5004            U223  -3          A18X+079290Y+028170X0140Y0590R090 S2      
327m5005            U223  -6          A18X+079290Y+027403X0140Y0590R090 S2      
327m5005            J35   -OA9        A01X+028843Y+003276X0150Y0570R180 S1      
317m5005            VIA   -    M      A01X+028700Y+002036X0200Y         S2      
017m5005            VIA   -    M      A18X+028700Y+002036X0260Y         S2      
017m5005                  -    MD0100PA00X+028700Y+002036                       
317m5006            VIA   -    MD0100PA00X+029138Y+005575X0200Y         S0      
327m5006            J35   -OB8        A01X+029080Y+004437X0150Y0570R180 S1      
327m5006            U222  -3          A18X+083550Y+030675X0140Y0590R090 S2      
327m5006            VIA   -    M      A18X+080765Y+029227X0260Y         S2      
327m5007            J35   -OB9        A01X+028843Y+004437X0150Y0570R180 S1      
317m5007            VIA   -    M      A01X+028799Y+005489X0200Y         S2      
017m5007            VIA   -    M      A18X+028799Y+005489X0260Y         S2      
017m5007                  -    MD0100PA00X+028799Y+005489                       
327m5007            U222  -6          A18X+083550Y+029907X0140Y0590R090 S2      
327m5008            J35   -OB14       A01X+027662Y+004437X0150Y0570R180 S1      
317m5008            VIA   -    M      A01X+027590Y+004888X0200Y         S2      
017m5008            VIA   -    M      A18X+027590Y+004888X0260Y         S2      
017m5008                  -    MD0100PA00X+027590Y+004888                       
327m5008            U222  -8          A18X+081250Y+029651X0140Y0590R090 S2      
327m5009            U7    -8          A18X+081858Y+026606X0140Y0590R090 S2      
317m5009            VIA   -    MD0100PA00X+081368Y+026606X0200Y         S0      
327m5009            J38   -OA7        A01X+176757Y+003276X0150Y0570R180 S1      
317m5009            VIA   -    M      A01X+176592Y+002203X0200Y         S2      
017m5009            VIA   -    M      A18X+176592Y+002203X0260Y         S2      
017m5009                  -    MD0100PA00X+176592Y+002203                       
327m5010            J38   -OA8        A01X+176520Y+003276X0150Y0570R180 S1      
317m5010            VIA   -    MD0100PA00X+176598Y+002703X0200Y         S0      
327m5010            U7    -3          A18X+084158Y+027630X0140Y0590R090 S2      
317m5010            VIA   -    M      A01X+083618Y+027569X0300Y         S1      
017m5010            VIA   -    M      A18X+083618Y+027569X0200Y         S1      
017m5010                  -    MD0100PA00X+083618Y+027569                       
317m5011            VIA   -    M      A01X+176592Y+001703X0200Y         S2      
017m5011            VIA   -    M      A18X+176592Y+001703X0260Y         S2      
017m5011                  -    MD0100PA00X+176592Y+001703                       
327m5011            J38   -OA9        A01X+176284Y+003276X0150Y0570R180 S1      
327m5011            U7    -6          A18X+084158Y+026862X0140Y0590R090 S2      
317m5011            VIA   -    MD0100PA00X+083630Y+026862X0200Y         S0      
317m5012            VIA   -    M      A01X+176553Y+005369X0200Y         S2      
017m5012            VIA   -    M      A18X+176553Y+005369X0260Y         S2      
017m5012                  -    MD0100PA00X+176553Y+005369                       
327m5012            J38   -OB8        A01X+176520Y+004437X0150Y0570R180 S1      
317m5012            VIA   -    MD0100PA00X+079386Y+030532X0200Y         S0      
327m5012            U67   -3          A18X+078798Y+030647X0140Y0590R090 S2      
327m5013            J38   -OB9        A01X+176284Y+004437X0150Y0570R180 S1      
317m5013            VIA   -    MD0100PA00X+176301Y+005122X0200Y         S0      
327m5013            U67   -6          A18X+078798Y+029879X0140Y0590R090 S2      
317m5013            VIA   -    M      A01X+079322Y+029606X0300Y         S1      
017m5013            VIA   -    M      A18X+079322Y+029606X0200Y         S1      
017m5013                  -    MD0100PA00X+079322Y+029606                       
327m5014            J38   -OB14       A01X+175103Y+004437X0150Y0570R180 S1      
317m5014            VIA   -    M      A01X+175103Y+003906X0200Y         S2      
017m5014            VIA   -    M      A18X+175103Y+003906X0260Y         S2      
017m5014                  -    MD0100PA00X+175103Y+003906                       
317m5014            VIA   -    MD0100PA00X+076979Y+029623X0200Y         S0      
327m5014            U67   -8          A18X+076498Y+029623X0140Y0590R090 S2      
327m5015            R3213 -1          A18X+075745Y+027340X0198Y0197     S2      
327m5015            VIA   -    M      A18X+076205Y+027403X0260Y    R090 S2      
327m5015            U223  -9          A18X+076990Y+027403X0140Y0590R090 S2      
327m5016            VIA   -    M      A18X+081120Y+026862X0260Y         S2      
327m5016            U7    -9          A18X+081858Y+026862X0140Y0590R090 S2      
327m5016            R74   -1          A18X+080645Y+026862X0198Y0197     S2      
327m5017            VIA   -    M      A18X+080230Y+028431X0260Y         S2      
327m5017            R3215 -1          A18X+080704Y+028431X0198Y0197R180 S2      
327m5017            U223  -2          A18X+079290Y+028426X0140Y0590R090 S2      
327m5018            R76   -1          A18X+085008Y+028760X0198Y0197     S2      
327m5018            VIA   -    M      A18X+084961Y+028238X0260Y         S2      
327m5018            U7    -2          A18X+084158Y+027886X0140Y0590R090 S2      
327m5019            VIA   -    M      A18X+080242Y+027532X0260Y         S2      
327m5019            U223  -5          A18X+079290Y+027659X0140Y0590R090 S2      
327m5019            R3214 -1          A18X+080699Y+027682X0198Y0197R180 S2      
327m5020            R75   -1          A18X+085493Y+027356X0198Y0197R180 S2      
327m5020            VIA   -    M      A18X+085033Y+027356X0260Y         S2      
327m5020            U7    -5          A18X+084158Y+027118X0140Y0590R090 S2      
327m5021            VIA   -    M      A18X+084254Y+030931X0260Y    R180 S2      
327m5021            U222  -2          A18X+083550Y+030931X0140Y0590R090 S2      
327m5021            R3212 -1          A18X+084982Y+030885X0198Y0197R180 S2      
327m5022            R73   -1          A01X+078912Y+030876X0198Y0197R180 S1      
317m5022            VIA   -    M      A01X+079390Y+030903X0300Y         S1      
017m5022            VIA   -    M      A18X+079390Y+030903X0200Y         S1      
017m5022                  -    MD0100PA00X+079390Y+030903                       
327m5022            U67   -2          A18X+078798Y+030903X0140Y0590R090 S2      
327m5023            VIA   -    M      A18X+084254Y+030163X0260Y    R180 S2      
327m5023            U222  -5          A18X+083550Y+030163X0140Y0590R090 S2      
327m5023            R3211 -1          A18X+084966Y+030154X0198Y0197R180 S2      
327m5024            U67   -5          A18X+078798Y+030135X0140Y0590R090 S2      
327m5024            R72   -1          A01X+078920Y+030341X0198Y0197R180 S1      
317m5024            VIA   -    M      A01X+079406Y+030157X0300Y         S1      
017m5024            VIA   -    M      A18X+079406Y+030157X0200Y         S1      
017m5024                  -    MD0100PA00X+079406Y+030157                       
327m5025            U222  -9          A18X+081250Y+029907X0140Y0590R090 S2      
327m5025            VIA   -    M      A18X+080551Y+029885X0260Y         S2      
327m5025            R3210 -1          A18X+080108Y+029549X0198Y0197     S2      
327m5026            R59   -1          A01X+076367Y+029928X0198Y0197     S1      
327m5026            U67   -9          A18X+076498Y+029879X0140Y0590R090 S2      
317m5026            VIA   -    M      A01X+075851Y+029862X0200Y         S2      
017m5026            VIA   -    M      A18X+075851Y+029862X0260Y         S2      
017m5026                  -    MD0100PA00X+075851Y+029862                       
317m5027            VIA   -    MD0080PA01X+055041Y+105357X0160Y         S0      
327m5027            U26   -BP9        A01X+054857Y+105252X0177Y    R180 S1      
317m5027            VIA   -    MD0100PA01X+081200Y+106471X0190Y         S0      
327m5027            J37   -87         A01X+081200Y+106471X0205Y0590R090 S1      
317m5028            VIA   -    MD0080PA01X+054486Y+104400X0160Y         S0      
327m5028            U26   -BL10       A01X+054302Y+104295X0177Y    R180 S1      
317m5028            VIA   -    MD0100PA01X+079586Y+105132X0190Y         S0      
327m5028            J37   -227        A01X+079586Y+105132X0205Y0590R090 S1      
317m5029            VIA   -    MD0080PA01X+055041Y+106632X0160Y         S0      
327m5029            U26   -BV9        A01X+054857Y+106528X0177Y    R180 S1      
317m5029            VIA   -    MD0100PA01X+081200Y+108478X0190Y         S0      
327m5029            J37   -93         A01X+081200Y+108478X0205Y0590R090 S1      
317m5030            VIA   -    MD0080PA01X+054301Y+114924X0160Y         S0      
327m5030            U26   -DD11       A01X+054117Y+114819X0177Y    R180 S1      
317m5030            VIA   -    MD0100PA01X+079586Y+123872X0190Y         S0      
327m5030            J37   -283        A01X+079586Y+123872X0205Y0590R090 S1      
317m5031            VIA   -    MD0080PA01X+054301Y+113010X0160Y         S0      
327m5031            U26   -CV11       A01X+054117Y+112906X0177Y    R180 S1      
317m5031            VIA   -    MD0100PA01X+079586Y+120191X0190Y         S0      
327m5031            J37   -272        A01X+079586Y+120191X0205Y0590R090 S1      
317m5032            VIA   -    MD0080PA01X+054301Y+111097X0160Y         S0      
327m5032            U26   -CM11       A01X+054117Y+110992X0177Y    R180 S1      
317m5032            VIA   -    MD0100PA01X+079586Y+116510X0190Y         S0      
327m5032            J37   -261        A01X+079586Y+116510X0205Y0590R090 S1      
317m5033            VIA   -    MD0080PA01X+054301Y+109184X0160Y         S0      
327m5033            U26   -CF11       A01X+054117Y+109079X0177Y    R180 S1      
317m5033            VIA   -    MD0100PA01X+079586Y+112829X0190Y         S0      
327m5033            J37   -250        A01X+079586Y+112829X0205Y0590R090 S1      
317m5034            VIA   -    MD0080PA01X+054301Y+107270X0160Y         S0      
327m5034            U26   -BY11       A01X+054117Y+107166X0177Y    R180 S1      
317m5034            VIA   -    MD0100PA01X+079586Y+109148X0190Y         S0      
327m5034            J37   -239        A01X+079586Y+109148X0205Y0590R090 S1      
317m5035            VIA   -    MD0080PA01X+055041Y+114286X0160Y         S0      
327m5035            U26   -DB9        A01X+054857Y+114181X0177Y    R180 S1      
317m5035            VIA   -    MD0100PA01X+081200Y+123203X0190Y         S0      
327m5035            J37   -137        A01X+081200Y+123203X0205Y0590R090 S1      
317m5036            VIA   -    MD0080PA01X+055041Y+112373X0160Y         S0      
327m5036            U26   -CT9        A01X+054857Y+112268X0177Y    R180 S1      
317m5036            VIA   -    MD0100PA01X+081200Y+119522X0190Y         S0      
327m5036            J37   -126        A01X+081200Y+119522X0205Y0590R090 S1      
317m5037            VIA   -    MD0080PA01X+055041Y+110459X0160Y         S0      
327m5037            U26   -CK9        A01X+054857Y+110354X0177Y    R180 S1      
317m5037            VIA   -    MD0100PA01X+081200Y+115841X0190Y         S0      
327m5037            J37   -115        A01X+081200Y+115841X0205Y0590R090 S1      
317m5038            VIA   -    MD0080PA01X+055041Y+108546X0160Y         S0      
327m5038            U26   -CD9        A01X+054857Y+108441X0177Y    R180 S1      
317m5038            VIA   -    MD0100PA01X+081200Y+112160X0190Y         S0      
327m5038            J37   -104        A01X+081200Y+112160X0205Y0590R090 S1      
317m5039            VIA   -    MD0080PA01X+054856Y+106951X0160Y         S0      
327m5039            U26   -BW9        A01X+054672Y+106847X0177Y    R180 S1      
317m5039            VIA   -    MD0100PA01X+081200Y+108813X0190Y         S0      
327m5039            J37   -94         A01X+081200Y+108813X0205Y0590R090 S1      
317m5040            VIA   -    MD0080PA01X+054486Y+114605X0160Y         S0      
327m5040            U26   -DC10       A01X+054302Y+114500X0177Y    R180 S1      
317m5040            VIA   -    MD0100PA01X+079586Y+123538X0190Y         S0      
327m5040            J37   -282        A01X+079586Y+123538X0205Y0590R090 S1      
317m5041            VIA   -    MD0080PA01X+054486Y+112692X0160Y         S0      
327m5041            U26   -CU10       A01X+054302Y+112587X0177Y    R180 S1      
317m5041            VIA   -    MD0100PA01X+079586Y+119856X0190Y         S0      
327m5041            J37   -271        A01X+079586Y+119856X0205Y0590R090 S1      
317m5042            VIA   -    MD0080PA01X+054486Y+110778X0160Y         S0      
327m5042            U26   -CL10       A01X+054302Y+110673X0177Y    R180 S1      
317m5042            VIA   -    MD0100PA01X+079586Y+116175X0190Y         S0      
327m5042            J37   -260        A01X+079586Y+116175X0205Y0590R090 S1      
317m5043            VIA   -    MD0080PA01X+054486Y+108865X0160Y         S0      
327m5043            U26   -CE10       A01X+054302Y+108760X0177Y    R180 S1      
317m5043            VIA   -    MD0100PA01X+079586Y+112494X0190Y         S0      
327m5043            J37   -249        A01X+079586Y+112494X0205Y0590R090 S1      
317m5044            VIA   -    MD0080PA01X+054486Y+106951X0160Y         S0      
327m5044            U26   -BW10       A01X+054302Y+106847X0177Y    R180 S1      
317m5044            VIA   -    MD0100PA01X+079586Y+108813X0190Y         S0      
327m5044            J37   -238        A01X+079586Y+108813X0205Y0590R090 S1      
317m5045            VIA   -    MD0080PA01X+054856Y+114605X0160Y         S0      
327m5045            U26   -DC9        A01X+054672Y+114500X0177Y    R180 S1      
317m5045            VIA   -    MD0100PA01X+081200Y+123538X0190Y         S0      
327m5045            J37   -138        A01X+081200Y+123538X0205Y0590R090 S1      
317m5046            VIA   -    MD0080PA01X+054856Y+112692X0160Y         S0      
327m5046            U26   -CU9        A01X+054672Y+112587X0177Y    R180 S1      
317m5046            VIA   -    MD0100PA01X+081200Y+119856X0190Y         S0      
327m5046            J37   -127        A01X+081200Y+119856X0205Y0590R090 S1      
317m5047            VIA   -    MD0080PA01X+054856Y+110778X0160Y         S0      
327m5047            U26   -CL9        A01X+054672Y+110673X0177Y    R180 S1      
317m5047            VIA   -    MD0100PA01X+081200Y+116175X0190Y         S0      
327m5047            J37   -116        A01X+081200Y+116175X0205Y0590R090 S1      
317m5048            VIA   -    MD0080PA01X+054856Y+108865X0160Y         S0      
327m5048            U26   -CE9        A01X+054672Y+108760X0177Y    R180 S1      
317m5048            VIA   -    MD0100PA01X+081200Y+112494X0190Y         S0      
327m5048            J37   -105        A01X+081200Y+112494X0205Y0590R090 S1      
317m5049            VIA   -    MD0080PA01X+054486Y+110140X0160Y         S0      
327m5049            U26   -CJ10       A01X+054302Y+110036X0177Y    R180 S1      
317m5049            VIA   -    MD0100PA01X+081200Y+115171X0190Y         S0      
327m5049            J37   -113        A01X+081200Y+115171X0205Y0590R090 S1      
317m5050            VIA   -    MD0080PA01X+055041Y+109821X0160Y         S0      
327m5050            U26   -CH9        A01X+054857Y+109717X0177Y    R180 S1      
317m5050            VIA   -    MD0100PA01X+081200Y+114502X0190Y         S0      
327m5050            J37   -111        A01X+081200Y+114502X0205Y0590R090 S1      
317m5051            VIA   -    MD0080PA01X+054301Y+109821X0160Y         S0      
327m5051            U26   -CH11       A01X+054117Y+109717X0177Y    R180 S1      
317m5051            VIA   -    MD0100PA01X+079586Y+114168X0190Y         S0      
327m5051            J37   -254        A01X+079586Y+114168X0205Y0590R090 S1      
317m5052            VIA   -    MD0080PA01X+054856Y+109502X0160Y         S0      
327m5052            U26   -CG9        A01X+054672Y+109398X0177Y    R180 S1      
317m5052            VIA   -    MD0100PA01X+079586Y+113498X0190Y         S0      
327m5052            J37   -252        A01X+079586Y+113498X0205Y0590R090 S1      
317m5053            VIA   -    MD0080PA01X+054486Y+109502X0160Y         S0      
327m5053            U26   -CG10       A01X+054302Y+109398X0177Y    R180 S1      
317m5053            VIA   -    MD0100PA01X+081200Y+113833X0190Y         S0      
327m5053            J37   -109        A01X+081200Y+113833X0205Y0590R090 S1      
317m5054            VIA   -    MD0080PA01X+055041Y+109184X0160Y         S0      
327m5054            U26   -CF9        A01X+054857Y+109079X0177Y    R180 S1      
317m5054            VIA   -    MD0100PA01X+081200Y+113164X0190Y         S0      
327m5054            J37   -107        A01X+081200Y+113164X0205Y0590R090 S1      
317m5055            VIA   -    MD0080PA01X+054301Y+108546X0160Y         S0      
327m5055            U26   -CD11       A01X+054117Y+108441X0177Y    R180 S1      
317m5055            VIA   -    MD0100PA01X+079586Y+111825X0190Y         S0      
327m5055            J37   -247        A01X+079586Y+111825X0205Y0590R090 S1      
317m5056            VIA   -    MD0080PA01X+055041Y+115562X0160Y         S0      
327m5056            U26   -DF9        A01X+054857Y+115457X0177Y    R180 S1      
317m5056            VIA   -    MD0100PA01X+079586Y+125211X0190Y         S0      
327m5056            J37   -287        A01X+079586Y+125211X0205Y0590R090 S1      
317m5057            VIA   -    MD0080PA01X+054856Y+115243X0160Y         S0      
327m5057            U26   -DE9        A01X+054672Y+115138X0177Y    R180 S1      
317m5057            VIA   -    MD0100PA01X+079586Y+124542X0190Y         S0      
327m5057            J37   -285        A01X+079586Y+124542X0205Y0590R090 S1      
317m5058            VIA   -    MD0080PA01X+054856Y+108227X0160Y         S0      
327m5058            U26   -CC9        A01X+054672Y+108122X0177Y    R180 S1      
317m5058            VIA   -    MD0100PA01X+079586Y+111156X0190Y         S0      
327m5058            J37   -245        A01X+079586Y+111156X0205Y0590R090 S1      
317m5059            VIA   -    MD0080PA01X+054486Y+115243X0160Y         S0      
327m5059            U26   -DE10       A01X+054302Y+115138X0177Y    R180 S1      
317m5059            VIA   -    MD0100PA01X+081200Y+124876X0190Y         S0      
327m5059            J37   -142        A01X+081200Y+124876X0205Y0590R090 S1      
317m5060            VIA   -    MD0080PA01X+055041Y+114924X0160Y         S0      
327m5060            U26   -DD9        A01X+054857Y+114819X0177Y    R180 S1      
317m5060            VIA   -    MD0100PA01X+081200Y+124207X0190Y         S0      
327m5060            J37   -140        A01X+081200Y+124207X0205Y0590R090 S1      
317m5061            VIA   -    MD0080PA01X+054301Y+114286X0160Y         S0      
327m5061            U26   -DB11       A01X+054117Y+114181X0177Y    R180 S1      
317m5061            VIA   -    MD0100PA01X+079586Y+122868X0190Y         S0      
327m5061            J37   -280        A01X+079586Y+122868X0205Y0590R090 S1      
317m5062            VIA   -    MD0080PA01X+054856Y+113967X0160Y         S0      
327m5062            U26   -DA9        A01X+054672Y+113862X0177Y    R180 S1      
317m5062            VIA   -    MD0100PA01X+079586Y+122199X0190Y         S0      
327m5062            J37   -278        A01X+079586Y+122199X0205Y0590R090 S1      
317m5063            VIA   -    MD0080PA01X+054486Y+113967X0160Y         S0      
327m5063            U26   -DA10       A01X+054302Y+113862X0177Y    R180 S1      
317m5063            VIA   -    MD0100PA01X+081200Y+122534X0190Y         S0      
327m5063            J37   -135        A01X+081200Y+122534X0205Y0590R090 S1      
317m5064            VIA   -    MD0080PA01X+055041Y+113648X0160Y         S0      
327m5064            U26   -CY9        A01X+054857Y+113543X0177Y    R180 S1      
317m5064            VIA   -    MD0100PA01X+081200Y+121864X0190Y         S0      
327m5064            J37   -133        A01X+081200Y+121864X0205Y0590R090 S1      
317m5065            VIA   -    MD0080PA01X+054301Y+113648X0160Y         S0      
327m5065            U26   -CY11       A01X+054117Y+113543X0177Y    R180 S1      
317m5065            VIA   -    MD0100PA01X+079586Y+121530X0190Y         S0      
327m5065            J37   -276        A01X+079586Y+121530X0205Y0590R090 S1      
317m5066            VIA   -    MD0080PA01X+054856Y+113329X0160Y         S0      
327m5066            U26   -CW9        A01X+054672Y+113225X0177Y    R180 S1      
317m5066            VIA   -    MD0100PA01X+079586Y+120860X0190Y         S0      
327m5066            J37   -274        A01X+079586Y+120860X0205Y0590R090 S1      
317m5067            VIA   -    MD0080PA01X+054486Y+113329X0160Y         S0      
327m5067            U26   -CW10       A01X+054302Y+113225X0177Y    R180 S1      
317m5067            VIA   -    MD0100PA01X+081200Y+121195X0190Y         S0      
327m5067            J37   -131        A01X+081200Y+121195X0205Y0590R090 S1      
317m5068            VIA   -    MD0080PA01X+055041Y+113010X0160Y         S0      
327m5068            U26   -CV9        A01X+054857Y+112906X0177Y    R180 S1      
317m5068            VIA   -    MD0100PA01X+081200Y+120526X0190Y         S0      
327m5068            J37   -129        A01X+081200Y+120526X0205Y0590R090 S1      
317m5069            VIA   -    MD0080PA01X+054486Y+108227X0160Y         S0      
327m5069            U26   -CC10       A01X+054302Y+108122X0177Y    R180 S1      
317m5069            VIA   -    MD0100PA01X+081200Y+111490X0190Y         S0      
327m5069            J37   -102        A01X+081200Y+111490X0205Y0590R090 S1      
317m5070            VIA   -    MD0080PA01X+054301Y+112373X0160Y         S0      
327m5070            U26   -CT11       A01X+054117Y+112268X0177Y    R180 S1      
317m5070            VIA   -    MD0100PA01X+079586Y+119187X0190Y         S0      
327m5070            J37   -269        A01X+079586Y+119187X0205Y0590R090 S1      
317m5071            VIA   -    MD0080PA01X+054856Y+112054X0160Y         S0      
327m5071            U26   -CR9        A01X+054672Y+111949X0177Y    R180 S1      
317m5071            VIA   -    MD0100PA01X+079586Y+118518X0190Y         S0      
327m5071            J37   -267        A01X+079586Y+118518X0205Y0590R090 S1      
317m5072            VIA   -    MD0080PA01X+054486Y+112054X0160Y         S0      
327m5072            U26   -CR10       A01X+054302Y+111949X0177Y    R180 S1      
317m5072            VIA   -    MD0100PA01X+081200Y+118852X0190Y         S0      
327m5072            J37   -124        A01X+081200Y+118852X0205Y0590R090 S1      
317m5073            VIA   -    MD0080PA01X+055041Y+111735X0160Y         S0      
327m5073            U26   -CP9        A01X+054857Y+111630X0177Y    R180 S1      
317m5073            VIA   -    MD0100PA01X+081200Y+118183X0190Y         S0      
327m5073            J37   -122        A01X+081200Y+118183X0205Y0590R090 S1      
317m5074            VIA   -    MD0080PA01X+054301Y+111735X0160Y         S0      
327m5074            U26   -CP11       A01X+054117Y+111630X0177Y    R180 S1      
317m5074            VIA   -    MD0100PA01X+079586Y+117849X0190Y         S0      
327m5074            J37   -265        A01X+079586Y+117849X0205Y0590R090 S1      
317m5075            VIA   -    MD0080PA01X+054856Y+111416X0160Y         S0      
327m5075            U26   -CN9        A01X+054672Y+111311X0177Y    R180 S1      
317m5075            VIA   -    MD0100PA01X+079586Y+117179X0190Y         S0      
327m5075            J37   -263        A01X+079586Y+117179X0205Y0590R090 S1      
317m5076            VIA   -    MD0080PA01X+054486Y+111416X0160Y         S0      
327m5076            U26   -CN10       A01X+054302Y+111311X0177Y    R180 S1      
317m5076            VIA   -    MD0100PA01X+081200Y+117514X0190Y         S0      
327m5076            J37   -120        A01X+081200Y+117514X0205Y0590R090 S1      
317m5077            VIA   -    MD0080PA01X+055041Y+111097X0160Y         S0      
327m5077            U26   -CM9        A01X+054857Y+110992X0177Y    R180 S1      
317m5077            VIA   -    MD0100PA01X+081200Y+116845X0190Y         S0      
327m5077            J37   -118        A01X+081200Y+116845X0205Y0590R090 S1      
317m5078            VIA   -    MD0080PA01X+054301Y+110459X0160Y         S0      
327m5078            U26   -CK11       A01X+054117Y+110354X0177Y    R180 S1      
317m5078            VIA   -    MD0100PA01X+079586Y+115506X0190Y         S0      
327m5078            J37   -258        A01X+079586Y+115506X0205Y0590R090 S1      
317m5079            VIA   -    MD0080PA01X+054856Y+110140X0160Y         S0      
327m5079            U26   -CJ9        A01X+054672Y+110036X0177Y    R180 S1      
317m5079            VIA   -    MD0100PA01X+079586Y+114837X0190Y         S0      
327m5079            J37   -256        A01X+079586Y+114837X0205Y0590R090 S1      
317m5080            VIA   -    MD0080PA01X+055041Y+107908X0160Y         S0      
327m5080            U26   -CB9        A01X+054857Y+107803X0177Y    R180 S1      
317m5080            VIA   -    MD0100PA01X+081200Y+110821X0190Y         S0      
327m5080            J37   -100        A01X+081200Y+110821X0205Y0590R090 S1      
317m5081            VIA   -    MD0080PA01X+054856Y+105038X0160Y         S0      
327m5081            U26   -BN9        A01X+054672Y+104933X0177Y    R180 S1      
317m5081            VIA   -    MD0100PA01X+079586Y+105801X0190Y         S0      
327m5081            J37   -229        A01X+079586Y+105801X0205Y0590R090 S1      
317m5082            VIA   -    MD0080PA01X+054301Y+104719X0160Y         S0      
327m5082            U26   -BM11       A01X+054117Y+104614X0177Y    R180 S1      
317m5082            VIA   -    MD0100PA01X+081200Y+105467X0190Y         S0      
327m5082            J37   -84         A01X+081200Y+105467X0205Y0590R090 S1      
317m5083            VIA   -    MD0080PA01X+054301Y+106632X0160Y         S0      
327m5083            U26   -BV11       A01X+054117Y+106528X0177Y    R180 S1      
317m5083            VIA   -    MD0100PA01X+079586Y+108144X0190Y         S0      
327m5083            J37   -236        A01X+079586Y+108144X0205Y0590R090 S1      
317m5084            VIA   -    MD0080PA01X+054856Y+106314X0160Y         S0      
327m5084            U26   -BU9        A01X+054672Y+106209X0177Y    R180 S1      
317m5084            VIA   -    MD0100PA01X+079586Y+107474X0190Y         S0      
327m5084            J37   -234        A01X+079586Y+107474X0205Y0590R090 S1      
317m5085            VIA   -    MD0080PA01X+054486Y+106314X0160Y         S0      
327m5085            U26   -BU10       A01X+054302Y+106209X0177Y    R180 S1      
317m5085            VIA   -    MD0100PA01X+081200Y+107809X0190Y         S0      
327m5085            J37   -91         A01X+081200Y+107809X0205Y0590R090 S1      
317m5086            VIA   -    MD0080PA01X+055041Y+105995X0160Y         S0      
327m5086            U26   -BT9        A01X+054857Y+105890X0177Y    R180 S1      
317m5086            VIA   -    MD0100PA01X+081200Y+107140X0190Y         S0      
327m5086            J37   -89         A01X+081200Y+107140X0205Y0590R090 S1      
317m5087            VIA   -    MD0080PA01X+054301Y+107908X0160Y         S0      
327m5087            U26   -CB11       A01X+054117Y+107803X0177Y    R180 S1      
317m5087            VIA   -    MD0100PA01X+079586Y+110486X0190Y         S0      
327m5087            J37   -243        A01X+079586Y+110486X0205Y0590R090 S1      
317m5088            VIA   -    MD0080PA01X+054856Y+107589X0160Y         S0      
327m5088            U26   -CA9        A01X+054672Y+107484X0177Y    R180 S1      
317m5088            VIA   -    MD0100PA01X+079586Y+109817X0190Y         S0      
327m5088            J37   -241        A01X+079586Y+109817X0205Y0590R090 S1      
317m5089            VIA   -    MD0080PA01X+054486Y+107589X0160Y         S0      
327m5089            U26   -CA10       A01X+054302Y+107484X0177Y    R180 S1      
317m5089            VIA   -    MD0100PA01X+081200Y+110152X0190Y         S0      
327m5089            J37   -98         A01X+081200Y+110152X0205Y0590R090 S1      
317m5090            VIA   -    MD0080PA01X+055041Y+107270X0160Y         S0      
327m5090            U26   -BY9        A01X+054857Y+107166X0177Y    R180 S1      
317m5090            VIA   -    MD0100PA01X+081200Y+109482X0190Y         S0      
327m5090            J37   -96         A01X+081200Y+109482X0205Y0590R090 S1      
317m5091            VIA   -    MD0080PA01X+055041Y+104081X0160Y         S0      
327m5091            U26   -BK9        A01X+054857Y+103976X0177Y    R180 S1      
317m5091            VIA   -    MD0100PA01X+081200Y+104797X0190Y         S0      
327m5091            J37   -82         A01X+081200Y+104797X0205Y0590R090 S1      
317m5092            VIA   -    MD0080PA01X+054301Y+104081X0160Y         S0      
327m5092            U26   -BK11       A01X+054117Y+103976X0177Y    R180 S1      
317m5092            VIA   -    MD0100PA01X+079586Y+104463X0190Y         S0      
327m5092            J37   -225        A01X+079586Y+104463X0205Y0590R090 S1      
317m5093            VIA   -    MD0080PA01X+054486Y+103762X0160Y         S0      
327m5093            U26   -BJ10       A01X+054302Y+103658X0177Y    R180 S1      
317m5093            VIA   -    MD0100PA01X+081200Y+104128X0190Y         S0      
327m5093            J37   -80         A01X+081200Y+104128X0205Y0590R090 S1      
317m5094            VIA   -    MD0080PA01X+054856Y+103762X0160Y         S0      
327m5094            U26   -BJ9        A01X+054672Y+103658X0177Y    R180 S1      
317m5094            VIA   -    MD0100PA01X+079586Y+103793X0190Y         S0      
327m5094            J37   -223        A01X+079586Y+103793X0205Y0590R090 S1      
317m5095            VIA   -    MD0080PA01X+055041Y+103443X0160Y         S0      
327m5095            U26   -BH9        A01X+054857Y+103339X0177Y    R180 S1      
317m5095            VIA   -    MD0100PA01X+081200Y+103459X0190Y         S0      
327m5095            J37   -78         A01X+081200Y+103459X0205Y0590R090 S1      
317m5096            VIA   -    MD0080PA01X+054301Y+103443X0160Y         S0      
327m5096            U26   -BH11       A01X+054117Y+103339X0177Y    R180 S1      
317m5096            VIA   -    MD0100PA01X+079586Y+103124X0190Y         S0      
327m5096            J37   -221        A01X+079586Y+103124X0205Y0590R090 S1      
317m5097            VIA   -    MD0080PA01X+054486Y+103124X0160Y         S0      
327m5097            U26   -BG10       A01X+054302Y+103020X0177Y    R180 S1      
317m5097            VIA   -    MD0100PA01X+081200Y+102790X0190Y         S0      
327m5097            J37   -76         A01X+081200Y+102790X0205Y0590R090 S1      
317m5098            VIA   -    MD0080PA01X+054486Y+105038X0160Y         S0      
327m5098            U26   -BN10       A01X+054302Y+104933X0177Y    R180 S1      
317m5098            VIA   -    MD0100PA01X+081200Y+106136X0190Y         S0      
327m5098            J37   -86         A01X+081200Y+106136X0205Y0590R090 S1      
317m5099            VIA   -    MD0080PA01X+054368Y+100718X0160Y    R180 S0      
327m5099            U26   -BC10       A01X+054184Y+100823X0177Y    R180 S1      
317m5099            VIA   -    MD0100PA01X+081200Y+100112X0190Y         S0      
327m5099            J37   -74         A01X+081200Y+100112X0205Y0590R090 S1      
317m5100            VIA   -    MD0080PA01X+054368Y+097529X0160Y    R180 S0      
327m5100            U26   -AN10       A01X+054184Y+097634X0177Y    R180 S1      
317m5100            VIA   -    MD0100PA01X+079586Y+094423X0190Y         S0      
327m5100            J37   -201        A01X+079586Y+094423X0205Y0590R090 S1      
317m5101            VIA   -    MD0080PA01X+054368Y+095616X0160Y    R180 S0      
327m5101            U26   -AG10       A01X+054184Y+095721X0177Y    R180 S1      
317m5101            VIA   -    MD0100PA01X+079586Y+090742X0190Y         S0      
327m5101            J37   -190        A01X+079586Y+090742X0205Y0590R090 S1      
317m5102            VIA   -    MD0080PA01X+054368Y+093702X0160Y    R180 S0      
327m5102            U26   -AA10       A01X+054184Y+093807X0177Y    R180 S1      
317m5102            VIA   -    MD0100PA01X+079586Y+087061X0190Y         S0      
327m5102            J37   -179        A01X+079586Y+087061X0205Y0590R090 S1      
317m5103            VIA   -    MD0080PA01X+054368Y+091789X0160Y    R180 S0      
327m5103            U26   -R10        A01X+054184Y+091894X0177Y    R180 S1      
317m5103            VIA   -    MD0100PA01X+079586Y+083380X0190Y         S0      
327m5103            J37   -168        A01X+079586Y+083380X0205Y0590R090 S1      
317m5104            VIA   -    MD0080PA01X+054368Y+089876X0160Y    R180 S0      
327m5104            U26   -J10        A01X+054184Y+089980X0177Y    R180 S1      
317m5104            VIA   -    MD0100PA01X+079586Y+079699X0190Y         S0      
327m5104            J37   -157        A01X+079586Y+079699X0205Y0590R090 S1      
317m5105            VIA   -    MD0080PA01X+054738Y+096892X0160Y    R180 S0      
327m5105            U26   -AL9        A01X+054554Y+096996X0177Y    R180 S1      
317m5105            VIA   -    MD0100PA01X+081200Y+093754X0190Y         S0      
327m5105            J37   -55         A01X+081200Y+093754X0205Y0590R090 S1      
317m5106            VIA   -    MD0080PA01X+054738Y+094978X0160Y    R180 S0      
327m5106            U26   -AE9        A01X+054554Y+095083X0177Y    R180 S1      
317m5106            VIA   -    MD0100PA01X+081200Y+090073X0190Y         S0      
327m5106            J37   -44         A01X+081200Y+090073X0205Y0590R090 S1      
317m5107            VIA   -    MD0080PA01X+054738Y+093065X0160Y    R180 S0      
327m5107            U26   -W9         A01X+054554Y+093169X0177Y    R180 S1      
317m5107            VIA   -    MD0100PA01X+081200Y+086392X0190Y         S0      
327m5107            J37   -33         A01X+081200Y+086392X0205Y0590R090 S1      
317m5108            VIA   -    MD0080PA01X+054738Y+091151X0160Y    R180 S0      
327m5108            U26   -N9         A01X+054554Y+091256X0177Y    R180 S1      
317m5108            VIA   -    MD0100PA01X+081200Y+082711X0190Y         S0      
327m5108            J37   -22         A01X+081200Y+082711X0205Y0590R090 S1      
317m5109            VIA   -    MD0080PA01X+054738Y+089238X0160Y    R180 S0      
327m5109            U26   -G9         A01X+054554Y+089343X0177Y    R180 S1      
317m5109            VIA   -    MD0100PA01X+081200Y+079030X0190Y         S0      
327m5109            J37   -11         A01X+081200Y+079030X0205Y0590R090 S1      
317m5110            VIA   -    MD0080PA01X+054183Y+097210X0160Y    R180 S0      
327m5110            U26   -AM11       A01X+053999Y+097315X0177Y    R180 S1      
317m5110            VIA   -    MD0100PA01X+079586Y+094089X0190Y         S0      
327m5110            J37   -200        A01X+079586Y+094089X0205Y0590R090 S1      
317m5111            VIA   -    MD0080PA01X+054183Y+095297X0160Y    R180 S0      
327m5111            U26   -AF11       A01X+053999Y+095402X0177Y    R180 S1      
317m5111            VIA   -    MD0100PA01X+079586Y+090408X0190Y         S0      
327m5111            J37   -189        A01X+079586Y+090408X0205Y0590R090 S1      
317m5112            VIA   -    MD0080PA01X+054183Y+093384X0160Y    R180 S0      
327m5112            U26   -Y11        A01X+053999Y+093488X0177Y    R180 S1      
317m5112            VIA   -    MD0100PA01X+079586Y+086726X0190Y         S0      
327m5112            J37   -178        A01X+079586Y+086726X0205Y0590R090 S1      
317m5113            VIA   -    MD0080PA01X+054183Y+091470X0160Y    R180 S0      
327m5113            U26   -P11        A01X+053999Y+091575X0177Y    R180 S1      
317m5113            VIA   -    MD0100PA01X+079586Y+083045X0190Y         S0      
327m5113            J37   -167        A01X+079586Y+083045X0205Y0590R090 S1      
317m5114            VIA   -    MD0080PA01X+054183Y+089557X0160Y    R180 S0      
327m5114            U26   -H11        A01X+053999Y+089662X0177Y    R180 S1      
317m5114            VIA   -    MD0100PA01X+079586Y+079364X0190Y         S0      
327m5114            J37   -156        A01X+079586Y+079364X0205Y0590R090 S1      
317m5115            VIA   -    MD0080PA01X+054923Y+097210X0160Y    R180 S0      
327m5115            U26   -AM9        A01X+054739Y+097315X0177Y    R180 S1      
317m5115            VIA   -    MD0100PA01X+081200Y+094089X0190Y         S0      
327m5115            J37   -56         A01X+081200Y+094089X0205Y0590R090 S1      
317m5116            VIA   -    MD0080PA01X+054923Y+095297X0160Y    R180 S0      
327m5116            U26   -AF9        A01X+054739Y+095402X0177Y    R180 S1      
317m5116            VIA   -    MD0100PA01X+081200Y+090408X0190Y         S0      
327m5116            J37   -45         A01X+081200Y+090408X0205Y0590R090 S1      
317m5117            VIA   -    MD0080PA01X+054923Y+093384X0160Y    R180 S0      
327m5117            U26   -Y9         A01X+054739Y+093488X0177Y    R180 S1      
317m5117            VIA   -    MD0100PA01X+081200Y+086726X0190Y         S0      
327m5117            J37   -34         A01X+081200Y+086726X0205Y0590R090 S1      
317m5118            VIA   -    MD0080PA01X+054923Y+091470X0160Y    R180 S0      
327m5118            U26   -P9         A01X+054739Y+091575X0177Y    R180 S1      
317m5118            VIA   -    MD0100PA01X+081200Y+083045X0190Y         S0      
327m5118            J37   -23         A01X+081200Y+083045X0205Y0590R090 S1      
317m5119            VIA   -    MD0080PA01X+054923Y+089557X0160Y    R180 S0      
327m5119            U26   -H9         A01X+054739Y+089662X0177Y    R180 S1      
317m5119            VIA   -    MD0100PA01X+081200Y+079364X0190Y         S0      
327m5119            J37   -12         A01X+081200Y+079364X0205Y0590R090 S1      
317m5120            VIA   -    MD0080PA01X+054183Y+090832X0160Y    R180 S0      
327m5120            U26   -M11        A01X+053999Y+090937X0177Y    R180 S1      
317m5120            VIA   -    MD0100PA01X+081200Y+082042X0190Y         S0      
327m5120            J37   -20         A01X+081200Y+082042X0205Y0590R090 S1      
317m5121            VIA   -    MD0080PA01X+054738Y+090514X0160Y    R180 S0      
327m5121            U26   -L9         A01X+054554Y+090618X0177Y    R180 S1      
317m5121            VIA   -    MD0100PA01X+081200Y+081372X0190Y         S0      
327m5121            J37   -18         A01X+081200Y+081372X0205Y0590R090 S1      
317m5122            VIA   -    MD0080PA01X+054368Y+090514X0160Y    R180 S0      
327m5122            U26   -L10        A01X+054184Y+090618X0177Y    R180 S1      
317m5122            VIA   -    MD0100PA01X+079586Y+081038X0190Y         S0      
327m5122            J37   -161        A01X+079586Y+081038X0205Y0590R090 S1      
317m5123            VIA   -    MD0080PA01X+054923Y+090195X0160Y    R180 S0      
327m5123            U26   -K9         A01X+054739Y+090299X0177Y    R180 S1      
317m5123            VIA   -    MD0100PA01X+079586Y+080368X0190Y         S0      
327m5123            J37   -159        A01X+079586Y+080368X0205Y0590R090 S1      
317m5124            VIA   -    MD0080PA01X+054183Y+090195X0160Y    R180 S0      
327m5124            U26   -K11        A01X+053999Y+090299X0177Y    R180 S1      
317m5124            VIA   -    MD0100PA01X+081200Y+080703X0190Y         S0      
327m5124            J37   -16         A01X+081200Y+080703X0205Y0590R090 S1      
317m5125            VIA   -    MD0080PA01X+054738Y+089876X0160Y    R180 S0      
327m5125            U26   -J9         A01X+054554Y+089980X0177Y    R180 S1      
317m5125            VIA   -    MD0100PA01X+081200Y+080034X0190Y         S0      
327m5125            J37   -14         A01X+081200Y+080034X0205Y0590R090 S1      
317m5126            VIA   -    MD0080PA01X+054368Y+089238X0160Y    R180 S0      
327m5126            U26   -G10        A01X+054184Y+089343X0177Y    R180 S1      
317m5126            VIA   -    MD0100PA01X+079586Y+078695X0190Y         S0      
327m5126            J37   -154        A01X+079586Y+078695X0205Y0590R090 S1      
317m5127            VIA   -    MD0080PA01X+054368Y+096254X0160Y    R180 S0      
327m5127            U26   -AJ10       A01X+054184Y+096358X0177Y    R180 S1      
317m5127            VIA   -    MD0100PA01X+079586Y+092081X0190Y         S0      
327m5127            J37   -194        A01X+079586Y+092081X0205Y0590R090 S1      
317m5128            VIA   -    MD0080PA01X+054923Y+095935X0160Y    R180 S0      
327m5128            U26   -AH9        A01X+054739Y+096040X0177Y    R180 S1      
317m5128            VIA   -    MD0100PA01X+079586Y+091412X0190Y         S0      
327m5128            J37   -192        A01X+079586Y+091412X0205Y0590R090 S1      
317m5129            VIA   -    MD0080PA01X+054923Y+088919X0160Y    R180 S0      
327m5129            U26   -F9         A01X+054739Y+089024X0177Y    R180 S1      
317m5129            VIA   -    MD0100PA01X+079586Y+078026X0190Y         S0      
327m5129            J37   -152        A01X+079586Y+078026X0205Y0590R090 S1      
317m5130            VIA   -    MD0080PA01X+054183Y+095935X0160Y    R180 S0      
327m5130            U26   -AH11       A01X+053999Y+096040X0177Y    R180 S1      
317m5130            VIA   -    MD0100PA01X+081200Y+091746X0190Y         S0      
327m5130            J37   -49         A01X+081200Y+091746X0205Y0590R090 S1      
317m5131            VIA   -    MD0080PA01X+054738Y+095616X0160Y    R180 S0      
327m5131            U26   -AG9        A01X+054554Y+095721X0177Y    R180 S1      
317m5131            VIA   -    MD0100PA01X+081200Y+091077X0190Y         S0      
327m5131            J37   -47         A01X+081200Y+091077X0205Y0590R090 S1      
317m5132            VIA   -    MD0080PA01X+054368Y+094978X0160Y    R180 S0      
327m5132            U26   -AE10       A01X+054184Y+095083X0177Y    R180 S1      
317m5132            VIA   -    MD0100PA01X+079586Y+089738X0190Y         S0      
327m5132            J37   -187        A01X+079586Y+089738X0205Y0590R090 S1      
317m5133            VIA   -    MD0080PA01X+054923Y+094659X0160Y    R180 S0      
327m5133            U26   -AD9        A01X+054739Y+094764X0177Y    R180 S1      
317m5133            VIA   -    MD0100PA01X+079586Y+089069X0190Y         S0      
327m5133            J37   -185        A01X+079586Y+089069X0205Y0590R090 S1      
317m5134            VIA   -    MD0080PA01X+054183Y+094659X0160Y    R180 S0      
327m5134            U26   -AD11       A01X+053999Y+094764X0177Y    R180 S1      
317m5134            VIA   -    MD0100PA01X+081200Y+089404X0190Y         S0      
327m5134            J37   -42         A01X+081200Y+089404X0205Y0590R090 S1      
317m5135            VIA   -    MD0080PA01X+054738Y+094340X0160Y    R180 S0      
327m5135            U26   -AC9        A01X+054554Y+094445X0177Y    R180 S1      
317m5135            VIA   -    MD0100PA01X+081200Y+088734X0190Y         S0      
327m5135            J37   -40         A01X+081200Y+088734X0205Y0590R090 S1      
317m5136            VIA   -    MD0080PA01X+054368Y+094340X0160Y    R180 S0      
327m5136            U26   -AC10       A01X+054184Y+094445X0177Y    R180 S1      
317m5136            VIA   -    MD0100PA01X+079586Y+088400X0190Y         S0      
327m5136            J37   -183        A01X+079586Y+088400X0205Y0590R090 S1      
317m5137            VIA   -    MD0080PA01X+054923Y+094021X0160Y    R180 S0      
327m5137            U26   -AB9        A01X+054739Y+094126X0177Y    R180 S1      
317m5137            VIA   -    MD0100PA01X+079586Y+087730X0190Y         S0      
327m5137            J37   -181        A01X+079586Y+087730X0205Y0590R090 S1      
317m5138            VIA   -    MD0080PA01X+054183Y+094021X0160Y    R180 S0      
327m5138            U26   -AB11       A01X+053999Y+094126X0177Y    R180 S1      
317m5138            VIA   -    MD0100PA01X+081200Y+088065X0190Y         S0      
327m5138            J37   -38         A01X+081200Y+088065X0205Y0590R090 S1      
317m5139            VIA   -    MD0080PA01X+054738Y+093702X0160Y    R180 S0      
327m5139            U26   -AA9        A01X+054554Y+093807X0177Y    R180 S1      
317m5139            VIA   -    MD0100PA01X+081200Y+087396X0190Y         S0      
327m5139            J37   -36         A01X+081200Y+087396X0205Y0590R090 S1      
317m5140            VIA   -    MD0080PA01X+054183Y+088919X0160Y    R180 S0      
327m5140            U26   -F11        A01X+053999Y+089024X0177Y    R180 S1      
317m5140            VIA   -    MD0100PA01X+081200Y+078360X0190Y         S0      
327m5140            J37   -9          A01X+081200Y+078360X0205Y0590R090 S1      
317m5141            VIA   -    MD0080PA01X+054368Y+093065X0160Y    R180 S0      
327m5141            U26   -W10        A01X+054184Y+093169X0177Y    R180 S1      
317m5141            VIA   -    MD0100PA01X+079586Y+086057X0190Y         S0      
327m5141            J37   -176        A01X+079586Y+086057X0205Y0590R090 S1      
317m5142            VIA   -    MD0080PA01X+054923Y+092746X0160Y    R180 S0      
327m5142            U26   -V9         A01X+054739Y+092850X0177Y    R180 S1      
317m5142            VIA   -    MD0100PA01X+079586Y+085388X0190Y         S0      
327m5142            J37   -174        A01X+079586Y+085388X0205Y0590R090 S1      
317m5143            VIA   -    MD0080PA01X+054183Y+092746X0160Y    R180 S0      
327m5143            U26   -V11        A01X+053999Y+092850X0177Y    R180 S1      
317m5143            VIA   -    MD0100PA01X+081200Y+085723X0190Y         S0      
327m5143            J37   -31         A01X+081200Y+085723X0205Y0590R090 S1      
317m5144            VIA   -    MD0080PA01X+054738Y+092427X0160Y    R180 S0      
327m5144            U26   -U9         A01X+054554Y+092532X0177Y    R180 S1      
317m5144            VIA   -    MD0100PA01X+081200Y+085053X0190Y         S0      
327m5144            J37   -29         A01X+081200Y+085053X0205Y0590R090 S1      
317m5145            VIA   -    MD0080PA01X+054368Y+092427X0160Y    R180 S0      
327m5145            U26   -U10        A01X+054184Y+092532X0177Y    R180 S1      
317m5145            VIA   -    MD0100PA01X+079586Y+084719X0190Y         S0      
327m5145            J37   -172        A01X+079586Y+084719X0205Y0590R090 S1      
317m5146            VIA   -    MD0080PA01X+054923Y+092108X0160Y    R180 S0      
327m5146            U26   -T9         A01X+054739Y+092213X0177Y    R180 S1      
317m5146            VIA   -    MD0100PA01X+079586Y+084049X0190Y         S0      
327m5146            J37   -170        A01X+079586Y+084049X0205Y0590R090 S1      
317m5147            VIA   -    MD0080PA01X+054183Y+092108X0160Y    R180 S0      
327m5147            U26   -T11        A01X+053999Y+092213X0177Y    R180 S1      
317m5147            VIA   -    MD0100PA01X+081200Y+084384X0190Y         S0      
327m5147            J37   -27         A01X+081200Y+084384X0205Y0590R090 S1      
317m5148            VIA   -    MD0080PA01X+054738Y+091789X0160Y    R180 S0      
327m5148            U26   -R9         A01X+054554Y+091894X0177Y    R180 S1      
317m5148            VIA   -    MD0100PA01X+081200Y+083715X0190Y         S0      
327m5148            J37   -25         A01X+081200Y+083715X0205Y0590R090 S1      
317m5149            VIA   -    MD0080PA01X+054368Y+091151X0160Y    R180 S0      
327m5149            U26   -N10        A01X+054184Y+091256X0177Y    R180 S1      
317m5149            VIA   -    MD0100PA01X+079586Y+082376X0190Y         S0      
327m5149            J37   -165        A01X+079586Y+082376X0205Y0590R090 S1      
317m5150            VIA   -    MD0080PA01X+054923Y+090832X0160Y    R180 S0      
327m5150            U26   -M9         A01X+054739Y+090937X0177Y    R180 S1      
317m5150            VIA   -    MD0100PA01X+079586Y+081707X0190Y         S0      
327m5150            J37   -163        A01X+079586Y+081707X0205Y0590R090 S1      
317m5151            VIA   -    MD0080PA01X+054738Y+088600X0160Y    R180 S0      
327m5151            U26   -E9         A01X+054554Y+088705X0177Y    R180 S1      
317m5151            VIA   -    MD0100PA01X+081200Y+077691X0190Y         S0      
327m5151            J37   -7          A01X+081200Y+077691X0205Y0590R090 S1      
317m5152            VIA   -    MD0080PA01X+054183Y+099124X0160Y    R180 S0      
327m5152            U26   -AV11       A01X+053999Y+099228X0177Y    R180 S1      
317m5152            VIA   -    MD0100PA01X+079586Y+097100X0190Y         S0      
327m5152            J37   -209        A01X+079586Y+097100X0205Y0590R090 S1      
317m5153            VIA   -    MD0080PA01X+054738Y+098805X0160Y    R180 S0      
327m5153            U26   -AU9        A01X+054554Y+098910X0177Y    R180 S1      
317m5153            VIA   -    MD0100PA01X+081200Y+096766X0190Y         S0      
327m5153            J37   -64         A01X+081200Y+096766X0205Y0590R090 S1      
317m5154            VIA   -    MD0080PA01X+054368Y+098167X0160Y    R180 S0      
327m5154            U26   -AR10       A01X+054184Y+098272X0177Y    R180 S1      
317m5154            VIA   -    MD0100PA01X+079586Y+095762X0190Y         S0      
327m5154            J37   -205        A01X+079586Y+095762X0205Y0590R090 S1      
317m5155            VIA   -    MD0080PA01X+054923Y+097848X0160Y    R180 S0      
327m5155            U26   -AP9        A01X+054739Y+097953X0177Y    R180 S1      
317m5155            VIA   -    MD0100PA01X+079586Y+095093X0190Y         S0      
327m5155            J37   -203        A01X+079586Y+095093X0205Y0590R090 S1      
317m5156            VIA   -    MD0080PA01X+054183Y+097848X0160Y    R180 S0      
327m5156            U26   -AP11       A01X+053999Y+097953X0177Y    R180 S1      
317m5156            VIA   -    MD0100PA01X+081200Y+095427X0190Y         S0      
327m5156            J37   -60         A01X+081200Y+095427X0205Y0590R090 S1      
317m5157            VIA   -    MD0080PA01X+054738Y+097529X0160Y    R180 S0      
327m5157            U26   -AN9        A01X+054554Y+097634X0177Y    R180 S1      
317m5157            VIA   -    MD0100PA01X+081200Y+094758X0190Y         S0      
327m5157            J37   -58         A01X+081200Y+094758X0205Y0590R090 S1      
317m5158            VIA   -    MD0080PA01X+054368Y+096892X0160Y    R180 S0      
327m5158            U26   -AL10       A01X+054184Y+096996X0177Y    R180 S1      
317m5158            VIA   -    MD0100PA01X+079586Y+093419X0190Y         S0      
327m5158            J37   -198        A01X+079586Y+093419X0205Y0590R090 S1      
317m5159            VIA   -    MD0080PA01X+054923Y+096573X0160Y    R180 S0      
327m5159            U26   -AK9        A01X+054739Y+096677X0177Y    R180 S1      
317m5159            VIA   -    MD0100PA01X+079586Y+092750X0190Y         S0      
327m5159            J37   -196        A01X+079586Y+092750X0205Y0590R090 S1      
317m5160            VIA   -    MD0080PA01X+054183Y+096573X0160Y    R180 S0      
327m5160            U26   -AK11       A01X+053999Y+096677X0177Y    R180 S1      
317m5160            VIA   -    MD0100PA01X+081200Y+093085X0190Y         S0      
327m5160            J37   -53         A01X+081200Y+093085X0205Y0590R090 S1      
317m5161            VIA   -    MD0080PA01X+054738Y+096254X0160Y    R180 S0      
327m5161            U26   -AJ9        A01X+054554Y+096358X0177Y    R180 S1      
317m5161            VIA   -    MD0100PA01X+081200Y+092416X0190Y         S0      
327m5161            J37   -51         A01X+081200Y+092416X0205Y0590R090 S1      
317m5162            VIA   -    MD0080PA01X+054183Y+100399X0160Y    R180 S0      
327m5162            U26   -BB11       A01X+053999Y+100504X0177Y    R180 S1      
317m5162            VIA   -    MD0100PA01X+081200Y+099443X0190Y         S0      
327m5162            J37   -72         A01X+081200Y+099443X0205Y0590R090 S1      
317m5163            VIA   -    MD0080PA01X+054923Y+100399X0160Y    R180 S0      
327m5163            U26   -BB9        A01X+054739Y+100504X0177Y    R180 S1      
317m5163            VIA   -    MD0100PA01X+079586Y+099108X0190Y         S0      
327m5163            J37   -215        A01X+079586Y+099108X0205Y0590R090 S1      
317m5164            VIA   -    MD0080PA01X+054738Y+100080X0160Y    R180 S0      
327m5164            U26   -BA9        A01X+054554Y+100185X0177Y    R180 S1      
317m5164            VIA   -    MD0100PA01X+081200Y+098774X0190Y         S0      
327m5164            J37   -70         A01X+081200Y+098774X0205Y0590R090 S1      
317m5165            VIA   -    MD0080PA01X+054368Y+100080X0160Y    R180 S0      
327m5165            U26   -BA10       A01X+054184Y+100185X0177Y    R180 S1      
317m5165            VIA   -    MD0100PA01X+079586Y+098439X0190Y         S0      
327m5165            J37   -213        A01X+079586Y+098439X0205Y0590R090 S1      
317m5166            VIA   -    MD0080PA01X+054183Y+099762X0160Y    R180 S0      
327m5166            U26   -AY11       A01X+053999Y+099866X0177Y    R180 S1      
317m5166            VIA   -    MD0100PA01X+081200Y+098104X0190Y         S0      
327m5166            J37   -68         A01X+081200Y+098104X0205Y0590R090 S1      
317m5167            VIA   -    MD0080PA01X+054923Y+099762X0160Y    R180 S0      
327m5167            U26   -AY9        A01X+054739Y+099866X0177Y    R180 S1      
317m5167            VIA   -    MD0100PA01X+079586Y+097770X0190Y         S0      
327m5167            J37   -211        A01X+079586Y+097770X0205Y0590R090 S1      
317m5168            VIA   -    MD0080PA01X+054738Y+099443X0160Y    R180 S0      
327m5168            U26   -AW9        A01X+054554Y+099547X0177Y    R180 S1      
317m5168            VIA   -    MD0100PA01X+081200Y+097435X0190Y         S0      
327m5168            J37   -66         A01X+081200Y+097435X0205Y0590R090 S1      
317m5169            VIA   -    MD0080PA01X+054368Y+098805X0160Y    R180 S0      
327m5169            U26   -AU10       A01X+054184Y+098910X0177Y    R180 S1      
317m5169            VIA   -    MD0100PA01X+079586Y+096431X0190Y         S0      
327m5169            J37   -207        A01X+079586Y+096431X0205Y0590R090 S1      
317m5170            VIA   -    MD0080PA01X+054738Y+100718X0160Y    R180 S0      
327m5170            U26   -BC9        A01X+054554Y+100823X0177Y    R180 S1      
317m5170            VIA   -    MD0100PA01X+079586Y+099778X0190Y         S0      
327m5170            J37   -217        A01X+079586Y+099778X0205Y0590R090 S1      
317m5171            VIA   -    MD0080PA01X+054923Y+101037X0160Y    R180 S0      
327m5171            U26   -BD9        A01X+054739Y+101142X0177Y    R180 S1      
317m5171            VIA   -    MD0100PA01X+079586Y+100112X0190Y         S0      
327m5171            J37   -218        A01X+079586Y+100112X0205Y0590R090 S1      
317m5172            VIA   -    MD0080PA01X+054183Y+098486X0160Y    R180 S0      
327m5172            U26   -AT11       A01X+053999Y+098591X0177Y    R180 S1      
317m5172            VIA   -    MD0100PA18X+080650Y+096097X0190Y         S0      
327m5172            R511  -2          A18X+080650Y+096097X0198Y0197     S2      
327m5173            J37   -62         A01X+081200Y+096097X0205Y0590R090 S1      
317m5173            VIA   -    MD0100PA00X+081200Y+096097X0190Y         S0      
327m5173            R511  -1          A18X+080965Y+096097X0198Y0197     S2      
317m5174            VIA   -    MD0080PA01X+152655Y+105357X0160Y         S0      
327m5174            U25   -BP9        A01X+152472Y+105252X0177Y    R180 S1      
317m5174            VIA   -    MD0100PA01X+178814Y+106470X0190Y         S0      
327m5174            J67   -87         A01X+178814Y+106470X0205Y0590R090 S1      
317m5175            VIA   -    MD0080PA01X+152100Y+104400X0160Y         S0      
327m5175            U25   -BL10       A01X+151916Y+104295X0177Y    R180 S1      
317m5175            VIA   -    MD0100PA01X+177200Y+105132X0190Y         S0      
327m5175            J67   -227        A01X+177200Y+105132X0205Y0590R090 S1      
317m5176            VIA   -    MD0080PA01X+152655Y+106632X0160Y         S0      
327m5176            U25   -BV9        A01X+152472Y+106528X0177Y    R180 S1      
317m5176            VIA   -    MD0100PA01X+178814Y+108478X0190Y         S0      
327m5176            J67   -93         A01X+178814Y+108478X0205Y0590R090 S1      
317m5177            VIA   -    MD0080PA01X+151915Y+114924X0160Y         S0      
327m5177            U25   -DD11       A01X+151732Y+114819X0177Y    R180 S1      
317m5177            VIA   -    MD0100PA01X+177200Y+123872X0190Y         S0      
327m5177            J67   -283        A01X+177200Y+123872X0205Y0590R090 S1      
317m5178            VIA   -    MD0080PA01X+151915Y+113010X0160Y         S0      
327m5178            U25   -CV11       A01X+151732Y+112906X0177Y    R180 S1      
317m5178            VIA   -    MD0100PA01X+177200Y+120191X0190Y         S0      
327m5178            J67   -272        A01X+177200Y+120191X0205Y0590R090 S1      
317m5179            VIA   -    MD0080PA01X+151915Y+111097X0160Y         S0      
327m5179            U25   -CM11       A01X+151732Y+110992X0177Y    R180 S1      
317m5179            VIA   -    MD0100PA01X+177200Y+116510X0190Y         S0      
327m5179            J67   -261        A01X+177200Y+116510X0205Y0590R090 S1      
317m5180            VIA   -    MD0080PA01X+151915Y+109184X0160Y         S0      
327m5180            U25   -CF11       A01X+151732Y+109079X0177Y    R180 S1      
317m5180            VIA   -    MD0100PA01X+177200Y+112829X0190Y         S0      
327m5180            J67   -250        A01X+177200Y+112829X0205Y0590R090 S1      
317m5181            VIA   -    MD0080PA01X+151915Y+107270X0160Y         S0      
327m5181            U25   -BY11       A01X+151732Y+107165X0177Y    R180 S1      
317m5181            VIA   -    MD0100PA01X+177200Y+109148X0190Y         S0      
327m5181            J67   -239        A01X+177200Y+109148X0205Y0590R090 S1      
317m5182            VIA   -    MD0080PA01X+152655Y+114286X0160Y         S0      
327m5182            U25   -DB9        A01X+152472Y+114181X0177Y    R180 S1      
317m5182            VIA   -    MD0100PA01X+178814Y+123203X0190Y         S0      
327m5182            J67   -137        A01X+178814Y+123203X0205Y0590R090 S1      
317m5183            VIA   -    MD0080PA01X+152655Y+112372X0160Y         S0      
327m5183            U25   -CT9        A01X+152472Y+112268X0177Y    R180 S1      
317m5183            VIA   -    MD0100PA01X+178814Y+119522X0190Y         S0      
327m5183            J67   -126        A01X+178814Y+119522X0205Y0590R090 S1      
317m5184            VIA   -    MD0080PA01X+152655Y+110459X0160Y         S0      
327m5184            U25   -CK9        A01X+152472Y+110354X0177Y    R180 S1      
317m5184            VIA   -    MD0100PA01X+178814Y+115841X0190Y         S0      
327m5184            J67   -115        A01X+178814Y+115841X0205Y0590R090 S1      
317m5185            VIA   -    MD0080PA01X+152655Y+108546X0160Y         S0      
327m5185            U25   -CD9        A01X+152472Y+108441X0177Y    R180 S1      
317m5185            VIA   -    MD0100PA01X+178814Y+112160X0190Y         S0      
327m5185            J67   -104        A01X+178814Y+112160X0205Y0590R090 S1      
317m5186            VIA   -    MD0080PA01X+152470Y+106951X0160Y         S0      
327m5186            U25   -BW9        A01X+152287Y+106846X0177Y    R180 S1      
317m5186            VIA   -    MD0100PA01X+178814Y+108813X0190Y         S0      
327m5186            J67   -94         A01X+178814Y+108813X0205Y0590R090 S1      
317m5187            VIA   -    MD0080PA01X+152100Y+114605X0160Y         S0      
327m5187            U25   -DC10       A01X+151916Y+114500X0177Y    R180 S1      
317m5187            VIA   -    MD0100PA01X+177200Y+123537X0190Y         S0      
327m5187            J67   -282        A01X+177200Y+123537X0205Y0590R090 S1      
317m5188            VIA   -    MD0080PA01X+152100Y+112691X0160Y         S0      
327m5188            U25   -CU10       A01X+151916Y+112587X0177Y    R180 S1      
317m5188            VIA   -    MD0100PA01X+177200Y+119856X0190Y         S0      
327m5188            J67   -271        A01X+177200Y+119856X0205Y0590R090 S1      
317m5189            VIA   -    MD0080PA01X+152100Y+110778X0160Y         S0      
327m5189            U25   -CL10       A01X+151916Y+110673X0177Y    R180 S1      
317m5189            VIA   -    MD0100PA01X+177200Y+116175X0190Y         S0      
327m5189            J67   -260        A01X+177200Y+116175X0205Y0590R090 S1      
317m5190            VIA   -    MD0080PA01X+152100Y+108865X0160Y         S0      
327m5190            U25   -CE10       A01X+151916Y+108760X0177Y    R180 S1      
317m5190            VIA   -    MD0100PA01X+177200Y+112494X0190Y         S0      
327m5190            J67   -249        A01X+177200Y+112494X0205Y0590R090 S1      
317m5191            VIA   -    MD0080PA01X+152100Y+106951X0160Y         S0      
327m5191            U25   -BW10       A01X+151916Y+106846X0177Y    R180 S1      
317m5191            VIA   -    MD0100PA01X+177200Y+108813X0190Y         S0      
327m5191            J67   -238        A01X+177200Y+108813X0205Y0590R090 S1      
317m5192            VIA   -    MD0080PA01X+152470Y+114605X0160Y         S0      
327m5192            U25   -DC9        A01X+152287Y+114500X0177Y    R180 S1      
317m5192            VIA   -    MD0100PA01X+178814Y+123537X0190Y         S0      
327m5192            J67   -138        A01X+178814Y+123537X0205Y0590R090 S1      
317m5193            VIA   -    MD0080PA01X+152470Y+112691X0160Y         S0      
327m5193            U25   -CU9        A01X+152287Y+112587X0177Y    R180 S1      
317m5193            VIA   -    MD0100PA01X+178814Y+119856X0190Y         S0      
327m5193            J67   -127        A01X+178814Y+119856X0205Y0590R090 S1      
317m5194            VIA   -    MD0080PA01X+152470Y+110778X0160Y         S0      
327m5194            U25   -CL9        A01X+152287Y+110673X0177Y    R180 S1      
317m5194            VIA   -    MD0100PA01X+178814Y+116175X0190Y         S0      
327m5194            J67   -116        A01X+178814Y+116175X0205Y0590R090 S1      
317m5195            VIA   -    MD0080PA01X+152470Y+108865X0160Y         S0      
327m5195            U25   -CE9        A01X+152287Y+108760X0177Y    R180 S1      
317m5195            VIA   -    MD0100PA01X+178814Y+112494X0190Y         S0      
327m5195            J67   -105        A01X+178814Y+112494X0205Y0590R090 S1      
317m5196            VIA   -    MD0080PA01X+152100Y+110140X0160Y         S0      
327m5196            U25   -CJ10       A01X+151916Y+110036X0177Y    R180 S1      
317m5196            VIA   -    MD0100PA01X+178814Y+115171X0190Y         S0      
327m5196            J67   -113        A01X+178814Y+115171X0205Y0590R090 S1      
317m5197            VIA   -    MD0080PA01X+152655Y+109821X0160Y         S0      
327m5197            U25   -CH9        A01X+152472Y+109717X0177Y    R180 S1      
317m5197            VIA   -    MD0100PA01X+178814Y+114502X0190Y         S0      
327m5197            J67   -111        A01X+178814Y+114502X0205Y0590R090 S1      
317m5198            VIA   -    MD0080PA01X+151915Y+109821X0160Y         S0      
327m5198            U25   -CH11       A01X+151732Y+109717X0177Y    R180 S1      
317m5198            VIA   -    MD0100PA01X+177200Y+114167X0190Y         S0      
327m5198            J67   -254        A01X+177200Y+114167X0205Y0590R090 S1      
317m5199            VIA   -    MD0080PA01X+152470Y+109502X0160Y         S0      
327m5199            U25   -CG9        A01X+152287Y+109398X0177Y    R180 S1      
317m5199            VIA   -    MD0100PA01X+177200Y+113498X0190Y         S0      
327m5199            J67   -252        A01X+177200Y+113498X0205Y0590R090 S1      
317m5200            VIA   -    MD0080PA01X+152100Y+109502X0160Y         S0      
327m5200            U25   -CG10       A01X+151916Y+109398X0177Y    R180 S1      
317m5200            VIA   -    MD0100PA01X+178814Y+113833X0190Y         S0      
327m5200            J67   -109        A01X+178814Y+113833X0205Y0590R090 S1      
317m5201            VIA   -    MD0080PA01X+152655Y+109184X0160Y         S0      
327m5201            U25   -CF9        A01X+152472Y+109079X0177Y    R180 S1      
317m5201            VIA   -    MD0100PA01X+178814Y+113163X0190Y         S0      
327m5201            J67   -107        A01X+178814Y+113163X0205Y0590R090 S1      
317m5202            VIA   -    MD0080PA01X+151915Y+108546X0160Y         S0      
327m5202            U25   -CD11       A01X+151732Y+108441X0177Y    R180 S1      
317m5202            VIA   -    MD0100PA01X+177200Y+111825X0190Y         S0      
327m5202            J67   -247        A01X+177200Y+111825X0205Y0590R090 S1      
317m5203            VIA   -    MD0080PA01X+152655Y+115561X0160Y         S0      
327m5203            U25   -DF9        A01X+152472Y+115457X0177Y    R180 S1      
317m5203            VIA   -    MD0100PA01X+177200Y+125211X0190Y         S0      
327m5203            J67   -287        A01X+177200Y+125211X0205Y0590R090 S1      
317m5204            VIA   -    MD0080PA01X+152470Y+115242X0160Y         S0      
327m5204            U25   -DE9        A01X+152287Y+115138X0177Y    R180 S1      
317m5204            VIA   -    MD0100PA01X+177200Y+124541X0190Y         S0      
327m5204            J67   -285        A01X+177200Y+124541X0205Y0590R090 S1      
317m5205            VIA   -    MD0080PA01X+152470Y+108227X0160Y         S0      
327m5205            U25   -CC9        A01X+152287Y+108122X0177Y    R180 S1      
317m5205            VIA   -    MD0100PA01X+177200Y+111156X0190Y         S0      
327m5205            J67   -245        A01X+177200Y+111156X0205Y0590R090 S1      
317m5206            VIA   -    MD0080PA01X+152100Y+115242X0160Y         S0      
327m5206            U25   -DE10       A01X+151916Y+115138X0177Y    R180 S1      
317m5206            VIA   -    MD0100PA01X+178814Y+124876X0190Y         S0      
327m5206            J67   -142        A01X+178814Y+124876X0205Y0590R090 S1      
317m5207            VIA   -    MD0080PA01X+152655Y+114924X0160Y         S0      
327m5207            U25   -DD9        A01X+152472Y+114819X0177Y    R180 S1      
317m5207            VIA   -    MD0100PA01X+178814Y+124207X0190Y         S0      
327m5207            J67   -140        A01X+178814Y+124207X0205Y0590R090 S1      
317m5208            VIA   -    MD0080PA01X+151915Y+114286X0160Y         S0      
327m5208            U25   -DB11       A01X+151732Y+114181X0177Y    R180 S1      
317m5208            VIA   -    MD0100PA01X+177200Y+122868X0190Y         S0      
327m5208            J67   -280        A01X+177200Y+122868X0205Y0590R090 S1      
317m5209            VIA   -    MD0080PA01X+152470Y+113967X0160Y         S0      
327m5209            U25   -DA9        A01X+152287Y+113862X0177Y    R180 S1      
317m5209            VIA   -    MD0100PA01X+177200Y+122199X0190Y         S0      
327m5209            J67   -278        A01X+177200Y+122199X0205Y0590R090 S1      
317m5210            VIA   -    MD0080PA01X+152100Y+113967X0160Y         S0      
327m5210            U25   -DA10       A01X+151916Y+113862X0177Y    R180 S1      
317m5210            VIA   -    MD0100PA01X+178814Y+122534X0190Y         S0      
327m5210            J67   -135        A01X+178814Y+122534X0205Y0590R090 S1      
317m5211            VIA   -    MD0080PA01X+152655Y+113648X0160Y         S0      
327m5211            U25   -CY9        A01X+152472Y+113543X0177Y    R180 S1      
317m5211            VIA   -    MD0100PA01X+178814Y+121864X0190Y         S0      
327m5211            J67   -133        A01X+178814Y+121864X0205Y0590R090 S1      
317m5212            VIA   -    MD0080PA01X+151915Y+113648X0160Y         S0      
327m5212            U25   -CY11       A01X+151732Y+113543X0177Y    R180 S1      
317m5212            VIA   -    MD0100PA01X+177200Y+121530X0190Y         S0      
327m5212            J67   -276        A01X+177200Y+121530X0205Y0590R090 S1      
317m5213            VIA   -    MD0080PA01X+152470Y+113329X0160Y         S0      
327m5213            U25   -CW9        A01X+152287Y+113224X0177Y    R180 S1      
317m5213            VIA   -    MD0100PA01X+177200Y+120860X0190Y         S0      
327m5213            J67   -274        A01X+177200Y+120860X0205Y0590R090 S1      
317m5214            VIA   -    MD0080PA01X+152100Y+113329X0160Y         S0      
327m5214            U25   -CW10       A01X+151916Y+113224X0177Y    R180 S1      
317m5214            VIA   -    MD0100PA01X+178814Y+121195X0190Y         S0      
327m5214            J67   -131        A01X+178814Y+121195X0205Y0590R090 S1      
317m5215            VIA   -    MD0080PA01X+152655Y+113010X0160Y         S0      
327m5215            U25   -CV9        A01X+152472Y+112906X0177Y    R180 S1      
317m5215            VIA   -    MD0100PA01X+178814Y+120526X0190Y         S0      
327m5215            J67   -129        A01X+178814Y+120526X0205Y0590R090 S1      
317m5216            VIA   -    MD0080PA01X+152100Y+108227X0160Y         S0      
327m5216            U25   -CC10       A01X+151916Y+108122X0177Y    R180 S1      
317m5216            VIA   -    MD0100PA01X+178814Y+111490X0190Y         S0      
327m5216            J67   -102        A01X+178814Y+111490X0205Y0590R090 S1      
317m5217            VIA   -    MD0080PA01X+151915Y+112372X0160Y         S0      
327m5217            U25   -CT11       A01X+151732Y+112268X0177Y    R180 S1      
317m5217            VIA   -    MD0100PA01X+177200Y+119187X0190Y         S0      
327m5217            J67   -269        A01X+177200Y+119187X0205Y0590R090 S1      
317m5218            VIA   -    MD0080PA01X+152470Y+112054X0160Y         S0      
327m5218            U25   -CR9        A01X+152287Y+111949X0177Y    R180 S1      
317m5218            VIA   -    MD0100PA01X+177200Y+118518X0190Y         S0      
327m5218            J67   -267        A01X+177200Y+118518X0205Y0590R090 S1      
317m5219            VIA   -    MD0080PA01X+152100Y+112054X0160Y         S0      
327m5219            U25   -CR10       A01X+151916Y+111949X0177Y    R180 S1      
317m5219            VIA   -    MD0100PA01X+178814Y+118852X0190Y         S0      
327m5219            J67   -124        A01X+178814Y+118852X0205Y0590R090 S1      
317m5220            VIA   -    MD0080PA01X+152655Y+111735X0160Y         S0      
327m5220            U25   -CP9        A01X+152472Y+111630X0177Y    R180 S1      
317m5220            VIA   -    MD0100PA01X+178814Y+118183X0190Y         S0      
327m5220            J67   -122        A01X+178814Y+118183X0205Y0590R090 S1      
317m5221            VIA   -    MD0080PA01X+151915Y+111735X0160Y         S0      
327m5221            U25   -CP11       A01X+151732Y+111630X0177Y    R180 S1      
317m5221            VIA   -    MD0100PA01X+177200Y+117848X0190Y         S0      
327m5221            J67   -265        A01X+177200Y+117848X0205Y0590R090 S1      
317m5222            VIA   -    MD0080PA01X+152470Y+111416X0160Y         S0      
327m5222            U25   -CN9        A01X+152287Y+111311X0177Y    R180 S1      
317m5222            VIA   -    MD0100PA01X+177200Y+117179X0190Y         S0      
327m5222            J67   -263        A01X+177200Y+117179X0205Y0590R090 S1      
317m5223            VIA   -    MD0080PA01X+152100Y+111416X0160Y         S0      
327m5223            U25   -CN10       A01X+151916Y+111311X0177Y    R180 S1      
317m5223            VIA   -    MD0100PA01X+178814Y+117514X0190Y         S0      
327m5223            J67   -120        A01X+178814Y+117514X0205Y0590R090 S1      
317m5224            VIA   -    MD0080PA01X+152655Y+111097X0160Y         S0      
327m5224            U25   -CM9        A01X+152472Y+110992X0177Y    R180 S1      
317m5224            VIA   -    MD0100PA01X+178814Y+116844X0190Y         S0      
327m5224            J67   -118        A01X+178814Y+116844X0205Y0590R090 S1      
317m5225            VIA   -    MD0080PA01X+151915Y+110459X0160Y         S0      
327m5225            U25   -CK11       A01X+151732Y+110354X0177Y    R180 S1      
317m5225            VIA   -    MD0100PA01X+177200Y+115506X0190Y         S0      
327m5225            J67   -258        A01X+177200Y+115506X0205Y0590R090 S1      
317m5226            VIA   -    MD0080PA01X+152470Y+110140X0160Y         S0      
327m5226            U25   -CJ9        A01X+152287Y+110036X0177Y    R180 S1      
317m5226            VIA   -    MD0100PA01X+177200Y+114837X0190Y         S0      
327m5226            J67   -256        A01X+177200Y+114837X0205Y0590R090 S1      
317m5227            VIA   -    MD0080PA01X+152655Y+107908X0160Y         S0      
327m5227            U25   -CB9        A01X+152472Y+107803X0177Y    R180 S1      
317m5227            VIA   -    MD0100PA01X+178814Y+110821X0190Y         S0      
327m5227            J67   -100        A01X+178814Y+110821X0205Y0590R090 S1      
317m5228            VIA   -    MD0080PA01X+152470Y+105038X0160Y         S0      
327m5228            U25   -BN9        A01X+152287Y+104933X0177Y    R180 S1      
317m5228            VIA   -    MD0100PA01X+177200Y+105801X0190Y         S0      
327m5228            J67   -229        A01X+177200Y+105801X0205Y0590R090 S1      
317m5229            VIA   -    MD0080PA01X+151915Y+104719X0160Y         S0      
327m5229            U25   -BM11       A01X+151732Y+104614X0177Y    R180 S1      
317m5229            VIA   -    MD0100PA01X+178814Y+105467X0190Y         S0      
327m5229            J67   -84         A01X+178814Y+105467X0205Y0590R090 S1      
317m5230            VIA   -    MD0080PA01X+151915Y+106632X0160Y         S0      
327m5230            U25   -BV11       A01X+151732Y+106528X0177Y    R180 S1      
317m5230            VIA   -    MD0100PA01X+177200Y+108144X0190Y         S0      
327m5230            J67   -236        A01X+177200Y+108144X0205Y0590R090 S1      
317m5231            VIA   -    MD0080PA01X+152470Y+106313X0160Y         S0      
327m5231            U25   -BU9        A01X+152287Y+106209X0177Y    R180 S1      
317m5231            VIA   -    MD0100PA01X+177200Y+107474X0190Y         S0      
327m5231            J67   -234        A01X+177200Y+107474X0205Y0590R090 S1      
317m5232            VIA   -    MD0080PA01X+152100Y+106313X0160Y         S0      
327m5232            U25   -BU10       A01X+151916Y+106209X0177Y    R180 S1      
317m5232            VIA   -    MD0100PA01X+178814Y+107809X0190Y         S0      
327m5232            J67   -91         A01X+178814Y+107809X0205Y0590R090 S1      
317m5233            VIA   -    MD0080PA01X+152655Y+105994X0160Y         S0      
327m5233            U25   -BT9        A01X+152472Y+105890X0177Y    R180 S1      
317m5233            VIA   -    MD0100PA01X+178814Y+107140X0190Y         S0      
327m5233            J67   -89         A01X+178814Y+107140X0205Y0590R090 S1      
317m5234            VIA   -    MD0080PA01X+151915Y+107908X0160Y         S0      
327m5234            U25   -CB11       A01X+151732Y+107803X0177Y    R180 S1      
317m5234            VIA   -    MD0100PA01X+177200Y+110486X0190Y         S0      
327m5234            J67   -243        A01X+177200Y+110486X0205Y0590R090 S1      
317m5235            VIA   -    MD0080PA01X+152470Y+107589X0160Y         S0      
327m5235            U25   -CA9        A01X+152287Y+107484X0177Y    R180 S1      
317m5235            VIA   -    MD0100PA01X+177200Y+109817X0190Y         S0      
327m5235            J67   -241        A01X+177200Y+109817X0205Y0590R090 S1      
317m5236            VIA   -    MD0080PA01X+152100Y+107589X0160Y         S0      
327m5236            U25   -CA10       A01X+151916Y+107484X0177Y    R180 S1      
317m5236            VIA   -    MD0100PA01X+178814Y+110152X0190Y         S0      
327m5236            J67   -98         A01X+178814Y+110152X0205Y0590R090 S1      
317m5237            VIA   -    MD0080PA01X+152655Y+107270X0160Y         S0      
327m5237            U25   -BY9        A01X+152472Y+107165X0177Y    R180 S1      
317m5237            VIA   -    MD0100PA01X+178814Y+109482X0190Y         S0      
327m5237            J67   -96         A01X+178814Y+109482X0205Y0590R090 S1      
317m5238            VIA   -    MD0080PA01X+152655Y+104081X0160Y         S0      
327m5238            U25   -BK9        A01X+152472Y+103976X0177Y    R180 S1      
317m5238            VIA   -    MD0100PA01X+178814Y+104797X0190Y         S0      
327m5238            J67   -82         A01X+178814Y+104797X0205Y0590R090 S1      
317m5239            VIA   -    MD0080PA01X+151915Y+104081X0160Y         S0      
327m5239            U25   -BK11       A01X+151732Y+103976X0177Y    R180 S1      
317m5239            VIA   -    MD0100PA01X+177200Y+104463X0190Y         S0      
327m5239            J67   -225        A01X+177200Y+104463X0205Y0590R090 S1      
317m5240            VIA   -    MD0080PA01X+152100Y+103762X0160Y         S0      
327m5240            U25   -BJ10       A01X+151916Y+103658X0177Y    R180 S1      
317m5240            VIA   -    MD0100PA01X+178814Y+104128X0190Y         S0      
327m5240            J67   -80         A01X+178814Y+104128X0205Y0590R090 S1      
317m5241            VIA   -    MD0080PA01X+152470Y+103762X0160Y         S0      
327m5241            U25   -BJ9        A01X+152287Y+103658X0177Y    R180 S1      
317m5241            VIA   -    MD0100PA01X+177200Y+103793X0190Y         S0      
327m5241            J67   -223        A01X+177200Y+103793X0205Y0590R090 S1      
317m5242            VIA   -    MD0080PA01X+152655Y+103443X0160Y         S0      
327m5242            U25   -BH9        A01X+152472Y+103339X0177Y    R180 S1      
317m5242            VIA   -    MD0100PA01X+178814Y+103459X0190Y         S0      
327m5242            J67   -78         A01X+178814Y+103459X0205Y0590R090 S1      
317m5243            VIA   -    MD0080PA01X+151915Y+103443X0160Y         S0      
327m5243            U25   -BH11       A01X+151732Y+103339X0177Y    R180 S1      
317m5243            VIA   -    MD0100PA01X+177200Y+103124X0190Y         S0      
327m5243            J67   -221        A01X+177200Y+103124X0205Y0590R090 S1      
317m5244            VIA   -    MD0080PA01X+152100Y+103124X0160Y         S0      
327m5244            U25   -BG10       A01X+151916Y+103020X0177Y    R180 S1      
317m5244            VIA   -    MD0100PA01X+178814Y+102789X0190Y         S0      
327m5244            J67   -76         A01X+178814Y+102789X0205Y0590R090 S1      
317m5245            VIA   -    MD0080PA01X+152100Y+105038X0160Y         S0      
327m5245            U25   -BN10       A01X+151916Y+104933X0177Y    R180 S1      
317m5245            VIA   -    MD0100PA01X+178814Y+106136X0190Y         S0      
327m5245            J67   -86         A01X+178814Y+106136X0205Y0590R090 S1      
317m5246            VIA   -    MD0080PA01X+151982Y+100718X0160Y    R180 S0      
327m5246            U25   -BC10       A01X+151798Y+100823X0177Y    R180 S1      
317m5246            VIA   -    MD0100PA01X+178814Y+100112X0190Y         S0      
327m5246            J67   -74         A01X+178814Y+100112X0205Y0590R090 S1      
317m5247            VIA   -    MD0080PA01X+151982Y+097529X0160Y    R180 S0      
327m5247            U25   -AN10       A01X+151798Y+097634X0177Y    R180 S1      
317m5247            VIA   -    MD0100PA01X+177200Y+094423X0190Y         S0      
327m5247            J67   -201        A01X+177200Y+094423X0205Y0590R090 S1      
317m5248            VIA   -    MD0080PA01X+151982Y+095616X0160Y    R180 S0      
327m5248            U25   -AG10       A01X+151798Y+095720X0177Y    R180 S1      
317m5248            VIA   -    MD0100PA01X+177200Y+090742X0190Y         S0      
327m5248            J67   -190        A01X+177200Y+090742X0205Y0590R090 S1      
317m5249            VIA   -    MD0080PA01X+151982Y+093702X0160Y    R180 S0      
327m5249            U25   -AA10       A01X+151798Y+093807X0177Y    R180 S1      
317m5249            VIA   -    MD0100PA01X+177200Y+087061X0190Y         S0      
327m5249            J67   -179        A01X+177200Y+087061X0205Y0590R090 S1      
317m5250            VIA   -    MD0080PA01X+151982Y+091789X0160Y    R180 S0      
327m5250            U25   -R10        A01X+151798Y+091894X0177Y    R180 S1      
317m5250            VIA   -    MD0100PA01X+177200Y+083380X0190Y         S0      
327m5250            J67   -168        A01X+177200Y+083380X0205Y0590R090 S1      
317m5251            VIA   -    MD0080PA01X+151982Y+089876X0160Y    R180 S0      
327m5251            U25   -J10        A01X+151798Y+089980X0177Y    R180 S1      
317m5251            VIA   -    MD0100PA01X+177200Y+079699X0190Y         S0      
327m5251            J67   -157        A01X+177200Y+079699X0205Y0590R090 S1      
317m5252            VIA   -    MD0080PA01X+152352Y+096891X0160Y    R180 S0      
327m5252            U25   -AL9        A01X+152168Y+096996X0177Y    R180 S1      
317m5252            VIA   -    MD0100PA01X+178814Y+093754X0190Y         S0      
327m5252            J67   -55         A01X+178814Y+093754X0205Y0590R090 S1      
317m5253            VIA   -    MD0080PA01X+152352Y+094978X0160Y    R180 S0      
327m5253            U25   -AE9        A01X+152168Y+095083X0177Y    R180 S1      
317m5253            VIA   -    MD0100PA01X+178814Y+090073X0190Y         S0      
327m5253            J67   -44         A01X+178814Y+090073X0205Y0590R090 S1      
317m5254            VIA   -    MD0080PA01X+152352Y+093065X0160Y    R180 S0      
327m5254            U25   -W9         A01X+152168Y+093169X0177Y    R180 S1      
317m5254            VIA   -    MD0100PA01X+178814Y+086392X0190Y         S0      
327m5254            J67   -33         A01X+178814Y+086392X0205Y0590R090 S1      
317m5255            VIA   -    MD0080PA01X+152352Y+091151X0160Y    R180 S0      
327m5255            U25   -N9         A01X+152168Y+091256X0177Y    R180 S1      
317m5255            VIA   -    MD0100PA01X+178814Y+082711X0190Y         S0      
327m5255            J67   -22         A01X+178814Y+082711X0205Y0590R090 S1      
317m5256            VIA   -    MD0080PA01X+152352Y+089238X0160Y    R180 S0      
327m5256            U25   -G9         A01X+152168Y+089343X0177Y    R180 S1      
317m5256            VIA   -    MD0100PA01X+178814Y+079030X0190Y         S0      
327m5256            J67   -11         A01X+178814Y+079030X0205Y0590R090 S1      
317m5257            VIA   -    MD0080PA01X+151797Y+097210X0160Y    R180 S0      
327m5257            U25   -AM11       A01X+151613Y+097315X0177Y    R180 S1      
317m5257            VIA   -    MD0100PA01X+177200Y+094089X0190Y         S0      
327m5257            J67   -200        A01X+177200Y+094089X0205Y0590R090 S1      
317m5258            VIA   -    MD0080PA01X+151797Y+095297X0160Y    R180 S0      
327m5258            U25   -AF11       A01X+151613Y+095402X0177Y    R180 S1      
317m5258            VIA   -    MD0100PA01X+177200Y+090408X0190Y         S0      
327m5258            J67   -189        A01X+177200Y+090408X0205Y0590R090 S1      
317m5259            VIA   -    MD0080PA01X+151797Y+093384X0160Y    R180 S0      
327m5259            U25   -Y11        A01X+151613Y+093488X0177Y    R180 S1      
317m5259            VIA   -    MD0100PA01X+177200Y+086726X0190Y         S0      
327m5259            J67   -178        A01X+177200Y+086726X0205Y0590R090 S1      
317m5260            VIA   -    MD0080PA01X+151797Y+091470X0160Y    R180 S0      
327m5260            U25   -P11        A01X+151613Y+091575X0177Y    R180 S1      
317m5260            VIA   -    MD0100PA01X+177200Y+083045X0190Y         S0      
327m5260            J67   -167        A01X+177200Y+083045X0205Y0590R090 S1      
317m5261            VIA   -    MD0080PA01X+151797Y+089557X0160Y    R180 S0      
327m5261            U25   -H11        A01X+151613Y+089662X0177Y    R180 S1      
317m5261            VIA   -    MD0100PA01X+177200Y+079364X0190Y         S0      
327m5261            J67   -156        A01X+177200Y+079364X0205Y0590R090 S1      
317m5262            VIA   -    MD0080PA01X+152537Y+097210X0160Y    R180 S0      
327m5262            U25   -AM9        A01X+152354Y+097315X0177Y    R180 S1      
317m5262            VIA   -    MD0100PA01X+178814Y+094089X0190Y         S0      
327m5262            J67   -56         A01X+178814Y+094089X0205Y0590R090 S1      
317m5263            VIA   -    MD0080PA01X+152537Y+095297X0160Y    R180 S0      
327m5263            U25   -AF9        A01X+152354Y+095402X0177Y    R180 S1      
317m5263            VIA   -    MD0100PA01X+178814Y+090408X0190Y         S0      
327m5263            J67   -45         A01X+178814Y+090408X0205Y0590R090 S1      
317m5264            VIA   -    MD0080PA01X+152537Y+093384X0160Y    R180 S0      
327m5264            U25   -Y9         A01X+152354Y+093488X0177Y    R180 S1      
317m5264            VIA   -    MD0100PA01X+178814Y+086726X0190Y         S0      
327m5264            J67   -34         A01X+178814Y+086726X0205Y0590R090 S1      
317m5265            VIA   -    MD0080PA01X+152537Y+091470X0160Y    R180 S0      
327m5265            U25   -P9         A01X+152354Y+091575X0177Y    R180 S1      
317m5265            VIA   -    MD0100PA01X+178814Y+083045X0190Y         S0      
327m5265            J67   -23         A01X+178814Y+083045X0205Y0590R090 S1      
317m5266            VIA   -    MD0080PA01X+152537Y+089557X0160Y    R180 S0      
327m5266            U25   -H9         A01X+152354Y+089662X0177Y    R180 S1      
317m5266            VIA   -    MD0100PA01X+178814Y+079364X0190Y         S0      
327m5266            J67   -12         A01X+178814Y+079364X0205Y0590R090 S1      
317m5267            VIA   -    MD0080PA01X+151797Y+090832X0160Y    R180 S0      
327m5267            U25   -M11        A01X+151613Y+090937X0177Y    R180 S1      
317m5267            VIA   -    MD0100PA01X+178814Y+082041X0190Y         S0      
327m5267            J67   -20         A01X+178814Y+082041X0205Y0590R090 S1      
317m5268            VIA   -    MD0080PA01X+152352Y+090513X0160Y    R180 S0      
327m5268            U25   -L9         A01X+152168Y+090618X0177Y    R180 S1      
317m5268            VIA   -    MD0100PA01X+178814Y+081372X0190Y         S0      
327m5268            J67   -18         A01X+178814Y+081372X0205Y0590R090 S1      
317m5269            VIA   -    MD0080PA01X+151982Y+090513X0160Y    R180 S0      
327m5269            U25   -L10        A01X+151798Y+090618X0177Y    R180 S1      
317m5269            VIA   -    MD0100PA01X+177200Y+081037X0190Y         S0      
327m5269            J67   -161        A01X+177200Y+081037X0205Y0590R090 S1      
317m5270            VIA   -    MD0080PA01X+152537Y+090195X0160Y    R180 S0      
327m5270            U25   -K9         A01X+152354Y+090299X0177Y    R180 S1      
317m5270            VIA   -    MD0100PA01X+177200Y+080368X0190Y         S0      
327m5270            J67   -159        A01X+177200Y+080368X0205Y0590R090 S1      
317m5271            VIA   -    MD0080PA01X+151797Y+090195X0160Y    R180 S0      
327m5271            U25   -K11        A01X+151613Y+090299X0177Y    R180 S1      
317m5271            VIA   -    MD0100PA01X+178814Y+080703X0190Y         S0      
327m5271            J67   -16         A01X+178814Y+080703X0205Y0590R090 S1      
317m5272            VIA   -    MD0080PA01X+152352Y+089876X0160Y    R180 S0      
327m5272            U25   -J9         A01X+152168Y+089980X0177Y    R180 S1      
317m5272            VIA   -    MD0100PA01X+178814Y+080034X0190Y         S0      
327m5272            J67   -14         A01X+178814Y+080034X0205Y0590R090 S1      
317m5273            VIA   -    MD0080PA01X+151982Y+089238X0160Y    R180 S0      
327m5273            U25   -G10        A01X+151798Y+089343X0177Y    R180 S1      
317m5273            VIA   -    MD0100PA01X+177200Y+078695X0190Y         S0      
327m5273            J67   -154        A01X+177200Y+078695X0205Y0590R090 S1      
317m5274            VIA   -    MD0080PA01X+151982Y+096254X0160Y    R180 S0      
327m5274            U25   -AJ10       A01X+151798Y+096358X0177Y    R180 S1      
317m5274            VIA   -    MD0100PA01X+177200Y+092081X0190Y         S0      
327m5274            J67   -194        A01X+177200Y+092081X0205Y0590R090 S1      
317m5275            VIA   -    MD0080PA01X+152537Y+095935X0160Y    R180 S0      
327m5275            U25   -AH9        A01X+152354Y+096039X0177Y    R180 S1      
317m5275            VIA   -    MD0100PA01X+177200Y+091411X0190Y         S0      
327m5275            J67   -192        A01X+177200Y+091411X0205Y0590R090 S1      
317m5276            VIA   -    MD0080PA01X+152537Y+088919X0160Y    R180 S0      
327m5276            U25   -F9         A01X+152354Y+089024X0177Y    R180 S1      
317m5276            VIA   -    MD0100PA01X+177200Y+078026X0190Y         S0      
327m5276            J67   -152        A01X+177200Y+078026X0205Y0590R090 S1      
317m5277            VIA   -    MD0080PA01X+151797Y+095935X0160Y    R180 S0      
327m5277            U25   -AH11       A01X+151613Y+096039X0177Y    R180 S1      
317m5277            VIA   -    MD0100PA01X+178814Y+091746X0190Y         S0      
327m5277            J67   -49         A01X+178814Y+091746X0205Y0590R090 S1      
317m5278            VIA   -    MD0080PA01X+152352Y+095616X0160Y    R180 S0      
327m5278            U25   -AG9        A01X+152168Y+095720X0177Y    R180 S1      
317m5278            VIA   -    MD0100PA01X+178814Y+091077X0190Y         S0      
327m5278            J67   -47         A01X+178814Y+091077X0205Y0590R090 S1      
317m5279            VIA   -    MD0080PA01X+151982Y+094978X0160Y    R180 S0      
327m5279            U25   -AE10       A01X+151798Y+095083X0177Y    R180 S1      
317m5279            VIA   -    MD0100PA01X+177200Y+089738X0190Y         S0      
327m5279            J67   -187        A01X+177200Y+089738X0205Y0590R090 S1      
317m5280            VIA   -    MD0080PA01X+152537Y+094659X0160Y    R180 S0      
327m5280            U25   -AD9        A01X+152354Y+094764X0177Y    R180 S1      
317m5280            VIA   -    MD0100PA01X+177200Y+089069X0190Y         S0      
327m5280            J67   -185        A01X+177200Y+089069X0205Y0590R090 S1      
317m5281            VIA   -    MD0080PA01X+151797Y+094659X0160Y    R180 S0      
327m5281            U25   -AD11       A01X+151613Y+094764X0177Y    R180 S1      
317m5281            VIA   -    MD0100PA01X+178814Y+089404X0190Y         S0      
327m5281            J67   -42         A01X+178814Y+089404X0205Y0590R090 S1      
317m5282            VIA   -    MD0080PA01X+152352Y+094340X0160Y    R180 S0      
327m5282            U25   -AC9        A01X+152168Y+094445X0177Y    R180 S1      
317m5282            VIA   -    MD0100PA01X+178814Y+088734X0190Y         S0      
327m5282            J67   -40         A01X+178814Y+088734X0205Y0590R090 S1      
317m5283            VIA   -    MD0080PA01X+151982Y+094340X0160Y    R180 S0      
327m5283            U25   -AC10       A01X+151798Y+094445X0177Y    R180 S1      
317m5283            VIA   -    MD0100PA01X+177200Y+088400X0190Y         S0      
327m5283            J67   -183        A01X+177200Y+088400X0205Y0590R090 S1      
317m5284            VIA   -    MD0080PA01X+152537Y+094021X0160Y    R180 S0      
327m5284            U25   -AB9        A01X+152354Y+094126X0177Y    R180 S1      
317m5284            VIA   -    MD0100PA01X+177200Y+087730X0190Y         S0      
327m5284            J67   -181        A01X+177200Y+087730X0205Y0590R090 S1      
317m5285            VIA   -    MD0080PA01X+151797Y+094021X0160Y    R180 S0      
327m5285            U25   -AB11       A01X+151613Y+094126X0177Y    R180 S1      
317m5285            VIA   -    MD0100PA01X+178814Y+088065X0190Y         S0      
327m5285            J67   -38         A01X+178814Y+088065X0205Y0590R090 S1      
317m5286            VIA   -    MD0080PA01X+152352Y+093702X0160Y    R180 S0      
327m5286            U25   -AA9        A01X+152168Y+093807X0177Y    R180 S1      
317m5286            VIA   -    MD0100PA01X+178814Y+087396X0190Y         S0      
327m5286            J67   -36         A01X+178814Y+087396X0205Y0590R090 S1      
317m5287            VIA   -    MD0080PA01X+151797Y+088919X0160Y    R180 S0      
327m5287            U25   -F11        A01X+151613Y+089024X0177Y    R180 S1      
317m5287            VIA   -    MD0100PA01X+178814Y+078360X0190Y         S0      
327m5287            J67   -9          A01X+178814Y+078360X0205Y0590R090 S1      
317m5288            VIA   -    MD0080PA01X+151982Y+093065X0160Y    R180 S0      
327m5288            U25   -W10        A01X+151798Y+093169X0177Y    R180 S1      
317m5288            VIA   -    MD0100PA01X+177200Y+086057X0190Y         S0      
327m5288            J67   -176        A01X+177200Y+086057X0205Y0590R090 S1      
317m5289            VIA   -    MD0080PA01X+152537Y+092746X0160Y    R180 S0      
327m5289            U25   -V9         A01X+152354Y+092850X0177Y    R180 S1      
317m5289            VIA   -    MD0100PA01X+177200Y+085388X0190Y         S0      
327m5289            J67   -174        A01X+177200Y+085388X0205Y0590R090 S1      
317m5290            VIA   -    MD0080PA01X+151797Y+092746X0160Y    R180 S0      
327m5290            U25   -V11        A01X+151613Y+092850X0177Y    R180 S1      
317m5290            VIA   -    MD0100PA01X+178814Y+085722X0190Y         S0      
327m5290            J67   -31         A01X+178814Y+085722X0205Y0590R090 S1      
317m5291            VIA   -    MD0080PA01X+152352Y+092427X0160Y    R180 S0      
327m5291            U25   -U9         A01X+152168Y+092532X0177Y    R180 S1      
317m5291            VIA   -    MD0100PA01X+178814Y+085053X0190Y         S0      
327m5291            J67   -29         A01X+178814Y+085053X0205Y0590R090 S1      
317m5292            VIA   -    MD0080PA01X+151982Y+092427X0160Y    R180 S0      
327m5292            U25   -U10        A01X+151798Y+092532X0177Y    R180 S1      
317m5292            VIA   -    MD0100PA01X+177200Y+084718X0190Y         S0      
327m5292            J67   -172        A01X+177200Y+084718X0205Y0590R090 S1      
317m5293            VIA   -    MD0080PA01X+152537Y+092108X0160Y    R180 S0      
327m5293            U25   -T9         A01X+152354Y+092213X0177Y    R180 S1      
317m5293            VIA   -    MD0100PA01X+177200Y+084049X0190Y         S0      
327m5293            J67   -170        A01X+177200Y+084049X0205Y0590R090 S1      
317m5294            VIA   -    MD0080PA01X+151797Y+092108X0160Y    R180 S0      
327m5294            U25   -T11        A01X+151613Y+092213X0177Y    R180 S1      
317m5294            VIA   -    MD0100PA01X+178814Y+084384X0190Y         S0      
327m5294            J67   -27         A01X+178814Y+084384X0205Y0590R090 S1      
317m5295            VIA   -    MD0080PA01X+152352Y+091789X0160Y    R180 S0      
327m5295            U25   -R9         A01X+152168Y+091894X0177Y    R180 S1      
317m5295            VIA   -    MD0100PA01X+178814Y+083715X0190Y         S0      
327m5295            J67   -25         A01X+178814Y+083715X0205Y0590R090 S1      
317m5296            VIA   -    MD0080PA01X+151982Y+091151X0160Y    R180 S0      
327m5296            U25   -N10        A01X+151798Y+091256X0177Y    R180 S1      
317m5296            VIA   -    MD0100PA01X+177200Y+082376X0190Y         S0      
327m5296            J67   -165        A01X+177200Y+082376X0205Y0590R090 S1      
317m5297            VIA   -    MD0080PA01X+152537Y+090832X0160Y    R180 S0      
327m5297            U25   -M9         A01X+152354Y+090937X0177Y    R180 S1      
317m5297            VIA   -    MD0100PA01X+177200Y+081707X0190Y         S0      
327m5297            J67   -163        A01X+177200Y+081707X0205Y0590R090 S1      
317m5298            VIA   -    MD0080PA01X+152352Y+088600X0160Y    R180 S0      
327m5298            U25   -E9         A01X+152168Y+088705X0177Y    R180 S1      
317m5298            VIA   -    MD0100PA01X+178814Y+077691X0190Y         S0      
327m5298            J67   -7          A01X+178814Y+077691X0205Y0590R090 S1      
317m5299            VIA   -    MD0080PA01X+151797Y+099124X0160Y    R180 S0      
327m5299            U25   -AV11       A01X+151613Y+099228X0177Y    R180 S1      
317m5299            VIA   -    MD0100PA01X+177200Y+097100X0190Y         S0      
327m5299            J67   -209        A01X+177200Y+097100X0205Y0590R090 S1      
317m5300            VIA   -    MD0080PA01X+152352Y+098805X0160Y    R180 S0      
327m5300            U25   -AU9        A01X+152168Y+098910X0177Y    R180 S1      
317m5300            VIA   -    MD0100PA01X+178814Y+096766X0190Y         S0      
327m5300            J67   -64         A01X+178814Y+096766X0205Y0590R090 S1      
317m5301            VIA   -    MD0080PA01X+151982Y+098167X0160Y    R180 S0      
327m5301            U25   -AR10       A01X+151798Y+098272X0177Y    R180 S1      
317m5301            VIA   -    MD0100PA01X+177200Y+095762X0190Y         S0      
327m5301            J67   -205        A01X+177200Y+095762X0205Y0590R090 S1      
317m5302            VIA   -    MD0080PA01X+152537Y+097848X0160Y    R180 S0      
327m5302            U25   -AP9        A01X+152354Y+097953X0177Y    R180 S1      
317m5302            VIA   -    MD0100PA01X+177200Y+095092X0190Y         S0      
327m5302            J67   -203        A01X+177200Y+095092X0205Y0590R090 S1      
317m5303            VIA   -    MD0080PA01X+151797Y+097848X0160Y    R180 S0      
327m5303            U25   -AP11       A01X+151613Y+097953X0177Y    R180 S1      
317m5303            VIA   -    MD0100PA01X+178814Y+095427X0190Y         S0      
327m5303            J67   -60         A01X+178814Y+095427X0205Y0590R090 S1      
317m5304            VIA   -    MD0080PA01X+152352Y+097529X0160Y    R180 S0      
327m5304            U25   -AN9        A01X+152168Y+097634X0177Y    R180 S1      
317m5304            VIA   -    MD0100PA01X+178814Y+094758X0190Y         S0      
327m5304            J67   -58         A01X+178814Y+094758X0205Y0590R090 S1      
317m5305            VIA   -    MD0080PA01X+151982Y+096891X0160Y    R180 S0      
327m5305            U25   -AL10       A01X+151798Y+096996X0177Y    R180 S1      
317m5305            VIA   -    MD0100PA01X+177200Y+093419X0190Y         S0      
327m5305            J67   -198        A01X+177200Y+093419X0205Y0590R090 S1      
317m5306            VIA   -    MD0080PA01X+152537Y+096572X0160Y    R180 S0      
327m5306            U25   -AK9        A01X+152354Y+096677X0177Y    R180 S1      
317m5306            VIA   -    MD0100PA01X+177200Y+092750X0190Y         S0      
327m5306            J67   -196        A01X+177200Y+092750X0205Y0590R090 S1      
317m5307            VIA   -    MD0080PA01X+151797Y+096572X0160Y    R180 S0      
327m5307            U25   -AK11       A01X+151613Y+096677X0177Y    R180 S1      
317m5307            VIA   -    MD0100PA01X+178814Y+093085X0190Y         S0      
327m5307            J67   -53         A01X+178814Y+093085X0205Y0590R090 S1      
317m5308            VIA   -    MD0080PA01X+152352Y+096254X0160Y    R180 S0      
327m5308            U25   -AJ9        A01X+152168Y+096358X0177Y    R180 S1      
317m5308            VIA   -    MD0100PA01X+178814Y+092415X0190Y         S0      
327m5308            J67   -51         A01X+178814Y+092415X0205Y0590R090 S1      
317m5309            VIA   -    MD0080PA01X+151797Y+100399X0160Y    R180 S0      
327m5309            U25   -BB11       A01X+151613Y+100504X0177Y    R180 S1      
317m5309            VIA   -    MD0100PA01X+178814Y+099443X0190Y         S0      
327m5309            J67   -72         A01X+178814Y+099443X0205Y0590R090 S1      
317m5310            VIA   -    MD0080PA01X+152537Y+100399X0160Y    R180 S0      
327m5310            U25   -BB9        A01X+152354Y+100504X0177Y    R180 S1      
317m5310            VIA   -    MD0100PA01X+177200Y+099108X0190Y         S0      
327m5310            J67   -215        A01X+177200Y+099108X0205Y0590R090 S1      
317m5311            VIA   -    MD0080PA01X+152352Y+100080X0160Y    R180 S0      
327m5311            U25   -BA9        A01X+152168Y+100185X0177Y    R180 S1      
317m5311            VIA   -    MD0100PA01X+178814Y+098774X0190Y         S0      
327m5311            J67   -70         A01X+178814Y+098774X0205Y0590R090 S1      
317m5312            VIA   -    MD0080PA01X+151982Y+100080X0160Y    R180 S0      
327m5312            U25   -BA10       A01X+151798Y+100185X0177Y    R180 S1      
317m5312            VIA   -    MD0100PA01X+177200Y+098439X0190Y         S0      
327m5312            J67   -213        A01X+177200Y+098439X0205Y0590R090 S1      
317m5313            VIA   -    MD0080PA01X+151797Y+099762X0160Y    R180 S0      
327m5313            U25   -AY11       A01X+151613Y+099866X0177Y    R180 S1      
317m5313            VIA   -    MD0100PA01X+178814Y+098104X0190Y         S0      
327m5313            J67   -68         A01X+178814Y+098104X0205Y0590R090 S1      
317m5314            VIA   -    MD0080PA01X+152537Y+099762X0160Y    R180 S0      
327m5314            U25   -AY9        A01X+152354Y+099866X0177Y    R180 S1      
317m5314            VIA   -    MD0100PA01X+177200Y+097770X0190Y         S0      
327m5314            J67   -211        A01X+177200Y+097770X0205Y0590R090 S1      
317m5315            VIA   -    MD0080PA01X+152352Y+099443X0160Y    R180 S0      
327m5315            U25   -AW9        A01X+152168Y+099547X0177Y    R180 S1      
317m5315            VIA   -    MD0100PA01X+178814Y+097435X0190Y         S0      
327m5315            J67   -66         A01X+178814Y+097435X0205Y0590R090 S1      
317m5316            VIA   -    MD0080PA01X+151982Y+098805X0160Y    R180 S0      
327m5316            U25   -AU10       A01X+151798Y+098910X0177Y    R180 S1      
317m5316            VIA   -    MD0100PA01X+177200Y+096431X0190Y         S0      
327m5316            J67   -207        A01X+177200Y+096431X0205Y0590R090 S1      
317m5317            VIA   -    MD0080PA01X+152352Y+100718X0160Y    R180 S0      
327m5317            U25   -BC9        A01X+152168Y+100823X0177Y    R180 S1      
317m5317            VIA   -    MD0100PA01X+177200Y+099778X0190Y         S0      
327m5317            J67   -217        A01X+177200Y+099778X0205Y0590R090 S1      
317m5318            VIA   -    MD0080PA01X+152537Y+101037X0160Y    R180 S0      
327m5318            U25   -BD9        A01X+152354Y+101142X0177Y    R180 S1      
317m5318            VIA   -    MD0100PA01X+177200Y+100112X0190Y         S0      
327m5318            J67   -218        A01X+177200Y+100112X0205Y0590R090 S1      
317m5319            VIA   -    MD0080PA01X+151797Y+098486X0160Y    R180 S0      
327m5319            U25   -AT11       A01X+151613Y+098591X0177Y    R180 S1      
317m5319            VIA   -    MD0100PA18X+178264Y+096096X0190Y         S0      
327m5319            R386  -2          A18X+178264Y+096096X0198Y0197     S2      
327m5320            J67   -62         A01X+178814Y+096096X0205Y0590R090 S1      
317m5320            VIA   -    MD0100PA00X+178814Y+096096X0190Y         S0      
327m5320            R386  -1          A18X+178579Y+096096X0198Y0197     S2      
317m5321            VIA   -    MD0080PA01X+056152Y+105357X0160Y         S0      
327m5321            U26   -BP6        A01X+055968Y+105252X0177Y    R180 S1      
317m5321            VIA   -    MD0100PA01X+078230Y+106471X0190Y         S0      
327m5321            J99   -87         A01X+078230Y+106471X0205Y0590R090 S1      
317m5322            VIA   -    MD0080PA01X+055596Y+104400X0160Y         S0      
327m5322            U26   -BL7        A01X+055413Y+104295X0177Y    R180 S1      
317m5322            VIA   -    MD0100PA01X+076616Y+105132X0190Y         S0      
327m5322            J99   -227        A01X+076616Y+105132X0205Y0590R090 S1      
317m5323            VIA   -    MD0080PA01X+056152Y+106632X0160Y         S0      
327m5323            U26   -BV6        A01X+055968Y+106528X0177Y    R180 S1      
317m5323            VIA   -    MD0100PA01X+078230Y+108478X0190Y         S0      
327m5323            J99   -93         A01X+078230Y+108478X0205Y0590R090 S1      
317m5324            VIA   -    MD0080PA01X+055781Y+114924X0160Y         S0      
327m5324            U26   -DD7        A01X+055598Y+114819X0177Y    R180 S1      
317m5324            VIA   -    MD0100PA01X+076616Y+123872X0190Y         S0      
327m5324            J99   -283        A01X+076616Y+123872X0205Y0590R090 S1      
317m5325            VIA   -    MD0080PA01X+055781Y+113010X0160Y         S0      
327m5325            U26   -CV7        A01X+055598Y+112906X0177Y    R180 S1      
317m5325            VIA   -    MD0100PA01X+076616Y+120191X0190Y         S0      
327m5325            J99   -272        A01X+076616Y+120191X0205Y0590R090 S1      
317m5326            VIA   -    MD0080PA01X+055781Y+111097X0160Y         S0      
327m5326            U26   -CM7        A01X+055598Y+110992X0177Y    R180 S1      
317m5326            VIA   -    MD0100PA01X+076616Y+116510X0190Y         S0      
327m5326            J99   -261        A01X+076616Y+116510X0205Y0590R090 S1      
317m5327            VIA   -    MD0080PA01X+055781Y+109184X0160Y         S0      
327m5327            U26   -CF7        A01X+055598Y+109079X0177Y    R180 S1      
317m5327            VIA   -    MD0100PA01X+076616Y+112829X0190Y         S0      
327m5327            J99   -250        A01X+076616Y+112829X0205Y0590R090 S1      
317m5328            VIA   -    MD0080PA01X+055781Y+107270X0160Y         S0      
327m5328            U26   -BY7        A01X+055598Y+107166X0177Y    R180 S1      
317m5328            VIA   -    MD0100PA01X+076616Y+109148X0190Y         S0      
327m5328            J99   -239        A01X+076616Y+109148X0205Y0590R090 S1      
317m5329            VIA   -    MD0080PA01X+056152Y+114286X0160Y         S0      
327m5329            U26   -DB6        A01X+055968Y+114181X0177Y    R180 S1      
317m5329            VIA   -    MD0100PA01X+078230Y+123203X0190Y         S0      
327m5329            J99   -137        A01X+078230Y+123203X0205Y0590R090 S1      
317m5330            VIA   -    MD0080PA01X+056152Y+112373X0160Y         S0      
327m5330            U26   -CT6        A01X+055968Y+112268X0177Y    R180 S1      
317m5330            VIA   -    MD0100PA01X+078230Y+119522X0190Y         S0      
327m5330            J99   -126        A01X+078230Y+119522X0205Y0590R090 S1      
317m5331            VIA   -    MD0080PA01X+056152Y+110459X0160Y         S0      
327m5331            U26   -CK6        A01X+055968Y+110354X0177Y    R180 S1      
317m5331            VIA   -    MD0100PA01X+078230Y+115841X0190Y         S0      
327m5331            J99   -115        A01X+078230Y+115841X0205Y0590R090 S1      
317m5332            VIA   -    MD0080PA01X+056152Y+108546X0160Y         S0      
327m5332            U26   -CD6        A01X+055968Y+108441X0177Y    R180 S1      
317m5332            VIA   -    MD0100PA01X+078230Y+112160X0190Y         S0      
327m5332            J99   -104        A01X+078230Y+112160X0205Y0590R090 S1      
317m5333            VIA   -    MD0080PA01X+056336Y+106951X0160Y         S0      
327m5333            U26   -BW5        A01X+056153Y+106847X0177Y    R180 S1      
317m5333            VIA   -    MD0100PA01X+078230Y+108813X0190Y         S0      
327m5333            J99   -94         A01X+078230Y+108813X0205Y0590R090 S1      
317m5334            VIA   -    MD0080PA01X+055596Y+114605X0160Y         S0      
327m5334            U26   -DC7        A01X+055413Y+114500X0177Y    R180 S1      
317m5334            VIA   -    MD0100PA01X+076616Y+123538X0190Y         S0      
327m5334            J99   -282        A01X+076616Y+123538X0205Y0590R090 S1      
317m5335            VIA   -    MD0080PA01X+055596Y+112692X0160Y         S0      
327m5335            U26   -CU7        A01X+055413Y+112587X0177Y    R180 S1      
317m5335            VIA   -    MD0100PA01X+076616Y+119856X0190Y         S0      
327m5335            J99   -271        A01X+076616Y+119856X0205Y0590R090 S1      
317m5336            VIA   -    MD0080PA01X+055596Y+110778X0160Y         S0      
327m5336            U26   -CL7        A01X+055413Y+110673X0177Y    R180 S1      
317m5336            VIA   -    MD0100PA01X+076616Y+116175X0190Y         S0      
327m5336            J99   -260        A01X+076616Y+116175X0205Y0590R090 S1      
317m5337            VIA   -    MD0080PA01X+055596Y+108865X0160Y         S0      
327m5337            U26   -CE7        A01X+055413Y+108760X0177Y    R180 S1      
317m5337            VIA   -    MD0100PA01X+076616Y+112494X0190Y         S0      
327m5337            J99   -249        A01X+076616Y+112494X0205Y0590R090 S1      
317m5338            VIA   -    MD0080PA01X+055596Y+106951X0160Y         S0      
327m5338            U26   -BW7        A01X+055413Y+106847X0177Y    R180 S1      
317m5338            VIA   -    MD0100PA01X+076616Y+108813X0190Y         S0      
327m5338            J99   -238        A01X+076616Y+108813X0205Y0590R090 S1      
317m5339            VIA   -    MD0080PA01X+056336Y+114605X0160Y         S0      
327m5339            U26   -DC5        A01X+056153Y+114500X0177Y    R180 S1      
317m5339            VIA   -    MD0100PA01X+078230Y+123538X0190Y         S0      
327m5339            J99   -138        A01X+078230Y+123538X0205Y0590R090 S1      
317m5340            VIA   -    MD0080PA01X+056336Y+112692X0160Y         S0      
327m5340            U26   -CU5        A01X+056153Y+112587X0177Y    R180 S1      
317m5340            VIA   -    MD0100PA01X+078230Y+119856X0190Y         S0      
327m5340            J99   -127        A01X+078230Y+119856X0205Y0590R090 S1      
317m5341            VIA   -    MD0080PA01X+056336Y+110778X0160Y         S0      
327m5341            U26   -CL5        A01X+056153Y+110673X0177Y    R180 S1      
317m5341            VIA   -    MD0100PA01X+078230Y+116175X0190Y         S0      
327m5341            J99   -116        A01X+078230Y+116175X0205Y0590R090 S1      
317m5342            VIA   -    MD0080PA01X+056336Y+108865X0160Y         S0      
327m5342            U26   -CE5        A01X+056153Y+108760X0177Y    R180 S1      
317m5342            VIA   -    MD0100PA01X+078230Y+112494X0190Y         S0      
327m5342            J99   -105        A01X+078230Y+112494X0205Y0590R090 S1      
317m5343            VIA   -    MD0080PA01X+055596Y+110140X0160Y         S0      
327m5343            U26   -CJ7        A01X+055413Y+110036X0177Y    R180 S1      
317m5343            VIA   -    MD0100PA01X+078230Y+115171X0190Y         S0      
327m5343            J99   -113        A01X+078230Y+115171X0205Y0590R090 S1      
317m5344            VIA   -    MD0080PA01X+056152Y+109821X0160Y         S0      
327m5344            U26   -CH6        A01X+055968Y+109717X0177Y    R180 S1      
317m5344            VIA   -    MD0100PA01X+078230Y+114502X0190Y         S0      
327m5344            J99   -111        A01X+078230Y+114502X0205Y0590R090 S1      
317m5345            VIA   -    MD0080PA01X+055781Y+109821X0160Y         S0      
327m5345            U26   -CH7        A01X+055598Y+109717X0177Y    R180 S1      
317m5345            VIA   -    MD0100PA01X+076616Y+114168X0190Y         S0      
327m5345            J99   -254        A01X+076616Y+114168X0205Y0590R090 S1      
317m5346            VIA   -    MD0080PA01X+056336Y+109502X0160Y         S0      
327m5346            U26   -CG5        A01X+056153Y+109398X0177Y    R180 S1      
317m5346            VIA   -    MD0100PA01X+076616Y+113498X0190Y         S0      
327m5346            J99   -252        A01X+076616Y+113498X0205Y0590R090 S1      
317m5347            VIA   -    MD0080PA01X+055596Y+109502X0160Y         S0      
327m5347            U26   -CG7        A01X+055413Y+109398X0177Y    R180 S1      
317m5347            VIA   -    MD0100PA01X+078230Y+113833X0190Y         S0      
327m5347            J99   -109        A01X+078230Y+113833X0205Y0590R090 S1      
317m5348            VIA   -    MD0080PA01X+056152Y+109184X0160Y         S0      
327m5348            U26   -CF6        A01X+055968Y+109079X0177Y    R180 S1      
317m5348            VIA   -    MD0100PA01X+078230Y+113164X0190Y         S0      
327m5348            J99   -107        A01X+078230Y+113164X0205Y0590R090 S1      
317m5349            VIA   -    MD0080PA01X+055781Y+108546X0160Y         S0      
327m5349            U26   -CD7        A01X+055598Y+108441X0177Y    R180 S1      
317m5349            VIA   -    MD0100PA01X+076616Y+111825X0190Y         S0      
327m5349            J99   -247        A01X+076616Y+111825X0205Y0590R090 S1      
317m5350            VIA   -    MD0080PA01X+055781Y+115562X0160Y         S0      
327m5350            U26   -DF7        A01X+055598Y+115457X0177Y    R180 S1      
317m5350            VIA   -    MD0100PA01X+076616Y+125211X0190Y         S0      
327m5350            J99   -287        A01X+076616Y+125211X0205Y0590R090 S1      
317m5351            VIA   -    MD0080PA01X+056336Y+115243X0160Y         S0      
327m5351            U26   -DE5        A01X+056153Y+115138X0177Y    R180 S1      
317m5351            VIA   -    MD0100PA01X+076616Y+124542X0190Y         S0      
327m5351            J99   -285        A01X+076616Y+124542X0205Y0590R090 S1      
317m5352            VIA   -    MD0080PA01X+056336Y+108227X0160Y         S0      
327m5352            U26   -CC5        A01X+056153Y+108122X0177Y    R180 S1      
317m5352            VIA   -    MD0100PA01X+076616Y+111156X0190Y         S0      
327m5352            J99   -245        A01X+076616Y+111156X0205Y0590R090 S1      
317m5353            VIA   -    MD0080PA01X+055596Y+115243X0160Y         S0      
327m5353            U26   -DE7        A01X+055413Y+115138X0177Y    R180 S1      
317m5353            VIA   -    MD0100PA01X+078230Y+124876X0190Y         S0      
327m5353            J99   -142        A01X+078230Y+124876X0205Y0590R090 S1      
317m5354            VIA   -    MD0080PA01X+056152Y+114924X0160Y         S0      
327m5354            U26   -DD6        A01X+055968Y+114819X0177Y    R180 S1      
317m5354            VIA   -    MD0100PA01X+078230Y+124207X0190Y         S0      
327m5354            J99   -140        A01X+078230Y+124207X0205Y0590R090 S1      
317m5355            VIA   -    MD0080PA01X+055781Y+114286X0160Y         S0      
327m5355            U26   -DB7        A01X+055598Y+114181X0177Y    R180 S1      
317m5355            VIA   -    MD0100PA01X+076616Y+122868X0190Y         S0      
327m5355            J99   -280        A01X+076616Y+122868X0205Y0590R090 S1      
317m5356            VIA   -    MD0080PA01X+056336Y+113967X0160Y         S0      
327m5356            U26   -DA5        A01X+056153Y+113862X0177Y    R180 S1      
317m5356            VIA   -    MD0100PA01X+076616Y+122199X0190Y         S0      
327m5356            J99   -278        A01X+076616Y+122199X0205Y0590R090 S1      
317m5357            VIA   -    MD0080PA01X+055596Y+113967X0160Y         S0      
327m5357            U26   -DA7        A01X+055413Y+113862X0177Y    R180 S1      
317m5357            VIA   -    MD0100PA01X+078230Y+122534X0190Y         S0      
327m5357            J99   -135        A01X+078230Y+122534X0205Y0590R090 S1      
317m5358            VIA   -    MD0080PA01X+056152Y+113648X0160Y         S0      
327m5358            U26   -CY6        A01X+055968Y+113543X0177Y    R180 S1      
317m5358            VIA   -    MD0100PA01X+078230Y+121864X0190Y         S0      
327m5358            J99   -133        A01X+078230Y+121864X0205Y0590R090 S1      
317m5359            VIA   -    MD0080PA01X+055781Y+113648X0160Y         S0      
327m5359            U26   -CY7        A01X+055598Y+113543X0177Y    R180 S1      
317m5359            VIA   -    MD0100PA01X+076616Y+121530X0190Y         S0      
327m5359            J99   -276        A01X+076616Y+121530X0205Y0590R090 S1      
317m5360            VIA   -    MD0080PA01X+056336Y+113329X0160Y         S0      
327m5360            U26   -CW5        A01X+056153Y+113225X0177Y    R180 S1      
317m5360            VIA   -    MD0100PA01X+076616Y+120860X0190Y         S0      
327m5360            J99   -274        A01X+076616Y+120860X0205Y0590R090 S1      
317m5361            VIA   -    MD0080PA01X+055596Y+113329X0160Y         S0      
327m5361            U26   -CW7        A01X+055413Y+113225X0177Y    R180 S1      
317m5361            VIA   -    MD0100PA01X+078230Y+121195X0190Y         S0      
327m5361            J99   -131        A01X+078230Y+121195X0205Y0590R090 S1      
317m5362            VIA   -    MD0080PA01X+056152Y+113010X0160Y         S0      
327m5362            U26   -CV6        A01X+055968Y+112906X0177Y    R180 S1      
317m5362            VIA   -    MD0100PA01X+078230Y+120526X0190Y         S0      
327m5362            J99   -129        A01X+078230Y+120526X0205Y0590R090 S1      
317m5363            VIA   -    MD0080PA01X+055596Y+108227X0160Y         S0      
327m5363            U26   -CC7        A01X+055413Y+108122X0177Y    R180 S1      
317m5363            VIA   -    MD0100PA01X+078230Y+111490X0190Y         S0      
327m5363            J99   -102        A01X+078230Y+111490X0205Y0590R090 S1      
317m5364            VIA   -    MD0080PA01X+055781Y+112373X0160Y         S0      
327m5364            U26   -CT7        A01X+055598Y+112268X0177Y    R180 S1      
317m5364            VIA   -    MD0100PA01X+076616Y+119187X0190Y         S0      
327m5364            J99   -269        A01X+076616Y+119187X0205Y0590R090 S1      
317m5365            VIA   -    MD0080PA01X+056336Y+112054X0160Y         S0      
327m5365            U26   -CR5        A01X+056153Y+111949X0177Y    R180 S1      
317m5365            VIA   -    MD0100PA01X+076616Y+118518X0190Y         S0      
327m5365            J99   -267        A01X+076616Y+118518X0205Y0590R090 S1      
317m5366            VIA   -    MD0080PA01X+055596Y+112054X0160Y         S0      
327m5366            U26   -CR7        A01X+055413Y+111949X0177Y    R180 S1      
317m5366            VIA   -    MD0100PA01X+078230Y+118852X0190Y         S0      
327m5366            J99   -124        A01X+078230Y+118852X0205Y0590R090 S1      
317m5367            VIA   -    MD0080PA01X+056152Y+111735X0160Y         S0      
327m5367            U26   -CP6        A01X+055968Y+111630X0177Y    R180 S1      
317m5367            VIA   -    MD0100PA01X+078230Y+118183X0190Y         S0      
327m5367            J99   -122        A01X+078230Y+118183X0205Y0590R090 S1      
317m5368            VIA   -    MD0080PA01X+055781Y+111735X0160Y         S0      
327m5368            U26   -CP7        A01X+055598Y+111630X0177Y    R180 S1      
317m5368            VIA   -    MD0100PA01X+076616Y+117849X0190Y         S0      
327m5368            J99   -265        A01X+076616Y+117849X0205Y0590R090 S1      
317m5369            VIA   -    MD0080PA01X+056336Y+111416X0160Y         S0      
327m5369            U26   -CN5        A01X+056153Y+111311X0177Y    R180 S1      
317m5369            VIA   -    MD0100PA01X+076616Y+117179X0190Y         S0      
327m5369            J99   -263        A01X+076616Y+117179X0205Y0590R090 S1      
317m5370            VIA   -    MD0080PA01X+055596Y+111416X0160Y         S0      
327m5370            U26   -CN7        A01X+055413Y+111311X0177Y    R180 S1      
317m5370            VIA   -    MD0100PA01X+078230Y+117514X0190Y         S0      
327m5370            J99   -120        A01X+078230Y+117514X0205Y0590R090 S1      
317m5371            VIA   -    MD0080PA01X+056152Y+111097X0160Y         S0      
327m5371            U26   -CM6        A01X+055968Y+110992X0177Y    R180 S1      
317m5371            VIA   -    MD0100PA01X+078230Y+116845X0190Y         S0      
327m5371            J99   -118        A01X+078230Y+116845X0205Y0590R090 S1      
317m5372            VIA   -    MD0080PA01X+055781Y+110459X0160Y         S0      
327m5372            U26   -CK7        A01X+055598Y+110354X0177Y    R180 S1      
317m5372            VIA   -    MD0100PA01X+076616Y+115506X0190Y         S0      
327m5372            J99   -258        A01X+076616Y+115506X0205Y0590R090 S1      
317m5373            VIA   -    MD0080PA01X+056336Y+110140X0160Y         S0      
327m5373            U26   -CJ5        A01X+056153Y+110036X0177Y    R180 S1      
317m5373            VIA   -    MD0100PA01X+076616Y+114837X0190Y         S0      
327m5373            J99   -256        A01X+076616Y+114837X0205Y0590R090 S1      
317m5374            VIA   -    MD0080PA01X+056152Y+107908X0160Y         S0      
327m5374            U26   -CB6        A01X+055968Y+107803X0177Y    R180 S1      
317m5374            VIA   -    MD0100PA01X+078230Y+110821X0190Y         S0      
327m5374            J99   -100        A01X+078230Y+110821X0205Y0590R090 S1      
317m5375            VIA   -    MD0080PA01X+056336Y+105038X0160Y         S0      
327m5375            U26   -BN5        A01X+056153Y+104933X0177Y    R180 S1      
317m5375            VIA   -    MD0100PA01X+076616Y+105801X0190Y         S0      
327m5375            J99   -229        A01X+076616Y+105801X0205Y0590R090 S1      
317m5376            VIA   -    MD0080PA01X+055781Y+104719X0160Y         S0      
327m5376            U26   -BM7        A01X+055598Y+104614X0177Y    R180 S1      
317m5376            VIA   -    MD0100PA01X+078230Y+105467X0190Y         S0      
327m5376            J99   -84         A01X+078230Y+105467X0205Y0590R090 S1      
317m5377            VIA   -    MD0080PA01X+055781Y+106632X0160Y         S0      
327m5377            U26   -BV7        A01X+055598Y+106528X0177Y    R180 S1      
317m5377            VIA   -    MD0100PA01X+076616Y+108144X0190Y         S0      
327m5377            J99   -236        A01X+076616Y+108144X0205Y0590R090 S1      
317m5378            VIA   -    MD0080PA01X+056336Y+106314X0160Y         S0      
327m5378            U26   -BU5        A01X+056153Y+106209X0177Y    R180 S1      
317m5378            VIA   -    MD0100PA01X+076616Y+107474X0190Y         S0      
327m5378            J99   -234        A01X+076616Y+107474X0205Y0590R090 S1      
317m5379            VIA   -    MD0080PA01X+055596Y+106314X0160Y         S0      
327m5379            U26   -BU7        A01X+055413Y+106209X0177Y    R180 S1      
317m5379            VIA   -    MD0100PA01X+078230Y+107809X0190Y         S0      
327m5379            J99   -91         A01X+078230Y+107809X0205Y0590R090 S1      
317m5380            VIA   -    MD0080PA01X+056152Y+105995X0160Y         S0      
327m5380            U26   -BT6        A01X+055968Y+105890X0177Y    R180 S1      
317m5380            VIA   -    MD0100PA01X+078230Y+107140X0190Y         S0      
327m5380            J99   -89         A01X+078230Y+107140X0205Y0590R090 S1      
317m5381            VIA   -    MD0080PA01X+055781Y+107908X0160Y         S0      
327m5381            U26   -CB7        A01X+055598Y+107803X0177Y    R180 S1      
317m5381            VIA   -    MD0100PA01X+076616Y+110486X0190Y         S0      
327m5381            J99   -243        A01X+076616Y+110486X0205Y0590R090 S1      
317m5382            VIA   -    MD0080PA01X+056336Y+107589X0160Y         S0      
327m5382            U26   -CA5        A01X+056153Y+107484X0177Y    R180 S1      
317m5382            VIA   -    MD0100PA01X+076616Y+109817X0190Y         S0      
327m5382            J99   -241        A01X+076616Y+109817X0205Y0590R090 S1      
317m5383            VIA   -    MD0080PA01X+055596Y+107589X0160Y         S0      
327m5383            U26   -CA7        A01X+055413Y+107484X0177Y    R180 S1      
317m5383            VIA   -    MD0100PA01X+078230Y+110152X0190Y         S0      
327m5383            J99   -98         A01X+078230Y+110152X0205Y0590R090 S1      
317m5384            VIA   -    MD0080PA01X+056152Y+107270X0160Y         S0      
327m5384            U26   -BY6        A01X+055968Y+107166X0177Y    R180 S1      
317m5384            VIA   -    MD0100PA01X+078230Y+109482X0190Y         S0      
327m5384            J99   -96         A01X+078230Y+109482X0205Y0590R090 S1      
317m5385            VIA   -    MD0080PA01X+056152Y+104081X0160Y         S0      
327m5385            U26   -BK6        A01X+055968Y+103976X0177Y    R180 S1      
317m5385            VIA   -    MD0100PA01X+078230Y+104797X0190Y         S0      
327m5385            J99   -82         A01X+078230Y+104797X0205Y0590R090 S1      
317m5386            VIA   -    MD0080PA01X+055781Y+104081X0160Y         S0      
327m5386            U26   -BK7        A01X+055598Y+103976X0177Y    R180 S1      
317m5386            VIA   -    MD0100PA01X+076616Y+104463X0190Y         S0      
327m5386            J99   -225        A01X+076616Y+104463X0205Y0590R090 S1      
317m5387            VIA   -    MD0080PA01X+055596Y+103762X0160Y         S0      
327m5387            U26   -BJ7        A01X+055413Y+103658X0177Y    R180 S1      
317m5387            VIA   -    MD0100PA01X+078230Y+104128X0190Y         S0      
327m5387            J99   -80         A01X+078230Y+104128X0205Y0590R090 S1      
317m5388            VIA   -    MD0080PA01X+056336Y+103762X0160Y         S0      
327m5388            U26   -BJ5        A01X+056153Y+103658X0177Y    R180 S1      
317m5388            VIA   -    MD0100PA01X+076616Y+103793X0190Y         S0      
327m5388            J99   -223        A01X+076616Y+103793X0205Y0590R090 S1      
317m5389            VIA   -    MD0080PA01X+056152Y+103443X0160Y         S0      
327m5389            U26   -BH6        A01X+055968Y+103339X0177Y    R180 S1      
317m5389            VIA   -    MD0100PA01X+078230Y+103459X0190Y         S0      
327m5389            J99   -78         A01X+078230Y+103459X0205Y0590R090 S1      
317m5390            VIA   -    MD0080PA01X+055781Y+103443X0160Y         S0      
327m5390            U26   -BH7        A01X+055598Y+103339X0177Y    R180 S1      
317m5390            VIA   -    MD0100PA01X+076616Y+103124X0190Y         S0      
327m5390            J99   -221        A01X+076616Y+103124X0205Y0590R090 S1      
317m5391            VIA   -    MD0080PA01X+055596Y+103124X0160Y         S0      
327m5391            U26   -BG7        A01X+055413Y+103020X0177Y    R180 S1      
317m5391            VIA   -    MD0100PA01X+078230Y+102790X0190Y         S0      
327m5391            J99   -76         A01X+078230Y+102790X0205Y0590R090 S1      
317m5392            VIA   -    MD0080PA01X+055596Y+105038X0160Y         S0      
327m5392            U26   -BN7        A01X+055413Y+104933X0177Y    R180 S1      
317m5392            VIA   -    MD0100PA01X+078230Y+106136X0190Y         S0      
327m5392            J99   -86         A01X+078230Y+106136X0205Y0590R090 S1      
317m5393            VIA   -    MD0080PA01X+055478Y+100718X0160Y    R180 S0      
327m5393            U26   -BC7        A01X+055294Y+100823X0177Y    R180 S1      
317m5393            VIA   -    MD0100PA01X+078230Y+100112X0190Y         S0      
327m5393            J99   -74         A01X+078230Y+100112X0205Y0590R090 S1      
317m5394            VIA   -    MD0080PA01X+055478Y+097529X0160Y    R180 S0      
327m5394            U26   -AN7        A01X+055294Y+097634X0177Y    R180 S1      
317m5394            VIA   -    MD0100PA01X+076616Y+094423X0190Y         S0      
327m5394            J99   -201        A01X+076616Y+094423X0205Y0590R090 S1      
317m5395            VIA   -    MD0080PA01X+055478Y+095616X0160Y    R180 S0      
327m5395            U26   -AG7        A01X+055294Y+095721X0177Y    R180 S1      
317m5395            VIA   -    MD0100PA01X+076616Y+090742X0190Y         S0      
327m5395            J99   -190        A01X+076616Y+090742X0205Y0590R090 S1      
317m5396            VIA   -    MD0080PA01X+055478Y+093702X0160Y    R180 S0      
327m5396            U26   -AA7        A01X+055294Y+093807X0177Y    R180 S1      
317m5396            VIA   -    MD0100PA01X+076616Y+087061X0190Y         S0      
327m5396            J99   -179        A01X+076616Y+087061X0205Y0590R090 S1      
317m5397            VIA   -    MD0080PA01X+055478Y+091789X0160Y    R180 S0      
327m5397            U26   -R7         A01X+055294Y+091894X0177Y    R180 S1      
317m5397            VIA   -    MD0100PA01X+076616Y+083380X0190Y         S0      
327m5397            J99   -168        A01X+076616Y+083380X0205Y0590R090 S1      
317m5398            VIA   -    MD0080PA01X+055478Y+089876X0160Y    R180 S0      
327m5398            U26   -J7         A01X+055294Y+089980X0177Y    R180 S1      
317m5398            VIA   -    MD0100PA01X+076616Y+079699X0190Y         S0      
327m5398            J99   -157        A01X+076616Y+079699X0205Y0590R090 S1      
317m5399            VIA   -    MD0080PA01X+056218Y+096892X0160Y    R180 S0      
327m5399            U26   -AL5        A01X+056035Y+096996X0177Y    R180 S1      
317m5399            VIA   -    MD0100PA01X+078230Y+093754X0190Y         S0      
327m5399            J99   -55         A01X+078230Y+093754X0205Y0590R090 S1      
317m5400            VIA   -    MD0080PA01X+056218Y+094978X0160Y    R180 S0      
327m5400            U26   -AE5        A01X+056035Y+095083X0177Y    R180 S1      
317m5400            VIA   -    MD0100PA01X+078230Y+090073X0190Y         S0      
327m5400            J99   -44         A01X+078230Y+090073X0205Y0590R090 S1      
317m5401            VIA   -    MD0080PA01X+056218Y+093065X0160Y    R180 S0      
327m5401            U26   -W5         A01X+056035Y+093169X0177Y    R180 S1      
317m5401            VIA   -    MD0100PA01X+078230Y+086392X0190Y         S0      
327m5401            J99   -33         A01X+078230Y+086392X0205Y0590R090 S1      
317m5402            VIA   -    MD0080PA01X+056218Y+091151X0160Y    R180 S0      
327m5402            U26   -N5         A01X+056035Y+091256X0177Y    R180 S1      
317m5402            VIA   -    MD0100PA01X+078230Y+082711X0190Y         S0      
327m5402            J99   -22         A01X+078230Y+082711X0205Y0590R090 S1      
317m5403            VIA   -    MD0080PA01X+056218Y+089238X0160Y    R180 S0      
327m5403            U26   -G5         A01X+056035Y+089343X0177Y    R180 S1      
317m5403            VIA   -    MD0100PA01X+078230Y+079030X0190Y         S0      
327m5403            J99   -11         A01X+078230Y+079030X0205Y0590R090 S1      
317m5404            VIA   -    MD0080PA01X+055663Y+097210X0160Y    R180 S0      
327m5404            U26   -AM7        A01X+055480Y+097315X0177Y    R180 S1      
317m5404            VIA   -    MD0100PA01X+076616Y+094089X0190Y         S0      
327m5404            J99   -200        A01X+076616Y+094089X0205Y0590R090 S1      
317m5405            VIA   -    MD0080PA01X+055663Y+095297X0160Y    R180 S0      
327m5405            U26   -AF7        A01X+055480Y+095402X0177Y    R180 S1      
317m5405            VIA   -    MD0100PA01X+076616Y+090408X0190Y         S0      
327m5405            J99   -189        A01X+076616Y+090408X0205Y0590R090 S1      
317m5406            VIA   -    MD0080PA01X+055663Y+093384X0160Y    R180 S0      
327m5406            U26   -Y7         A01X+055480Y+093488X0177Y    R180 S1      
317m5406            VIA   -    MD0100PA01X+076616Y+086726X0190Y         S0      
327m5406            J99   -178        A01X+076616Y+086726X0205Y0590R090 S1      
317m5407            VIA   -    MD0080PA01X+055663Y+091470X0160Y    R180 S0      
327m5407            U26   -P7         A01X+055480Y+091575X0177Y    R180 S1      
317m5407            VIA   -    MD0100PA01X+076616Y+083045X0190Y         S0      
327m5407            J99   -167        A01X+076616Y+083045X0205Y0590R090 S1      
317m5408            VIA   -    MD0080PA01X+055663Y+089557X0160Y    R180 S0      
327m5408            U26   -H7         A01X+055480Y+089662X0177Y    R180 S1      
317m5408            VIA   -    MD0100PA01X+076616Y+079364X0190Y         S0      
327m5408            J99   -156        A01X+076616Y+079364X0205Y0590R090 S1      
317m5409            VIA   -    MD0080PA01X+056033Y+097210X0160Y    R180 S0      
327m5409            U26   -AM6        A01X+055850Y+097315X0177Y    R180 S1      
317m5409            VIA   -    MD0100PA01X+078230Y+094089X0190Y         S0      
327m5409            J99   -56         A01X+078230Y+094089X0205Y0590R090 S1      
317m5410            VIA   -    MD0080PA01X+056033Y+095297X0160Y    R180 S0      
327m5410            U26   -AF6        A01X+055850Y+095402X0177Y    R180 S1      
317m5410            VIA   -    MD0100PA01X+078230Y+090408X0190Y         S0      
327m5410            J99   -45         A01X+078230Y+090408X0205Y0590R090 S1      
317m5411            VIA   -    MD0080PA01X+056033Y+093384X0160Y    R180 S0      
327m5411            U26   -Y6         A01X+055850Y+093488X0177Y    R180 S1      
317m5411            VIA   -    MD0100PA01X+078230Y+086726X0190Y         S0      
327m5411            J99   -34         A01X+078230Y+086726X0205Y0590R090 S1      
317m5412            VIA   -    MD0080PA01X+056033Y+091470X0160Y    R180 S0      
327m5412            U26   -P6         A01X+055850Y+091575X0177Y    R180 S1      
317m5412            VIA   -    MD0100PA01X+078230Y+083045X0190Y         S0      
327m5412            J99   -23         A01X+078230Y+083045X0205Y0590R090 S1      
317m5413            VIA   -    MD0080PA01X+056033Y+089557X0160Y    R180 S0      
327m5413            U26   -H6         A01X+055850Y+089662X0177Y    R180 S1      
317m5413            VIA   -    MD0100PA01X+078230Y+079364X0190Y         S0      
327m5413            J99   -12         A01X+078230Y+079364X0205Y0590R090 S1      
317m5414            VIA   -    MD0080PA01X+055663Y+090832X0160Y    R180 S0      
327m5414            U26   -M7         A01X+055480Y+090937X0177Y    R180 S1      
317m5414            VIA   -    MD0100PA01X+078230Y+082042X0190Y         S0      
327m5414            J99   -20         A01X+078230Y+082042X0205Y0590R090 S1      
317m5415            VIA   -    MD0080PA01X+056218Y+090514X0160Y    R180 S0      
327m5415            U26   -L5         A01X+056035Y+090618X0177Y    R180 S1      
317m5415            VIA   -    MD0100PA01X+078230Y+081372X0190Y         S0      
327m5415            J99   -18         A01X+078230Y+081372X0205Y0590R090 S1      
317m5416            VIA   -    MD0080PA01X+055478Y+090514X0160Y    R180 S0      
327m5416            U26   -L7         A01X+055294Y+090618X0177Y    R180 S1      
317m5416            VIA   -    MD0100PA01X+076616Y+081038X0190Y         S0      
327m5416            J99   -161        A01X+076616Y+081038X0205Y0590R090 S1      
317m5417            VIA   -    MD0080PA01X+056033Y+090195X0160Y    R180 S0      
327m5417            U26   -K6         A01X+055850Y+090299X0177Y    R180 S1      
317m5417            VIA   -    MD0100PA01X+076616Y+080368X0190Y         S0      
327m5417            J99   -159        A01X+076616Y+080368X0205Y0590R090 S1      
317m5418            VIA   -    MD0080PA01X+055663Y+090195X0160Y    R180 S0      
327m5418            U26   -K7         A01X+055480Y+090299X0177Y    R180 S1      
317m5418            VIA   -    MD0100PA01X+078230Y+080703X0190Y         S0      
327m5418            J99   -16         A01X+078230Y+080703X0205Y0590R090 S1      
317m5419            VIA   -    MD0080PA01X+056218Y+089876X0160Y    R180 S0      
327m5419            U26   -J5         A01X+056035Y+089980X0177Y    R180 S1      
317m5419            VIA   -    MD0100PA01X+078230Y+080034X0190Y         S0      
327m5419            J99   -14         A01X+078230Y+080034X0205Y0590R090 S1      
317m5420            VIA   -    MD0080PA01X+055478Y+089238X0160Y    R180 S0      
327m5420            U26   -G7         A01X+055294Y+089343X0177Y    R180 S1      
317m5420            VIA   -    MD0100PA01X+076616Y+078695X0190Y         S0      
327m5420            J99   -154        A01X+076616Y+078695X0205Y0590R090 S1      
317m5421            VIA   -    MD0080PA01X+055478Y+096254X0160Y    R180 S0      
327m5421            U26   -AJ7        A01X+055294Y+096358X0177Y    R180 S1      
317m5421            VIA   -    MD0100PA01X+076616Y+092081X0190Y         S0      
327m5421            J99   -194        A01X+076616Y+092081X0205Y0590R090 S1      
317m5422            VIA   -    MD0080PA01X+056033Y+095935X0160Y    R180 S0      
327m5422            U26   -AH6        A01X+055850Y+096040X0177Y    R180 S1      
317m5422            VIA   -    MD0100PA01X+076616Y+091412X0190Y         S0      
327m5422            J99   -192        A01X+076616Y+091412X0205Y0590R090 S1      
317m5423            VIA   -    MD0080PA01X+056033Y+088919X0160Y    R180 S0      
327m5423            U26   -F6         A01X+055850Y+089024X0177Y    R180 S1      
317m5423            VIA   -    MD0100PA01X+076616Y+078026X0190Y         S0      
327m5423            J99   -152        A01X+076616Y+078026X0205Y0590R090 S1      
317m5424            VIA   -    MD0080PA01X+055663Y+095935X0160Y    R180 S0      
327m5424            U26   -AH7        A01X+055480Y+096040X0177Y    R180 S1      
317m5424            VIA   -    MD0100PA01X+078230Y+091746X0190Y         S0      
327m5424            J99   -49         A01X+078230Y+091746X0205Y0590R090 S1      
317m5425            VIA   -    MD0080PA01X+056218Y+095616X0160Y    R180 S0      
327m5425            U26   -AG5        A01X+056035Y+095721X0177Y    R180 S1      
317m5425            VIA   -    MD0100PA01X+078230Y+091077X0190Y         S0      
327m5425            J99   -47         A01X+078230Y+091077X0205Y0590R090 S1      
317m5426            VIA   -    MD0080PA01X+055478Y+094978X0160Y    R180 S0      
327m5426            U26   -AE7        A01X+055294Y+095083X0177Y    R180 S1      
317m5426            VIA   -    MD0100PA01X+076616Y+089738X0190Y         S0      
327m5426            J99   -187        A01X+076616Y+089738X0205Y0590R090 S1      
317m5427            VIA   -    MD0080PA01X+056033Y+094659X0160Y    R180 S0      
327m5427            U26   -AD6        A01X+055850Y+094764X0177Y    R180 S1      
317m5427            VIA   -    MD0100PA01X+076616Y+089069X0190Y         S0      
327m5427            J99   -185        A01X+076616Y+089069X0205Y0590R090 S1      
317m5428            VIA   -    MD0080PA01X+055663Y+094659X0160Y    R180 S0      
327m5428            U26   -AD7        A01X+055480Y+094764X0177Y    R180 S1      
317m5428            VIA   -    MD0100PA01X+078230Y+089404X0190Y         S0      
327m5428            J99   -42         A01X+078230Y+089404X0205Y0590R090 S1      
317m5429            VIA   -    MD0080PA01X+056218Y+094340X0160Y    R180 S0      
327m5429            U26   -AC5        A01X+056035Y+094445X0177Y    R180 S1      
317m5429            VIA   -    MD0100PA01X+078230Y+088734X0190Y         S0      
327m5429            J99   -40         A01X+078230Y+088734X0205Y0590R090 S1      
317m5430            VIA   -    MD0080PA01X+055478Y+094340X0160Y    R180 S0      
327m5430            U26   -AC7        A01X+055294Y+094445X0177Y    R180 S1      
317m5430            VIA   -    MD0100PA01X+076616Y+088400X0190Y         S0      
327m5430            J99   -183        A01X+076616Y+088400X0205Y0590R090 S1      
317m5431            VIA   -    MD0080PA01X+056033Y+094021X0160Y    R180 S0      
327m5431            U26   -AB6        A01X+055850Y+094126X0177Y    R180 S1      
317m5431            VIA   -    MD0100PA01X+076616Y+087730X0190Y         S0      
327m5431            J99   -181        A01X+076616Y+087730X0205Y0590R090 S1      
317m5432            VIA   -    MD0080PA01X+055663Y+094021X0160Y    R180 S0      
327m5432            U26   -AB7        A01X+055480Y+094126X0177Y    R180 S1      
317m5432            VIA   -    MD0100PA01X+078230Y+088065X0190Y         S0      
327m5432            J99   -38         A01X+078230Y+088065X0205Y0590R090 S1      
317m5433            VIA   -    MD0080PA01X+056218Y+093702X0160Y    R180 S0      
327m5433            U26   -AA5        A01X+056035Y+093807X0177Y    R180 S1      
317m5433            VIA   -    MD0100PA01X+078230Y+087396X0190Y         S0      
327m5433            J99   -36         A01X+078230Y+087396X0205Y0590R090 S1      
317m5434            VIA   -    MD0080PA01X+055663Y+088919X0160Y    R180 S0      
327m5434            U26   -F7         A01X+055480Y+089024X0177Y    R180 S1      
317m5434            VIA   -    MD0100PA01X+078230Y+078360X0190Y         S0      
327m5434            J99   -9          A01X+078230Y+078360X0205Y0590R090 S1      
317m5435            VIA   -    MD0080PA01X+055478Y+093065X0160Y    R180 S0      
327m5435            U26   -W7         A01X+055294Y+093169X0177Y    R180 S1      
317m5435            VIA   -    MD0100PA01X+076616Y+086057X0190Y         S0      
327m5435            J99   -176        A01X+076616Y+086057X0205Y0590R090 S1      
317m5436            VIA   -    MD0080PA01X+056033Y+092746X0160Y    R180 S0      
327m5436            U26   -V6         A01X+055850Y+092850X0177Y    R180 S1      
317m5436            VIA   -    MD0100PA01X+076616Y+085388X0190Y         S0      
327m5436            J99   -174        A01X+076616Y+085388X0205Y0590R090 S1      
317m5437            VIA   -    MD0080PA01X+055663Y+092746X0160Y    R180 S0      
327m5437            U26   -V7         A01X+055480Y+092850X0177Y    R180 S1      
317m5437            VIA   -    MD0100PA01X+078230Y+085723X0190Y         S0      
327m5437            J99   -31         A01X+078230Y+085723X0205Y0590R090 S1      
317m5438            VIA   -    MD0080PA01X+056218Y+092427X0160Y    R180 S0      
327m5438            U26   -U5         A01X+056035Y+092532X0177Y    R180 S1      
317m5438            VIA   -    MD0100PA01X+078230Y+085053X0190Y         S0      
327m5438            J99   -29         A01X+078230Y+085053X0205Y0590R090 S1      
317m5439            VIA   -    MD0080PA01X+055478Y+092427X0160Y    R180 S0      
327m5439            U26   -U7         A01X+055294Y+092532X0177Y    R180 S1      
317m5439            VIA   -    MD0100PA01X+076616Y+084719X0190Y         S0      
327m5439            J99   -172        A01X+076616Y+084719X0205Y0590R090 S1      
317m5440            VIA   -    MD0080PA01X+056033Y+092108X0160Y    R180 S0      
327m5440            U26   -T6         A01X+055850Y+092213X0177Y    R180 S1      
317m5440            VIA   -    MD0100PA01X+076616Y+084049X0190Y         S0      
327m5440            J99   -170        A01X+076616Y+084049X0205Y0590R090 S1      
317m5441            VIA   -    MD0080PA01X+055663Y+092108X0160Y    R180 S0      
327m5441            U26   -T7         A01X+055480Y+092213X0177Y    R180 S1      
317m5441            VIA   -    MD0100PA01X+078230Y+084384X0190Y         S0      
327m5441            J99   -27         A01X+078230Y+084384X0205Y0590R090 S1      
317m5442            VIA   -    MD0080PA01X+056218Y+091789X0160Y    R180 S0      
327m5442            U26   -R5         A01X+056035Y+091894X0177Y    R180 S1      
317m5442            VIA   -    MD0100PA01X+078230Y+083715X0190Y         S0      
327m5442            J99   -25         A01X+078230Y+083715X0205Y0590R090 S1      
317m5443            VIA   -    MD0080PA01X+055478Y+091151X0160Y    R180 S0      
327m5443            U26   -N7         A01X+055294Y+091256X0177Y    R180 S1      
317m5443            VIA   -    MD0100PA01X+076616Y+082376X0190Y         S0      
327m5443            J99   -165        A01X+076616Y+082376X0205Y0590R090 S1      
317m5444            VIA   -    MD0080PA01X+056033Y+090832X0160Y    R180 S0      
327m5444            U26   -M6         A01X+055850Y+090937X0177Y    R180 S1      
327m5444            J99   -163        A01X+076616Y+081707X0205Y0590R090 S1      
317m5444            VIA   -    MD0100PA01X+076616Y+081707X0190Y         S0      
317m5445            VIA   -    MD0080PA01X+056218Y+088600X0160Y    R180 S0      
327m5445            U26   -E5         A01X+056035Y+088705X0177Y    R180 S1      
317m5445            VIA   -    MD0100PA01X+078230Y+077691X0190Y         S0      
327m5445            J99   -7          A01X+078230Y+077691X0205Y0590R090 S1      
317m5446            VIA   -    MD0080PA01X+055663Y+099124X0160Y    R180 S0      
327m5446            U26   -AV7        A01X+055480Y+099228X0177Y    R180 S1      
317m5446            VIA   -    MD0100PA01X+076616Y+097100X0190Y         S0      
327m5446            J99   -209        A01X+076616Y+097100X0205Y0590R090 S1      
317m5447            VIA   -    MD0080PA01X+056218Y+098805X0160Y    R180 S0      
327m5447            U26   -AU5        A01X+056035Y+098910X0177Y    R180 S1      
317m5447            VIA   -    MD0100PA01X+078230Y+096766X0190Y         S0      
327m5447            J99   -64         A01X+078230Y+096766X0205Y0590R090 S1      
317m5448            VIA   -    MD0080PA01X+055478Y+098167X0160Y    R180 S0      
327m5448            U26   -AR7        A01X+055294Y+098272X0177Y    R180 S1      
317m5448            VIA   -    MD0100PA01X+076616Y+095762X0190Y         S0      
327m5448            J99   -205        A01X+076616Y+095762X0205Y0590R090 S1      
317m5449            VIA   -    MD0080PA01X+056033Y+097848X0160Y    R180 S0      
327m5449            U26   -AP6        A01X+055850Y+097953X0177Y    R180 S1      
317m5449            VIA   -    MD0100PA01X+076616Y+095093X0190Y         S0      
327m5449            J99   -203        A01X+076616Y+095093X0205Y0590R090 S1      
317m5450            VIA   -    MD0080PA01X+055663Y+097848X0160Y    R180 S0      
327m5450            U26   -AP7        A01X+055480Y+097953X0177Y    R180 S1      
317m5450            VIA   -    MD0100PA01X+078230Y+095427X0190Y         S0      
327m5450            J99   -60         A01X+078230Y+095427X0205Y0590R090 S1      
317m5451            VIA   -    MD0080PA01X+056218Y+097529X0160Y    R180 S0      
327m5451            U26   -AN5        A01X+056035Y+097634X0177Y    R180 S1      
317m5451            VIA   -    MD0100PA01X+078230Y+094758X0190Y         S0      
327m5451            J99   -58         A01X+078230Y+094758X0205Y0590R090 S1      
317m5452            VIA   -    MD0080PA01X+055478Y+096892X0160Y    R180 S0      
327m5452            U26   -AL7        A01X+055294Y+096996X0177Y    R180 S1      
317m5452            VIA   -    MD0100PA01X+076616Y+093419X0190Y         S0      
327m5452            J99   -198        A01X+076616Y+093419X0205Y0590R090 S1      
317m5453            VIA   -    MD0080PA01X+056033Y+096573X0160Y    R180 S0      
327m5453            U26   -AK6        A01X+055850Y+096677X0177Y    R180 S1      
317m5453            VIA   -    MD0100PA01X+076616Y+092750X0190Y         S0      
327m5453            J99   -196        A01X+076616Y+092750X0205Y0590R090 S1      
317m5454            VIA   -    MD0080PA01X+055663Y+096573X0160Y    R180 S0      
327m5454            U26   -AK7        A01X+055480Y+096677X0177Y    R180 S1      
317m5454            VIA   -    MD0100PA01X+078230Y+093085X0190Y         S0      
327m5454            J99   -53         A01X+078230Y+093085X0205Y0590R090 S1      
317m5455            VIA   -    MD0080PA01X+056218Y+096254X0160Y    R180 S0      
327m5455            U26   -AJ5        A01X+056035Y+096358X0177Y    R180 S1      
317m5455            VIA   -    MD0100PA01X+078230Y+092416X0190Y         S0      
327m5455            J99   -51         A01X+078230Y+092416X0205Y0590R090 S1      
317m5456            VIA   -    MD0080PA01X+055663Y+100399X0160Y    R180 S0      
327m5456            U26   -BB7        A01X+055480Y+100504X0177Y    R180 S1      
317m5456            VIA   -    MD0100PA01X+078230Y+099443X0190Y         S0      
327m5456            J99   -72         A01X+078230Y+099443X0205Y0590R090 S1      
317m5457            VIA   -    MD0080PA01X+056033Y+100399X0160Y    R180 S0      
327m5457            U26   -BB6        A01X+055850Y+100504X0177Y    R180 S1      
317m5457            VIA   -    MD0100PA01X+076616Y+099108X0190Y         S0      
327m5457            J99   -215        A01X+076616Y+099108X0205Y0590R090 S1      
317m5458            VIA   -    MD0080PA01X+056218Y+100080X0160Y    R180 S0      
327m5458            U26   -BA5        A01X+056035Y+100185X0177Y    R180 S1      
317m5458            VIA   -    MD0100PA01X+078230Y+098774X0190Y         S0      
327m5458            J99   -70         A01X+078230Y+098774X0205Y0590R090 S1      
317m5459            VIA   -    MD0080PA01X+055478Y+100080X0160Y    R180 S0      
327m5459            U26   -BA7        A01X+055294Y+100185X0177Y    R180 S1      
317m5459            VIA   -    MD0100PA01X+076616Y+098439X0190Y         S0      
327m5459            J99   -213        A01X+076616Y+098439X0205Y0590R090 S1      
317m5460            VIA   -    MD0080PA01X+055663Y+099762X0160Y    R180 S0      
327m5460            U26   -AY7        A01X+055480Y+099866X0177Y    R180 S1      
317m5460            VIA   -    MD0100PA01X+078230Y+098104X0190Y         S0      
327m5460            J99   -68         A01X+078230Y+098104X0205Y0590R090 S1      
317m5461            VIA   -    MD0080PA01X+056033Y+099762X0160Y    R180 S0      
327m5461            U26   -AY6        A01X+055850Y+099866X0177Y    R180 S1      
317m5461            VIA   -    MD0100PA01X+076616Y+097770X0190Y         S0      
327m5461            J99   -211        A01X+076616Y+097770X0205Y0590R090 S1      
317m5462            VIA   -    MD0080PA01X+056218Y+099443X0160Y    R180 S0      
327m5462            U26   -AW5        A01X+056035Y+099547X0177Y    R180 S1      
317m5462            VIA   -    MD0100PA01X+078230Y+097435X0190Y         S0      
327m5462            J99   -66         A01X+078230Y+097435X0205Y0590R090 S1      
317m5463            VIA   -    MD0080PA01X+055478Y+098805X0160Y    R180 S0      
327m5463            U26   -AU7        A01X+055294Y+098910X0177Y    R180 S1      
317m5463            VIA   -    MD0100PA01X+076616Y+096431X0190Y         S0      
327m5463            J99   -207        A01X+076616Y+096431X0205Y0590R090 S1      
317m5464            VIA   -    MD0080PA01X+056218Y+100718X0160Y    R180 S0      
327m5464            U26   -BC5        A01X+056035Y+100823X0177Y    R180 S1      
317m5464            VIA   -    MD0100PA01X+076616Y+099778X0190Y         S0      
327m5464            J99   -217        A01X+076616Y+099778X0205Y0590R090 S1      
317m5465            VIA   -    MD0080PA01X+056033Y+101037X0160Y    R180 S0      
327m5465            U26   -BD6        A01X+055850Y+101142X0177Y    R180 S1      
317m5465            VIA   -    MD0100PA01X+076616Y+100112X0190Y         S0      
327m5465            J99   -218        A01X+076616Y+100112X0205Y0590R090 S1      
317m5466            VIA   -    MD0080PA01X+055663Y+098486X0160Y    R180 S0      
327m5466            U26   -AT7        A01X+055480Y+098591X0177Y    R180 S1      
317m5466            VIA   -    MD0100PA18X+077680Y+096097X0190Y         S0      
327m5466            R510  -2          A18X+077680Y+096097X0198Y0197     S2      
327m5467            J99   -62         A01X+078230Y+096097X0205Y0590R090 S1      
317m5467            VIA   -    MD0100PA00X+078230Y+096097X0190Y         S0      
327m5467            R510  -1          A18X+077995Y+096097X0198Y0197     S2      
317m5468            VIA   -    MD0080PA01X+153766Y+105357X0160Y         S0      
327m5468            U25   -BP6        A01X+153582Y+105252X0177Y    R180 S1      
317m5468            VIA   -    MD0100PA01X+175844Y+106470X0190Y         S0      
327m5468            J20   -87         A01X+175844Y+106470X0205Y0590R090 S1      
317m5469            VIA   -    MD0080PA01X+153211Y+104400X0160Y         S0      
327m5469            U25   -BL7        A01X+153027Y+104295X0177Y    R180 S1      
317m5469            VIA   -    MD0100PA01X+174230Y+105132X0190Y         S0      
327m5469            J20   -227        A01X+174230Y+105132X0205Y0590R090 S1      
317m5470            VIA   -    MD0080PA01X+153766Y+106632X0160Y         S0      
327m5470            U25   -BV6        A01X+153582Y+106528X0177Y    R180 S1      
317m5470            VIA   -    MD0100PA01X+175844Y+108478X0190Y         S0      
327m5470            J20   -93         A01X+175844Y+108478X0205Y0590R090 S1      
317m5471            VIA   -    MD0080PA01X+153396Y+114924X0160Y         S0      
327m5471            U25   -DD7        A01X+153212Y+114819X0177Y    R180 S1      
317m5471            VIA   -    MD0100PA01X+174230Y+123872X0190Y         S0      
327m5471            J20   -283        A01X+174230Y+123872X0205Y0590R090 S1      
317m5472            VIA   -    MD0080PA01X+153396Y+113010X0160Y         S0      
327m5472            U25   -CV7        A01X+153212Y+112906X0177Y    R180 S1      
317m5472            VIA   -    MD0100PA01X+174230Y+120191X0190Y         S0      
327m5472            J20   -272        A01X+174230Y+120191X0205Y0590R090 S1      
317m5473            VIA   -    MD0080PA01X+153396Y+111097X0160Y         S0      
327m5473            U25   -CM7        A01X+153212Y+110992X0177Y    R180 S1      
317m5473            VIA   -    MD0100PA01X+174230Y+116510X0190Y         S0      
327m5473            J20   -261        A01X+174230Y+116510X0205Y0590R090 S1      
317m5474            VIA   -    MD0080PA01X+153396Y+109184X0160Y         S0      
327m5474            U25   -CF7        A01X+153212Y+109079X0177Y    R180 S1      
317m5474            VIA   -    MD0100PA01X+174230Y+112829X0190Y         S0      
327m5474            J20   -250        A01X+174230Y+112829X0205Y0590R090 S1      
317m5475            VIA   -    MD0080PA01X+153396Y+107270X0160Y         S0      
327m5475            U25   -BY7        A01X+153212Y+107165X0177Y    R180 S1      
317m5475            VIA   -    MD0100PA01X+174230Y+109148X0190Y         S0      
327m5475            J20   -239        A01X+174230Y+109148X0205Y0590R090 S1      
317m5476            VIA   -    MD0080PA01X+153766Y+114286X0160Y         S0      
327m5476            U25   -DB6        A01X+153582Y+114181X0177Y    R180 S1      
317m5476            VIA   -    MD0100PA01X+175844Y+123203X0190Y         S0      
327m5476            J20   -137        A01X+175844Y+123203X0205Y0590R090 S1      
317m5477            VIA   -    MD0080PA01X+153766Y+112372X0160Y         S0      
327m5477            U25   -CT6        A01X+153582Y+112268X0177Y    R180 S1      
317m5477            VIA   -    MD0100PA01X+175844Y+119522X0190Y         S0      
327m5477            J20   -126        A01X+175844Y+119522X0205Y0590R090 S1      
317m5478            VIA   -    MD0080PA01X+153766Y+110459X0160Y         S0      
327m5478            U25   -CK6        A01X+153582Y+110354X0177Y    R180 S1      
317m5478            VIA   -    MD0100PA01X+175844Y+115841X0190Y         S0      
327m5478            J20   -115        A01X+175844Y+115841X0205Y0590R090 S1      
317m5479            VIA   -    MD0080PA01X+153766Y+108546X0160Y         S0      
327m5479            U25   -CD6        A01X+153582Y+108441X0177Y    R180 S1      
317m5479            VIA   -    MD0100PA01X+175844Y+112160X0190Y         S0      
327m5479            J20   -104        A01X+175844Y+112160X0205Y0590R090 S1      
317m5480            VIA   -    MD0080PA01X+153951Y+106951X0160Y         S0      
327m5480            U25   -BW5        A01X+153767Y+106846X0177Y    R180 S1      
317m5480            VIA   -    MD0100PA01X+175844Y+108813X0190Y         S0      
327m5480            J20   -94         A01X+175844Y+108813X0205Y0590R090 S1      
317m5481            VIA   -    MD0080PA01X+153211Y+114605X0160Y         S0      
327m5481            U25   -DC7        A01X+153027Y+114500X0177Y    R180 S1      
317m5481            VIA   -    MD0100PA01X+174230Y+123537X0190Y         S0      
327m5481            J20   -282        A01X+174230Y+123537X0205Y0590R090 S1      
317m5482            VIA   -    MD0080PA01X+153211Y+112691X0160Y         S0      
327m5482            U25   -CU7        A01X+153027Y+112587X0177Y    R180 S1      
317m5482            VIA   -    MD0100PA01X+174230Y+119856X0190Y         S0      
327m5482            J20   -271        A01X+174230Y+119856X0205Y0590R090 S1      
317m5483            VIA   -    MD0080PA01X+153211Y+110778X0160Y         S0      
327m5483            U25   -CL7        A01X+153027Y+110673X0177Y    R180 S1      
317m5483            VIA   -    MD0100PA01X+174230Y+116175X0190Y         S0      
327m5483            J20   -260        A01X+174230Y+116175X0205Y0590R090 S1      
317m5484            VIA   -    MD0080PA01X+153211Y+108865X0160Y         S0      
327m5484            U25   -CE7        A01X+153027Y+108760X0177Y    R180 S1      
317m5484            VIA   -    MD0100PA01X+174230Y+112494X0190Y         S0      
327m5484            J20   -249        A01X+174230Y+112494X0205Y0590R090 S1      
317m5485            VIA   -    MD0080PA01X+153211Y+106951X0160Y         S0      
327m5485            U25   -BW7        A01X+153027Y+106846X0177Y    R180 S1      
317m5485            VIA   -    MD0100PA01X+174230Y+108813X0190Y         S0      
327m5485            J20   -238        A01X+174230Y+108813X0205Y0590R090 S1      
317m5486            VIA   -    MD0080PA01X+153951Y+114605X0160Y         S0      
327m5486            U25   -DC5        A01X+153767Y+114500X0177Y    R180 S1      
317m5486            VIA   -    MD0100PA01X+175844Y+123537X0190Y         S0      
327m5486            J20   -138        A01X+175844Y+123537X0205Y0590R090 S1      
317m5487            VIA   -    MD0080PA01X+153951Y+112691X0160Y         S0      
327m5487            U25   -CU5        A01X+153767Y+112587X0177Y    R180 S1      
317m5487            VIA   -    MD0100PA01X+175844Y+119856X0190Y         S0      
327m5487            J20   -127        A01X+175844Y+119856X0205Y0590R090 S1      
317m5488            VIA   -    MD0080PA01X+153951Y+110778X0160Y         S0      
327m5488            U25   -CL5        A01X+153767Y+110673X0177Y    R180 S1      
317m5488            VIA   -    MD0100PA01X+175844Y+116175X0190Y         S0      
327m5488            J20   -116        A01X+175844Y+116175X0205Y0590R090 S1      
317m5489            VIA   -    MD0080PA01X+153951Y+108865X0160Y         S0      
327m5489            U25   -CE5        A01X+153767Y+108760X0177Y    R180 S1      
317m5489            VIA   -    MD0100PA01X+175844Y+112494X0190Y         S0      
327m5489            J20   -105        A01X+175844Y+112494X0205Y0590R090 S1      
317m5490            VIA   -    MD0080PA01X+153211Y+110140X0160Y         S0      
327m5490            U25   -CJ7        A01X+153027Y+110036X0177Y    R180 S1      
317m5490            VIA   -    MD0100PA01X+175844Y+115171X0190Y         S0      
327m5490            J20   -113        A01X+175844Y+115171X0205Y0590R090 S1      
317m5491            VIA   -    MD0080PA01X+153766Y+109821X0160Y         S0      
327m5491            U25   -CH6        A01X+153582Y+109717X0177Y    R180 S1      
317m5491            VIA   -    MD0100PA01X+175844Y+114502X0190Y         S0      
327m5491            J20   -111        A01X+175844Y+114502X0205Y0590R090 S1      
317m5492            VIA   -    MD0080PA01X+153396Y+109821X0160Y         S0      
327m5492            U25   -CH7        A01X+153212Y+109717X0177Y    R180 S1      
317m5492            VIA   -    MD0100PA01X+174230Y+114167X0190Y         S0      
327m5492            J20   -254        A01X+174230Y+114167X0205Y0590R090 S1      
317m5493            VIA   -    MD0080PA01X+153951Y+109502X0160Y         S0      
327m5493            U25   -CG5        A01X+153767Y+109398X0177Y    R180 S1      
317m5493            VIA   -    MD0100PA01X+174230Y+113498X0190Y         S0      
327m5493            J20   -252        A01X+174230Y+113498X0205Y0590R090 S1      
317m5494            VIA   -    MD0080PA01X+153211Y+109502X0160Y         S0      
327m5494            U25   -CG7        A01X+153027Y+109398X0177Y    R180 S1      
317m5494            VIA   -    MD0100PA01X+175844Y+113833X0190Y         S0      
327m5494            J20   -109        A01X+175844Y+113833X0205Y0590R090 S1      
317m5495            VIA   -    MD0080PA01X+153766Y+109184X0160Y         S0      
327m5495            U25   -CF6        A01X+153582Y+109079X0177Y    R180 S1      
317m5495            VIA   -    MD0100PA01X+175844Y+113163X0190Y         S0      
327m5495            J20   -107        A01X+175844Y+113163X0205Y0590R090 S1      
317m5496            VIA   -    MD0080PA01X+153396Y+108546X0160Y         S0      
327m5496            U25   -CD7        A01X+153212Y+108441X0177Y    R180 S1      
317m5496            VIA   -    MD0100PA01X+174230Y+111825X0190Y         S0      
327m5496            J20   -247        A01X+174230Y+111825X0205Y0590R090 S1      
317m5497            VIA   -    MD0080PA01X+153396Y+115561X0160Y         S0      
327m5497            U25   -DF7        A01X+153212Y+115457X0177Y    R180 S1      
317m5497            VIA   -    MD0100PA01X+174230Y+125211X0190Y         S0      
327m5497            J20   -287        A01X+174230Y+125211X0205Y0590R090 S1      
317m5498            VIA   -    MD0080PA01X+153951Y+115242X0160Y         S0      
327m5498            U25   -DE5        A01X+153767Y+115138X0177Y    R180 S1      
317m5498            VIA   -    MD0100PA01X+174230Y+124541X0190Y         S0      
327m5498            J20   -285        A01X+174230Y+124541X0205Y0590R090 S1      
317m5499            VIA   -    MD0080PA01X+153951Y+108227X0160Y         S0      
327m5499            U25   -CC5        A01X+153767Y+108122X0177Y    R180 S1      
317m5499            VIA   -    MD0100PA01X+174230Y+111156X0190Y         S0      
327m5499            J20   -245        A01X+174230Y+111156X0205Y0590R090 S1      
317m5500            VIA   -    MD0080PA01X+153211Y+115242X0160Y         S0      
327m5500            U25   -DE7        A01X+153027Y+115138X0177Y    R180 S1      
317m5500            VIA   -    MD0100PA01X+175844Y+124876X0190Y         S0      
327m5500            J20   -142        A01X+175844Y+124876X0205Y0590R090 S1      
317m5501            VIA   -    MD0080PA01X+153766Y+114924X0160Y         S0      
327m5501            U25   -DD6        A01X+153582Y+114819X0177Y    R180 S1      
317m5501            VIA   -    MD0100PA01X+175844Y+124207X0190Y         S0      
327m5501            J20   -140        A01X+175844Y+124207X0205Y0590R090 S1      
317m5502            VIA   -    MD0080PA01X+153396Y+114286X0160Y         S0      
327m5502            U25   -DB7        A01X+153212Y+114181X0177Y    R180 S1      
317m5502            VIA   -    MD0100PA01X+174230Y+122868X0190Y         S0      
327m5502            J20   -280        A01X+174230Y+122868X0205Y0590R090 S1      
317m5503            VIA   -    MD0080PA01X+153951Y+113967X0160Y         S0      
327m5503            U25   -DA5        A01X+153767Y+113862X0177Y    R180 S1      
317m5503            VIA   -    MD0100PA01X+174230Y+122199X0190Y         S0      
327m5503            J20   -278        A01X+174230Y+122199X0205Y0590R090 S1      
317m5504            VIA   -    MD0080PA01X+153211Y+113967X0160Y         S0      
327m5504            U25   -DA7        A01X+153027Y+113862X0177Y    R180 S1      
317m5504            VIA   -    MD0100PA01X+175844Y+122534X0190Y         S0      
327m5504            J20   -135        A01X+175844Y+122534X0205Y0590R090 S1      
317m5505            VIA   -    MD0080PA01X+153766Y+113648X0160Y         S0      
327m5505            U25   -CY6        A01X+153582Y+113543X0177Y    R180 S1      
317m5505            VIA   -    MD0100PA01X+175844Y+121864X0190Y         S0      
327m5505            J20   -133        A01X+175844Y+121864X0205Y0590R090 S1      
317m5506            VIA   -    MD0080PA01X+153396Y+113648X0160Y         S0      
327m5506            U25   -CY7        A01X+153212Y+113543X0177Y    R180 S1      
317m5506            VIA   -    MD0100PA01X+174230Y+121530X0190Y         S0      
327m5506            J20   -276        A01X+174230Y+121530X0205Y0590R090 S1      
317m5507            VIA   -    MD0080PA01X+153951Y+113329X0160Y         S0      
327m5507            U25   -CW5        A01X+153767Y+113224X0177Y    R180 S1      
317m5507            VIA   -    MD0100PA01X+174230Y+120860X0190Y         S0      
327m5507            J20   -274        A01X+174230Y+120860X0205Y0590R090 S1      
317m5508            VIA   -    MD0080PA01X+153211Y+113329X0160Y         S0      
327m5508            U25   -CW7        A01X+153027Y+113224X0177Y    R180 S1      
317m5508            VIA   -    MD0100PA01X+175844Y+121195X0190Y         S0      
327m5508            J20   -131        A01X+175844Y+121195X0205Y0590R090 S1      
317m5509            VIA   -    MD0080PA01X+153766Y+113010X0160Y         S0      
327m5509            U25   -CV6        A01X+153582Y+112906X0177Y    R180 S1      
317m5509            VIA   -    MD0100PA01X+175844Y+120526X0190Y         S0      
327m5509            J20   -129        A01X+175844Y+120526X0205Y0590R090 S1      
317m5510            VIA   -    MD0080PA01X+153211Y+108227X0160Y         S0      
327m5510            U25   -CC7        A01X+153027Y+108122X0177Y    R180 S1      
317m5510            VIA   -    MD0100PA01X+175844Y+111490X0190Y         S0      
327m5510            J20   -102        A01X+175844Y+111490X0205Y0590R090 S1      
317m5511            VIA   -    MD0080PA01X+153396Y+112372X0160Y         S0      
327m5511            U25   -CT7        A01X+153212Y+112268X0177Y    R180 S1      
317m5511            VIA   -    MD0100PA01X+174230Y+119187X0190Y         S0      
327m5511            J20   -269        A01X+174230Y+119187X0205Y0590R090 S1      
317m5512            VIA   -    MD0080PA01X+153951Y+112054X0160Y         S0      
327m5512            U25   -CR5        A01X+153767Y+111949X0177Y    R180 S1      
317m5512            VIA   -    MD0100PA01X+174230Y+118518X0190Y         S0      
327m5512            J20   -267        A01X+174230Y+118518X0205Y0590R090 S1      
317m5513            VIA   -    MD0080PA01X+153211Y+112054X0160Y         S0      
327m5513            U25   -CR7        A01X+153027Y+111949X0177Y    R180 S1      
317m5513            VIA   -    MD0100PA01X+175844Y+118852X0190Y         S0      
327m5513            J20   -124        A01X+175844Y+118852X0205Y0590R090 S1      
317m5514            VIA   -    MD0080PA01X+153766Y+111735X0160Y         S0      
327m5514            U25   -CP6        A01X+153582Y+111630X0177Y    R180 S1      
317m5514            VIA   -    MD0100PA01X+175844Y+118183X0190Y         S0      
327m5514            J20   -122        A01X+175844Y+118183X0205Y0590R090 S1      
317m5515            VIA   -    MD0080PA01X+153396Y+111735X0160Y         S0      
327m5515            U25   -CP7        A01X+153212Y+111630X0177Y    R180 S1      
317m5515            VIA   -    MD0100PA01X+174230Y+117848X0190Y         S0      
327m5515            J20   -265        A01X+174230Y+117848X0205Y0590R090 S1      
317m5516            VIA   -    MD0080PA01X+153951Y+111416X0160Y         S0      
327m5516            U25   -CN5        A01X+153767Y+111311X0177Y    R180 S1      
317m5516            VIA   -    MD0100PA01X+174230Y+117179X0190Y         S0      
327m5516            J20   -263        A01X+174230Y+117179X0205Y0590R090 S1      
317m5517            VIA   -    MD0080PA01X+153211Y+111416X0160Y         S0      
327m5517            U25   -CN7        A01X+153027Y+111311X0177Y    R180 S1      
317m5517            VIA   -    MD0100PA01X+175844Y+117514X0190Y         S0      
327m5517            J20   -120        A01X+175844Y+117514X0205Y0590R090 S1      
317m5518            VIA   -    MD0080PA01X+153766Y+111097X0160Y         S0      
327m5518            U25   -CM6        A01X+153582Y+110992X0177Y    R180 S1      
317m5518            VIA   -    MD0100PA01X+175844Y+116844X0190Y         S0      
327m5518            J20   -118        A01X+175844Y+116844X0205Y0590R090 S1      
317m5519            VIA   -    MD0080PA01X+153396Y+110459X0160Y         S0      
327m5519            U25   -CK7        A01X+153212Y+110354X0177Y    R180 S1      
317m5519            VIA   -    MD0100PA01X+174230Y+115506X0190Y         S0      
327m5519            J20   -258        A01X+174230Y+115506X0205Y0590R090 S1      
317m5520            VIA   -    MD0080PA01X+153951Y+110140X0160Y         S0      
327m5520            U25   -CJ5        A01X+153767Y+110036X0177Y    R180 S1      
317m5520            VIA   -    MD0100PA01X+174230Y+114837X0190Y         S0      
327m5520            J20   -256        A01X+174230Y+114837X0205Y0590R090 S1      
317m5521            VIA   -    MD0080PA01X+153766Y+107908X0160Y         S0      
327m5521            U25   -CB6        A01X+153582Y+107803X0177Y    R180 S1      
317m5521            VIA   -    MD0100PA01X+175844Y+110821X0190Y         S0      
327m5521            J20   -100        A01X+175844Y+110821X0205Y0590R090 S1      
317m5522            VIA   -    MD0080PA01X+153951Y+105038X0160Y         S0      
327m5522            U25   -BN5        A01X+153767Y+104933X0177Y    R180 S1      
317m5522            VIA   -    MD0100PA01X+174230Y+105801X0190Y         S0      
327m5522            J20   -229        A01X+174230Y+105801X0205Y0590R090 S1      
317m5523            VIA   -    MD0080PA01X+153396Y+104719X0160Y         S0      
327m5523            U25   -BM7        A01X+153212Y+104614X0177Y    R180 S1      
317m5523            VIA   -    MD0100PA01X+175844Y+105467X0190Y         S0      
327m5523            J20   -84         A01X+175844Y+105467X0205Y0590R090 S1      
317m5524            VIA   -    MD0080PA01X+153396Y+106632X0160Y         S0      
327m5524            U25   -BV7        A01X+153212Y+106528X0177Y    R180 S1      
317m5524            VIA   -    MD0100PA01X+174230Y+108144X0190Y         S0      
327m5524            J20   -236        A01X+174230Y+108144X0205Y0590R090 S1      
317m5525            VIA   -    MD0080PA01X+153951Y+106313X0160Y         S0      
327m5525            U25   -BU5        A01X+153767Y+106209X0177Y    R180 S1      
317m5525            VIA   -    MD0100PA01X+174230Y+107474X0190Y         S0      
327m5525            J20   -234        A01X+174230Y+107474X0205Y0590R090 S1      
317m5526            VIA   -    MD0080PA01X+153211Y+106313X0160Y         S0      
327m5526            U25   -BU7        A01X+153027Y+106209X0177Y    R180 S1      
317m5526            VIA   -    MD0100PA01X+175844Y+107809X0190Y         S0      
327m5526            J20   -91         A01X+175844Y+107809X0205Y0590R090 S1      
317m5527            VIA   -    MD0080PA01X+153766Y+105994X0160Y         S0      
327m5527            U25   -BT6        A01X+153582Y+105890X0177Y    R180 S1      
317m5527            VIA   -    MD0100PA01X+175844Y+107140X0190Y         S0      
327m5527            J20   -89         A01X+175844Y+107140X0205Y0590R090 S1      
317m5528            VIA   -    MD0080PA01X+153396Y+107908X0160Y         S0      
327m5528            U25   -CB7        A01X+153212Y+107803X0177Y    R180 S1      
317m5528            VIA   -    MD0100PA01X+174230Y+110486X0190Y         S0      
327m5528            J20   -243        A01X+174230Y+110486X0205Y0590R090 S1      
317m5529            VIA   -    MD0080PA01X+153951Y+107589X0160Y         S0      
327m5529            U25   -CA5        A01X+153767Y+107484X0177Y    R180 S1      
317m5529            VIA   -    MD0100PA01X+174230Y+109817X0190Y         S0      
327m5529            J20   -241        A01X+174230Y+109817X0205Y0590R090 S1      
317m5530            VIA   -    MD0080PA01X+153211Y+107589X0160Y         S0      
327m5530            U25   -CA7        A01X+153027Y+107484X0177Y    R180 S1      
317m5530            VIA   -    MD0100PA01X+175844Y+110152X0190Y         S0      
327m5530            J20   -98         A01X+175844Y+110152X0205Y0590R090 S1      
317m5531            VIA   -    MD0080PA01X+153766Y+107270X0160Y         S0      
327m5531            U25   -BY6        A01X+153582Y+107165X0177Y    R180 S1      
317m5531            VIA   -    MD0100PA01X+175844Y+109482X0190Y         S0      
327m5531            J20   -96         A01X+175844Y+109482X0205Y0590R090 S1      
317m5532            VIA   -    MD0080PA01X+153766Y+104081X0160Y         S0      
327m5532            U25   -BK6        A01X+153582Y+103976X0177Y    R180 S1      
317m5532            VIA   -    MD0100PA01X+175844Y+104797X0190Y         S0      
327m5532            J20   -82         A01X+175844Y+104797X0205Y0590R090 S1      
317m5533            VIA   -    MD0080PA01X+153396Y+104081X0160Y         S0      
327m5533            U25   -BK7        A01X+153212Y+103976X0177Y    R180 S1      
317m5533            VIA   -    MD0100PA01X+174230Y+104463X0190Y         S0      
327m5533            J20   -225        A01X+174230Y+104463X0205Y0590R090 S1      
317m5534            VIA   -    MD0080PA01X+153211Y+103762X0160Y         S0      
327m5534            U25   -BJ7        A01X+153027Y+103658X0177Y    R180 S1      
317m5534            VIA   -    MD0100PA01X+175844Y+104128X0190Y         S0      
327m5534            J20   -80         A01X+175844Y+104128X0205Y0590R090 S1      
317m5535            VIA   -    MD0080PA01X+153951Y+103762X0160Y         S0      
327m5535            U25   -BJ5        A01X+153767Y+103658X0177Y    R180 S1      
317m5535            VIA   -    MD0100PA01X+174230Y+103793X0190Y         S0      
327m5535            J20   -223        A01X+174230Y+103793X0205Y0590R090 S1      
317m5536            VIA   -    MD0080PA01X+153766Y+103443X0160Y         S0      
327m5536            U25   -BH6        A01X+153582Y+103339X0177Y    R180 S1      
317m5536            VIA   -    MD0100PA01X+175844Y+103459X0190Y         S0      
327m5536            J20   -78         A01X+175844Y+103459X0205Y0590R090 S1      
317m5537            VIA   -    MD0080PA01X+153396Y+103443X0160Y         S0      
327m5537            U25   -BH7        A01X+153212Y+103339X0177Y    R180 S1      
317m5537            VIA   -    MD0100PA01X+174230Y+103124X0190Y         S0      
327m5537            J20   -221        A01X+174230Y+103124X0205Y0590R090 S1      
317m5538            VIA   -    MD0080PA01X+153211Y+103124X0160Y         S0      
327m5538            U25   -BG7        A01X+153027Y+103020X0177Y    R180 S1      
317m5538            VIA   -    MD0100PA01X+175844Y+102789X0190Y         S0      
327m5538            J20   -76         A01X+175844Y+102789X0205Y0590R090 S1      
317m5539            VIA   -    MD0080PA01X+153211Y+105038X0160Y         S0      
327m5539            U25   -BN7        A01X+153027Y+104933X0177Y    R180 S1      
317m5539            VIA   -    MD0100PA01X+175844Y+106136X0190Y         S0      
327m5539            J20   -86         A01X+175844Y+106136X0205Y0590R090 S1      
317m5540            VIA   -    MD0080PA01X+153092Y+100718X0160Y    R180 S0      
327m5540            U25   -BC7        A01X+152909Y+100823X0177Y    R180 S1      
317m5540            VIA   -    MD0100PA01X+175844Y+100112X0190Y         S0      
327m5540            J20   -74         A01X+175844Y+100112X0205Y0590R090 S1      
317m5541            VIA   -    MD0080PA01X+153092Y+097529X0160Y    R180 S0      
327m5541            U25   -AN7        A01X+152909Y+097634X0177Y    R180 S1      
317m5541            VIA   -    MD0100PA01X+174230Y+094423X0190Y         S0      
327m5541            J20   -201        A01X+174230Y+094423X0205Y0590R090 S1      
317m5542            VIA   -    MD0080PA01X+153092Y+095616X0160Y    R180 S0      
327m5542            U25   -AG7        A01X+152909Y+095720X0177Y    R180 S1      
317m5542            VIA   -    MD0100PA01X+174230Y+090742X0190Y         S0      
327m5542            J20   -190        A01X+174230Y+090742X0205Y0590R090 S1      
317m5543            VIA   -    MD0080PA01X+153092Y+093702X0160Y    R180 S0      
327m5543            U25   -AA7        A01X+152909Y+093807X0177Y    R180 S1      
317m5543            VIA   -    MD0100PA01X+174230Y+087061X0190Y         S0      
327m5543            J20   -179        A01X+174230Y+087061X0205Y0590R090 S1      
317m5544            VIA   -    MD0080PA01X+153092Y+091789X0160Y    R180 S0      
327m5544            U25   -R7         A01X+152909Y+091894X0177Y    R180 S1      
317m5544            VIA   -    MD0100PA01X+174230Y+083380X0190Y         S0      
327m5544            J20   -168        A01X+174230Y+083380X0205Y0590R090 S1      
317m5545            VIA   -    MD0080PA01X+153092Y+089876X0160Y    R180 S0      
327m5545            U25   -J7         A01X+152909Y+089980X0177Y    R180 S1      
317m5545            VIA   -    MD0100PA01X+174230Y+079699X0190Y         S0      
327m5545            J20   -157        A01X+174230Y+079699X0205Y0590R090 S1      
317m5546            VIA   -    MD0080PA01X+153833Y+096891X0160Y    R180 S0      
327m5546            U25   -AL5        A01X+153649Y+096996X0177Y    R180 S1      
317m5546            VIA   -    MD0100PA01X+175844Y+093754X0190Y         S0      
327m5546            J20   -55         A01X+175844Y+093754X0205Y0590R090 S1      
317m5547            VIA   -    MD0080PA01X+153833Y+094978X0160Y    R180 S0      
327m5547            U25   -AE5        A01X+153649Y+095083X0177Y    R180 S1      
317m5547            VIA   -    MD0100PA01X+175844Y+090073X0190Y         S0      
327m5547            J20   -44         A01X+175844Y+090073X0205Y0590R090 S1      
317m5548            VIA   -    MD0080PA01X+153833Y+093065X0160Y    R180 S0      
327m5548            U25   -W5         A01X+153649Y+093169X0177Y    R180 S1      
317m5548            VIA   -    MD0100PA01X+175844Y+086392X0190Y         S0      
327m5548            J20   -33         A01X+175844Y+086392X0205Y0590R090 S1      
317m5549            VIA   -    MD0080PA01X+153833Y+091151X0160Y    R180 S0      
327m5549            U25   -N5         A01X+153649Y+091256X0177Y    R180 S1      
317m5549            VIA   -    MD0100PA01X+175844Y+082711X0190Y         S0      
327m5549            J20   -22         A01X+175844Y+082711X0205Y0590R090 S1      
317m5550            VIA   -    MD0080PA01X+153833Y+089238X0160Y    R180 S0      
327m5550            U25   -G5         A01X+153649Y+089343X0177Y    R180 S1      
317m5550            VIA   -    MD0100PA01X+175844Y+079030X0190Y         S0      
327m5550            J20   -11         A01X+175844Y+079030X0205Y0590R090 S1      
317m5551            VIA   -    MD0080PA01X+153278Y+097210X0160Y    R180 S0      
327m5551            U25   -AM7        A01X+153094Y+097315X0177Y    R180 S1      
317m5551            VIA   -    MD0100PA01X+174230Y+094089X0190Y         S0      
327m5551            J20   -200        A01X+174230Y+094089X0205Y0590R090 S1      
317m5552            VIA   -    MD0080PA01X+153278Y+095297X0160Y    R180 S0      
327m5552            U25   -AF7        A01X+153094Y+095402X0177Y    R180 S1      
317m5552            VIA   -    MD0100PA01X+174230Y+090408X0190Y         S0      
327m5552            J20   -189        A01X+174230Y+090408X0205Y0590R090 S1      
317m5553            VIA   -    MD0080PA01X+153278Y+093384X0160Y    R180 S0      
327m5553            U25   -Y7         A01X+153094Y+093488X0177Y    R180 S1      
317m5553            VIA   -    MD0100PA01X+174230Y+086726X0190Y         S0      
327m5553            J20   -178        A01X+174230Y+086726X0205Y0590R090 S1      
317m5554            VIA   -    MD0080PA01X+153278Y+091470X0160Y    R180 S0      
327m5554            U25   -P7         A01X+153094Y+091575X0177Y    R180 S1      
317m5554            VIA   -    MD0100PA01X+174230Y+083045X0190Y         S0      
327m5554            J20   -167        A01X+174230Y+083045X0205Y0590R090 S1      
317m5555            VIA   -    MD0080PA01X+153278Y+089557X0160Y    R180 S0      
327m5555            U25   -H7         A01X+153094Y+089662X0177Y    R180 S1      
317m5555            VIA   -    MD0100PA01X+174230Y+079364X0190Y         S0      
327m5555            J20   -156        A01X+174230Y+079364X0205Y0590R090 S1      
317m5556            VIA   -    MD0080PA01X+153648Y+097210X0160Y    R180 S0      
327m5556            U25   -AM6        A01X+153464Y+097315X0177Y    R180 S1      
317m5556            VIA   -    MD0100PA01X+175844Y+094089X0190Y         S0      
327m5556            J20   -56         A01X+175844Y+094089X0205Y0590R090 S1      
317m5557            VIA   -    MD0080PA01X+153648Y+095297X0160Y    R180 S0      
327m5557            U25   -AF6        A01X+153464Y+095402X0177Y    R180 S1      
317m5557            VIA   -    MD0100PA01X+175844Y+090408X0190Y         S0      
327m5557            J20   -45         A01X+175844Y+090408X0205Y0590R090 S1      
317m5558            VIA   -    MD0080PA01X+153648Y+093384X0160Y    R180 S0      
327m5558            U25   -Y6         A01X+153464Y+093488X0177Y    R180 S1      
317m5558            VIA   -    MD0100PA01X+175844Y+086726X0190Y         S0      
327m5558            J20   -34         A01X+175844Y+086726X0205Y0590R090 S1      
317m5559            VIA   -    MD0080PA01X+153648Y+091470X0160Y    R180 S0      
327m5559            U25   -P6         A01X+153464Y+091575X0177Y    R180 S1      
317m5559            VIA   -    MD0100PA01X+175844Y+083045X0190Y         S0      
327m5559            J20   -23         A01X+175844Y+083045X0205Y0590R090 S1      
317m5560            VIA   -    MD0080PA01X+153648Y+089557X0160Y    R180 S0      
327m5560            U25   -H6         A01X+153464Y+089662X0177Y    R180 S1      
317m5560            VIA   -    MD0100PA01X+175844Y+079364X0190Y         S0      
327m5560            J20   -12         A01X+175844Y+079364X0205Y0590R090 S1      
317m5561            VIA   -    MD0080PA01X+153278Y+090832X0160Y    R180 S0      
327m5561            U25   -M7         A01X+153094Y+090937X0177Y    R180 S1      
317m5561            VIA   -    MD0100PA01X+175844Y+082041X0190Y         S0      
327m5561            J20   -20         A01X+175844Y+082041X0205Y0590R090 S1      
317m5562            VIA   -    MD0080PA01X+153833Y+090513X0160Y    R180 S0      
327m5562            U25   -L5         A01X+153649Y+090618X0177Y    R180 S1      
317m5562            VIA   -    MD0100PA01X+175844Y+081372X0190Y         S0      
327m5562            J20   -18         A01X+175844Y+081372X0205Y0590R090 S1      
317m5563            VIA   -    MD0080PA01X+153092Y+090513X0160Y    R180 S0      
327m5563            U25   -L7         A01X+152909Y+090618X0177Y    R180 S1      
317m5563            VIA   -    MD0100PA01X+174230Y+081037X0190Y         S0      
327m5563            J20   -161        A01X+174230Y+081037X0205Y0590R090 S1      
317m5564            VIA   -    MD0080PA01X+153648Y+090195X0160Y    R180 S0      
327m5564            U25   -K6         A01X+153464Y+090299X0177Y    R180 S1      
317m5564            VIA   -    MD0100PA01X+174230Y+080368X0190Y         S0      
327m5564            J20   -159        A01X+174230Y+080368X0205Y0590R090 S1      
317m5565            VIA   -    MD0080PA01X+153278Y+090195X0160Y    R180 S0      
327m5565            U25   -K7         A01X+153094Y+090299X0177Y    R180 S1      
317m5565            VIA   -    MD0100PA01X+175844Y+080703X0190Y         S0      
327m5565            J20   -16         A01X+175844Y+080703X0205Y0590R090 S1      
317m5566            VIA   -    MD0080PA01X+153833Y+089876X0160Y    R180 S0      
327m5566            U25   -J5         A01X+153649Y+089980X0177Y    R180 S1      
317m5566            VIA   -    MD0100PA01X+175844Y+080034X0190Y         S0      
327m5566            J20   -14         A01X+175844Y+080034X0205Y0590R090 S1      
317m5567            VIA   -    MD0080PA01X+153092Y+089238X0160Y    R180 S0      
327m5567            U25   -G7         A01X+152909Y+089343X0177Y    R180 S1      
317m5567            VIA   -    MD0100PA01X+174230Y+078695X0190Y         S0      
327m5567            J20   -154        A01X+174230Y+078695X0205Y0590R090 S1      
317m5568            VIA   -    MD0080PA01X+153092Y+096254X0160Y    R180 S0      
327m5568            U25   -AJ7        A01X+152909Y+096358X0177Y    R180 S1      
317m5568            VIA   -    MD0100PA01X+174230Y+092081X0190Y         S0      
327m5568            J20   -194        A01X+174230Y+092081X0205Y0590R090 S1      
317m5569            VIA   -    MD0080PA01X+153648Y+095935X0160Y    R180 S0      
327m5569            U25   -AH6        A01X+153464Y+096039X0177Y    R180 S1      
317m5569            VIA   -    MD0100PA01X+174230Y+091411X0190Y         S0      
327m5569            J20   -192        A01X+174230Y+091411X0205Y0590R090 S1      
317m5570            VIA   -    MD0080PA01X+153648Y+088919X0160Y    R180 S0      
327m5570            U25   -F6         A01X+153464Y+089024X0177Y    R180 S1      
317m5570            VIA   -    MD0100PA01X+174230Y+078026X0190Y         S0      
327m5570            J20   -152        A01X+174230Y+078026X0205Y0590R090 S1      
317m5571            VIA   -    MD0080PA01X+153278Y+095935X0160Y    R180 S0      
327m5571            U25   -AH7        A01X+153094Y+096039X0177Y    R180 S1      
317m5571            VIA   -    MD0100PA01X+175844Y+091746X0190Y         S0      
327m5571            J20   -49         A01X+175844Y+091746X0205Y0590R090 S1      
317m5572            VIA   -    MD0080PA01X+153833Y+095616X0160Y    R180 S0      
327m5572            U25   -AG5        A01X+153649Y+095720X0177Y    R180 S1      
317m5572            VIA   -    MD0100PA01X+175844Y+091077X0190Y         S0      
327m5572            J20   -47         A01X+175844Y+091077X0205Y0590R090 S1      
317m5573            VIA   -    MD0080PA01X+153092Y+094978X0160Y    R180 S0      
327m5573            U25   -AE7        A01X+152909Y+095083X0177Y    R180 S1      
317m5573            VIA   -    MD0100PA01X+174230Y+089738X0190Y         S0      
327m5573            J20   -187        A01X+174230Y+089738X0205Y0590R090 S1      
317m5574            VIA   -    MD0080PA01X+153648Y+094659X0160Y    R180 S0      
327m5574            U25   -AD6        A01X+153464Y+094764X0177Y    R180 S1      
317m5574            VIA   -    MD0100PA01X+174230Y+089069X0190Y         S0      
327m5574            J20   -185        A01X+174230Y+089069X0205Y0590R090 S1      
317m5575            VIA   -    MD0080PA01X+153278Y+094659X0160Y    R180 S0      
327m5575            U25   -AD7        A01X+153094Y+094764X0177Y    R180 S1      
317m5575            VIA   -    MD0100PA01X+175844Y+089404X0190Y         S0      
327m5575            J20   -42         A01X+175844Y+089404X0205Y0590R090 S1      
317m5576            VIA   -    MD0080PA01X+153833Y+094340X0160Y    R180 S0      
327m5576            U25   -AC5        A01X+153649Y+094445X0177Y    R180 S1      
317m5576            VIA   -    MD0100PA01X+175844Y+088734X0190Y         S0      
327m5576            J20   -40         A01X+175844Y+088734X0205Y0590R090 S1      
317m5577            VIA   -    MD0080PA01X+153092Y+094340X0160Y    R180 S0      
327m5577            U25   -AC7        A01X+152909Y+094445X0177Y    R180 S1      
317m5577            VIA   -    MD0100PA01X+174230Y+088400X0190Y         S0      
327m5577            J20   -183        A01X+174230Y+088400X0205Y0590R090 S1      
317m5578            VIA   -    MD0080PA01X+153648Y+094021X0160Y    R180 S0      
327m5578            U25   -AB6        A01X+153464Y+094126X0177Y    R180 S1      
317m5578            VIA   -    MD0100PA01X+174230Y+087730X0190Y         S0      
327m5578            J20   -181        A01X+174230Y+087730X0205Y0590R090 S1      
317m5579            VIA   -    MD0080PA01X+153278Y+094021X0160Y    R180 S0      
327m5579            U25   -AB7        A01X+153094Y+094126X0177Y    R180 S1      
317m5579            VIA   -    MD0100PA01X+175844Y+088065X0190Y         S0      
327m5579            J20   -38         A01X+175844Y+088065X0205Y0590R090 S1      
317m5580            VIA   -    MD0080PA01X+153833Y+093702X0160Y    R180 S0      
327m5580            U25   -AA5        A01X+153649Y+093807X0177Y    R180 S1      
317m5580            VIA   -    MD0100PA01X+175844Y+087396X0190Y         S0      
327m5580            J20   -36         A01X+175844Y+087396X0205Y0590R090 S1      
317m5581            VIA   -    MD0080PA01X+153278Y+088919X0160Y    R180 S0      
327m5581            U25   -F7         A01X+153094Y+089024X0177Y    R180 S1      
317m5581            VIA   -    MD0100PA01X+175844Y+078360X0190Y         S0      
327m5581            J20   -9          A01X+175844Y+078360X0205Y0590R090 S1      
317m5582            VIA   -    MD0080PA01X+153092Y+093065X0160Y    R180 S0      
327m5582            U25   -W7         A01X+152909Y+093169X0177Y    R180 S1      
317m5582            VIA   -    MD0100PA01X+174230Y+086057X0190Y         S0      
327m5582            J20   -176        A01X+174230Y+086057X0205Y0590R090 S1      
317m5583            VIA   -    MD0080PA01X+153648Y+092746X0160Y    R180 S0      
327m5583            U25   -V6         A01X+153464Y+092850X0177Y    R180 S1      
317m5583            VIA   -    MD0100PA01X+174230Y+085388X0190Y         S0      
327m5583            J20   -174        A01X+174230Y+085388X0205Y0590R090 S1      
317m5584            VIA   -    MD0080PA01X+153278Y+092746X0160Y    R180 S0      
327m5584            U25   -V7         A01X+153094Y+092850X0177Y    R180 S1      
317m5584            VIA   -    MD0100PA01X+175844Y+085722X0190Y         S0      
327m5584            J20   -31         A01X+175844Y+085722X0205Y0590R090 S1      
317m5585            VIA   -    MD0080PA01X+153833Y+092427X0160Y    R180 S0      
327m5585            U25   -U5         A01X+153649Y+092532X0177Y    R180 S1      
317m5585            VIA   -    MD0100PA01X+175844Y+085053X0190Y         S0      
327m5585            J20   -29         A01X+175844Y+085053X0205Y0590R090 S1      
317m5586            VIA   -    MD0080PA01X+153092Y+092427X0160Y    R180 S0      
327m5586            U25   -U7         A01X+152909Y+092532X0177Y    R180 S1      
317m5586            VIA   -    MD0100PA01X+174230Y+084718X0190Y         S0      
327m5586            J20   -172        A01X+174230Y+084718X0205Y0590R090 S1      
317m5587            VIA   -    MD0080PA01X+153648Y+092108X0160Y    R180 S0      
327m5587            U25   -T6         A01X+153464Y+092213X0177Y    R180 S1      
317m5587            VIA   -    MD0100PA01X+174230Y+084049X0190Y         S0      
327m5587            J20   -170        A01X+174230Y+084049X0205Y0590R090 S1      
317m5588            VIA   -    MD0080PA01X+153278Y+092108X0160Y    R180 S0      
327m5588            U25   -T7         A01X+153094Y+092213X0177Y    R180 S1      
317m5588            VIA   -    MD0100PA01X+175844Y+084384X0190Y         S0      
327m5588            J20   -27         A01X+175844Y+084384X0205Y0590R090 S1      
317m5589            VIA   -    MD0080PA01X+153833Y+091789X0160Y    R180 S0      
327m5589            U25   -R5         A01X+153649Y+091894X0177Y    R180 S1      
317m5589            VIA   -    MD0100PA01X+175844Y+083715X0190Y         S0      
327m5589            J20   -25         A01X+175844Y+083715X0205Y0590R090 S1      
317m5590            VIA   -    MD0080PA01X+153092Y+091151X0160Y    R180 S0      
327m5590            U25   -N7         A01X+152909Y+091256X0177Y    R180 S1      
317m5590            VIA   -    MD0100PA01X+174230Y+082376X0190Y         S0      
327m5590            J20   -165        A01X+174230Y+082376X0205Y0590R090 S1      
317m5591            VIA   -    MD0080PA01X+153648Y+090832X0160Y    R180 S0      
327m5591            U25   -M6         A01X+153464Y+090937X0177Y    R180 S1      
327m5591            J20   -163        A01X+174230Y+081707X0205Y0590R090 S1      
317m5591            VIA   -    MD0100PA01X+174230Y+081707X0190Y         S0      
317m5592            VIA   -    MD0080PA01X+153833Y+088600X0160Y    R180 S0      
327m5592            U25   -E5         A01X+153649Y+088705X0177Y    R180 S1      
317m5592            VIA   -    MD0100PA01X+175844Y+077691X0190Y         S0      
327m5592            J20   -7          A01X+175844Y+077691X0205Y0590R090 S1      
317m5593            VIA   -    MD0080PA01X+153278Y+099124X0160Y    R180 S0      
327m5593            U25   -AV7        A01X+153094Y+099228X0177Y    R180 S1      
317m5593            VIA   -    MD0100PA01X+174230Y+097100X0190Y         S0      
327m5593            J20   -209        A01X+174230Y+097100X0205Y0590R090 S1      
317m5594            VIA   -    MD0080PA01X+153833Y+098805X0160Y    R180 S0      
327m5594            U25   -AU5        A01X+153649Y+098910X0177Y    R180 S1      
317m5594            VIA   -    MD0100PA01X+175844Y+096766X0190Y         S0      
327m5594            J20   -64         A01X+175844Y+096766X0205Y0590R090 S1      
317m5595            VIA   -    MD0080PA01X+153092Y+098167X0160Y    R180 S0      
327m5595            U25   -AR7        A01X+152909Y+098272X0177Y    R180 S1      
317m5595            VIA   -    MD0100PA01X+174230Y+095762X0190Y         S0      
327m5595            J20   -205        A01X+174230Y+095762X0205Y0590R090 S1      
317m5596            VIA   -    MD0080PA01X+153648Y+097848X0160Y    R180 S0      
327m5596            U25   -AP6        A01X+153464Y+097953X0177Y    R180 S1      
317m5596            VIA   -    MD0100PA01X+174230Y+095092X0190Y         S0      
327m5596            J20   -203        A01X+174230Y+095092X0205Y0590R090 S1      
317m5597            VIA   -    MD0080PA01X+153278Y+097848X0160Y    R180 S0      
327m5597            U25   -AP7        A01X+153094Y+097953X0177Y    R180 S1      
317m5597            VIA   -    MD0100PA01X+175844Y+095427X0190Y         S0      
327m5597            J20   -60         A01X+175844Y+095427X0205Y0590R090 S1      
317m5598            VIA   -    MD0080PA01X+153833Y+097529X0160Y    R180 S0      
327m5598            U25   -AN5        A01X+153649Y+097634X0177Y    R180 S1      
317m5598            VIA   -    MD0100PA01X+175844Y+094758X0190Y         S0      
327m5598            J20   -58         A01X+175844Y+094758X0205Y0590R090 S1      
317m5599            VIA   -    MD0080PA01X+153092Y+096891X0160Y    R180 S0      
327m5599            U25   -AL7        A01X+152909Y+096996X0177Y    R180 S1      
317m5599            VIA   -    MD0100PA01X+174230Y+093419X0190Y         S0      
327m5599            J20   -198        A01X+174230Y+093419X0205Y0590R090 S1      
317m5600            VIA   -    MD0080PA01X+153648Y+096572X0160Y    R180 S0      
327m5600            U25   -AK6        A01X+153464Y+096677X0177Y    R180 S1      
317m5600            VIA   -    MD0100PA01X+174230Y+092750X0190Y         S0      
327m5600            J20   -196        A01X+174230Y+092750X0205Y0590R090 S1      
317m5601            VIA   -    MD0080PA01X+153278Y+096572X0160Y    R180 S0      
327m5601            U25   -AK7        A01X+153094Y+096677X0177Y    R180 S1      
317m5601            VIA   -    MD0100PA01X+175844Y+093085X0190Y         S0      
327m5601            J20   -53         A01X+175844Y+093085X0205Y0590R090 S1      
317m5602            VIA   -    MD0080PA01X+153833Y+096254X0160Y    R180 S0      
327m5602            U25   -AJ5        A01X+153649Y+096358X0177Y    R180 S1      
317m5602            VIA   -    MD0100PA01X+175844Y+092415X0190Y         S0      
327m5602            J20   -51         A01X+175844Y+092415X0205Y0590R090 S1      
317m5603            VIA   -    MD0080PA01X+153278Y+100399X0160Y    R180 S0      
327m5603            U25   -BB7        A01X+153094Y+100504X0177Y    R180 S1      
317m5603            VIA   -    MD0100PA01X+175844Y+099443X0190Y         S0      
327m5603            J20   -72         A01X+175844Y+099443X0205Y0590R090 S1      
317m5604            VIA   -    MD0080PA01X+153648Y+100399X0160Y    R180 S0      
327m5604            U25   -BB6        A01X+153464Y+100504X0177Y    R180 S1      
317m5604            VIA   -    MD0100PA01X+174230Y+099108X0190Y         S0      
327m5604            J20   -215        A01X+174230Y+099108X0205Y0590R090 S1      
317m5605            VIA   -    MD0080PA01X+153833Y+100080X0160Y    R180 S0      
327m5605            U25   -BA5        A01X+153649Y+100185X0177Y    R180 S1      
317m5605            VIA   -    MD0100PA01X+175844Y+098774X0190Y         S0      
327m5605            J20   -70         A01X+175844Y+098774X0205Y0590R090 S1      
317m5606            VIA   -    MD0080PA01X+153092Y+100080X0160Y    R180 S0      
327m5606            U25   -BA7        A01X+152909Y+100185X0177Y    R180 S1      
317m5606            VIA   -    MD0100PA01X+174230Y+098439X0190Y         S0      
327m5606            J20   -213        A01X+174230Y+098439X0205Y0590R090 S1      
317m5607            VIA   -    MD0080PA01X+153278Y+099762X0160Y    R180 S0      
327m5607            U25   -AY7        A01X+153094Y+099866X0177Y    R180 S1      
317m5607            VIA   -    MD0100PA01X+175844Y+098104X0190Y         S0      
327m5607            J20   -68         A01X+175844Y+098104X0205Y0590R090 S1      
317m5608            VIA   -    MD0080PA01X+153648Y+099762X0160Y    R180 S0      
327m5608            U25   -AY6        A01X+153464Y+099866X0177Y    R180 S1      
317m5608            VIA   -    MD0100PA01X+174230Y+097770X0190Y         S0      
327m5608            J20   -211        A01X+174230Y+097770X0205Y0590R090 S1      
317m5609            VIA   -    MD0080PA01X+153833Y+099443X0160Y    R180 S0      
327m5609            U25   -AW5        A01X+153649Y+099547X0177Y    R180 S1      
317m5609            VIA   -    MD0100PA01X+175844Y+097435X0190Y         S0      
327m5609            J20   -66         A01X+175844Y+097435X0205Y0590R090 S1      
317m5610            VIA   -    MD0080PA01X+153092Y+098805X0160Y    R180 S0      
327m5610            U25   -AU7        A01X+152909Y+098910X0177Y    R180 S1      
317m5610            VIA   -    MD0100PA01X+174230Y+096431X0190Y         S0      
327m5610            J20   -207        A01X+174230Y+096431X0205Y0590R090 S1      
317m5611            VIA   -    MD0080PA01X+153833Y+100718X0160Y    R180 S0      
327m5611            U25   -BC5        A01X+153649Y+100823X0177Y    R180 S1      
317m5611            VIA   -    MD0100PA01X+174230Y+099778X0190Y         S0      
327m5611            J20   -217        A01X+174230Y+099778X0205Y0590R090 S1      
317m5612            VIA   -    MD0080PA01X+153648Y+101037X0160Y    R180 S0      
327m5612            U25   -BD6        A01X+153464Y+101142X0177Y    R180 S1      
317m5612            VIA   -    MD0100PA01X+174230Y+100112X0190Y         S0      
327m5612            J20   -218        A01X+174230Y+100112X0205Y0590R090 S1      
317m5613            VIA   -    MD0080PA01X+153278Y+098486X0160Y    R180 S0      
327m5613            U25   -AT7        A01X+153094Y+098591X0177Y    R180 S1      
317m5613            VIA   -    MD0100PA18X+175294Y+096096X0190Y         S0      
327m5613            R385  -2          A18X+175294Y+096096X0198Y0197     S2      
327m5614            J20   -62         A01X+175844Y+096096X0205Y0590R090 S1      
317m5614            VIA   -    MD0100PA00X+175844Y+096096X0190Y         S0      
327m5614            R385  -1          A18X+175609Y+096096X0198Y0197     S2      
317m5615            VIA   -    MD0080PA01X+052451Y+105357X0160Y         S0      
327m5615            U26   -BP16       A01X+052267Y+105252X0177Y    R180 S1      
317m5615            VIA   -    MD0100PA01X+075260Y+106471X0190Y         S0      
327m5615            J29   -87         A01X+075260Y+106471X0205Y0590R090 S1      
317m5616            VIA   -    MD0080PA01X+051896Y+104400X0160Y         S0      
327m5616            U26   -BL17       A01X+051712Y+104295X0177Y    R180 S1      
317m5616            VIA   -    MD0100PA01X+073646Y+105132X0190Y         S0      
327m5616            J29   -227        A01X+073646Y+105132X0205Y0590R090 S1      
317m5617            VIA   -    MD0080PA01X+052451Y+106632X0160Y         S0      
327m5617            U26   -BV16       A01X+052267Y+106528X0177Y    R180 S1      
317m5617            VIA   -    MD0100PA01X+075260Y+108478X0190Y         S0      
327m5617            J29   -93         A01X+075260Y+108478X0205Y0590R090 S1      
317m5618            VIA   -    MD0080PA01X+051710Y+114924X0160Y         S0      
327m5618            U26   -DD18       A01X+051527Y+114819X0177Y    R180 S1      
317m5618            VIA   -    MD0100PA01X+073646Y+123872X0190Y         S0      
327m5618            J29   -283        A01X+073646Y+123872X0205Y0590R090 S1      
317m5619            VIA   -    MD0080PA01X+051710Y+113010X0160Y         S0      
327m5619            U26   -CV18       A01X+051527Y+112906X0177Y    R180 S1      
317m5619            VIA   -    MD0100PA01X+073646Y+120191X0190Y         S0      
327m5619            J29   -272        A01X+073646Y+120191X0205Y0590R090 S1      
317m5620            VIA   -    MD0080PA01X+051710Y+111097X0160Y         S0      
327m5620            U26   -CM18       A01X+051527Y+110992X0177Y    R180 S1      
317m5620            VIA   -    MD0100PA01X+073646Y+116510X0190Y         S0      
327m5620            J29   -261        A01X+073646Y+116510X0205Y0590R090 S1      
317m5621            VIA   -    MD0080PA01X+051710Y+109184X0160Y         S0      
327m5621            U26   -CF18       A01X+051527Y+109079X0177Y    R180 S1      
317m5621            VIA   -    MD0100PA01X+073646Y+112829X0190Y         S0      
327m5621            J29   -250        A01X+073646Y+112829X0205Y0590R090 S1      
317m5622            VIA   -    MD0080PA01X+051710Y+107270X0160Y         S0      
327m5622            U26   -BY18       A01X+051527Y+107166X0177Y    R180 S1      
317m5622            VIA   -    MD0100PA01X+073646Y+109148X0190Y         S0      
327m5622            J29   -239        A01X+073646Y+109148X0205Y0590R090 S1      
317m5623            VIA   -    MD0080PA01X+052451Y+114286X0160Y         S0      
327m5623            U26   -DB16       A01X+052267Y+114181X0177Y    R180 S1      
317m5623            VIA   -    MD0100PA01X+075260Y+123203X0190Y         S0      
327m5623            J29   -137        A01X+075260Y+123203X0205Y0590R090 S1      
317m5624            VIA   -    MD0080PA01X+052451Y+112373X0160Y         S0      
327m5624            U26   -CT16       A01X+052267Y+112268X0177Y    R180 S1      
317m5624            VIA   -    MD0100PA01X+075260Y+119522X0190Y         S0      
327m5624            J29   -126        A01X+075260Y+119522X0205Y0590R090 S1      
317m5625            VIA   -    MD0080PA01X+052451Y+110459X0160Y         S0      
327m5625            U26   -CK16       A01X+052267Y+110354X0177Y    R180 S1      
317m5625            VIA   -    MD0100PA01X+075260Y+115841X0190Y         S0      
327m5625            J29   -115        A01X+075260Y+115841X0205Y0590R090 S1      
317m5626            VIA   -    MD0080PA01X+052451Y+108546X0160Y         S0      
327m5626            U26   -CD16       A01X+052267Y+108441X0177Y    R180 S1      
317m5626            VIA   -    MD0100PA01X+075260Y+112160X0190Y         S0      
327m5626            J29   -104        A01X+075260Y+112160X0205Y0590R090 S1      
317m5627            VIA   -    MD0080PA01X+052266Y+106951X0160Y         S0      
327m5627            U26   -BW16       A01X+052082Y+106847X0177Y    R180 S1      
317m5627            VIA   -    MD0100PA01X+075260Y+108813X0190Y         S0      
327m5627            J29   -94         A01X+075260Y+108813X0205Y0590R090 S1      
317m5628            VIA   -    MD0080PA01X+051896Y+114605X0160Y         S0      
327m5628            U26   -DC17       A01X+051712Y+114500X0177Y    R180 S1      
317m5628            VIA   -    MD0100PA01X+073646Y+123538X0190Y         S0      
327m5628            J29   -282        A01X+073646Y+123538X0205Y0590R090 S1      
317m5629            VIA   -    MD0080PA01X+051896Y+112692X0160Y         S0      
327m5629            U26   -CU17       A01X+051712Y+112587X0177Y    R180 S1      
317m5629            VIA   -    MD0100PA01X+073646Y+119856X0190Y         S0      
327m5629            J29   -271        A01X+073646Y+119856X0205Y0590R090 S1      
317m5630            VIA   -    MD0080PA01X+051896Y+110778X0160Y         S0      
327m5630            U26   -CL17       A01X+051712Y+110673X0177Y    R180 S1      
317m5630            VIA   -    MD0100PA01X+073646Y+116175X0190Y         S0      
327m5630            J29   -260        A01X+073646Y+116175X0205Y0590R090 S1      
317m5631            VIA   -    MD0080PA01X+051896Y+108865X0160Y         S0      
327m5631            U26   -CE17       A01X+051712Y+108760X0177Y    R180 S1      
317m5631            VIA   -    MD0100PA01X+073646Y+112494X0190Y         S0      
327m5631            J29   -249        A01X+073646Y+112494X0205Y0590R090 S1      
317m5632            VIA   -    MD0080PA01X+051896Y+106951X0160Y         S0      
327m5632            U26   -BW17       A01X+051712Y+106847X0177Y    R180 S1      
317m5632            VIA   -    MD0100PA01X+073646Y+108813X0190Y         S0      
327m5632            J29   -238        A01X+073646Y+108813X0205Y0590R090 S1      
317m5633            VIA   -    MD0080PA01X+052266Y+114605X0160Y         S0      
327m5633            U26   -DC16       A01X+052082Y+114500X0177Y    R180 S1      
317m5633            VIA   -    MD0100PA01X+075260Y+123538X0190Y         S0      
327m5633            J29   -138        A01X+075260Y+123538X0205Y0590R090 S1      
317m5634            VIA   -    MD0080PA01X+052266Y+112692X0160Y         S0      
327m5634            U26   -CU16       A01X+052082Y+112587X0177Y    R180 S1      
317m5634            VIA   -    MD0100PA01X+075260Y+119856X0190Y         S0      
327m5634            J29   -127        A01X+075260Y+119856X0205Y0590R090 S1      
317m5635            VIA   -    MD0080PA01X+052266Y+110778X0160Y         S0      
327m5635            U26   -CL16       A01X+052082Y+110673X0177Y    R180 S1      
317m5635            VIA   -    MD0100PA01X+075260Y+116175X0190Y         S0      
327m5635            J29   -116        A01X+075260Y+116175X0205Y0590R090 S1      
317m5636            VIA   -    MD0080PA01X+052266Y+108865X0160Y         S0      
327m5636            U26   -CE16       A01X+052082Y+108760X0177Y    R180 S1      
317m5636            VIA   -    MD0100PA01X+075260Y+112494X0190Y         S0      
327m5636            J29   -105        A01X+075260Y+112494X0205Y0590R090 S1      
317m5637            VIA   -    MD0080PA01X+051896Y+110140X0160Y         S0      
327m5637            U26   -CJ17       A01X+051712Y+110036X0177Y    R180 S1      
317m5637            VIA   -    MD0100PA01X+075260Y+115171X0190Y         S0      
327m5637            J29   -113        A01X+075260Y+115171X0205Y0590R090 S1      
317m5638            VIA   -    MD0080PA01X+052451Y+109821X0160Y         S0      
327m5638            U26   -CH16       A01X+052267Y+109717X0177Y    R180 S1      
317m5638            VIA   -    MD0100PA01X+075260Y+114502X0190Y         S0      
327m5638            J29   -111        A01X+075260Y+114502X0205Y0590R090 S1      
317m5639            VIA   -    MD0080PA01X+051710Y+109821X0160Y         S0      
327m5639            U26   -CH18       A01X+051527Y+109717X0177Y    R180 S1      
317m5639            VIA   -    MD0100PA01X+073646Y+114168X0190Y         S0      
327m5639            J29   -254        A01X+073646Y+114168X0205Y0590R090 S1      
317m5640            VIA   -    MD0080PA01X+052266Y+109502X0160Y         S0      
327m5640            U26   -CG16       A01X+052082Y+109398X0177Y    R180 S1      
317m5640            VIA   -    MD0100PA01X+073646Y+113498X0190Y         S0      
327m5640            J29   -252        A01X+073646Y+113498X0205Y0590R090 S1      
317m5641            VIA   -    MD0080PA01X+051896Y+109502X0160Y         S0      
327m5641            U26   -CG17       A01X+051712Y+109398X0177Y    R180 S1      
317m5641            VIA   -    MD0100PA01X+075260Y+113833X0190Y         S0      
327m5641            J29   -109        A01X+075260Y+113833X0205Y0590R090 S1      
317m5642            VIA   -    MD0080PA01X+052451Y+109184X0160Y         S0      
327m5642            U26   -CF16       A01X+052267Y+109079X0177Y    R180 S1      
317m5642            VIA   -    MD0100PA01X+075260Y+113164X0190Y         S0      
327m5642            J29   -107        A01X+075260Y+113164X0205Y0590R090 S1      
317m5643            VIA   -    MD0080PA01X+051710Y+108546X0160Y         S0      
327m5643            U26   -CD18       A01X+051527Y+108441X0177Y    R180 S1      
317m5643            VIA   -    MD0100PA01X+073646Y+111825X0190Y         S0      
327m5643            J29   -247        A01X+073646Y+111825X0205Y0590R090 S1      
317m5644            VIA   -    MD0080PA01X+052451Y+115562X0160Y         S0      
327m5644            U26   -DF16       A01X+052267Y+115457X0177Y    R180 S1      
317m5644            VIA   -    MD0100PA01X+073646Y+125211X0190Y         S0      
327m5644            J29   -287        A01X+073646Y+125211X0205Y0590R090 S1      
317m5645            VIA   -    MD0080PA01X+052266Y+115243X0160Y         S0      
327m5645            U26   -DE16       A01X+052082Y+115138X0177Y    R180 S1      
317m5645            VIA   -    MD0100PA01X+073646Y+124542X0190Y         S0      
327m5645            J29   -285        A01X+073646Y+124542X0205Y0590R090 S1      
317m5646            VIA   -    MD0080PA01X+052266Y+108227X0160Y         S0      
327m5646            U26   -CC16       A01X+052082Y+108122X0177Y    R180 S1      
317m5646            VIA   -    MD0100PA01X+073646Y+111156X0190Y         S0      
327m5646            J29   -245        A01X+073646Y+111156X0205Y0590R090 S1      
317m5647            VIA   -    MD0080PA01X+051896Y+115243X0160Y         S0      
327m5647            U26   -DE17       A01X+051712Y+115138X0177Y    R180 S1      
317m5647            VIA   -    MD0100PA01X+075260Y+124876X0190Y         S0      
327m5647            J29   -142        A01X+075260Y+124876X0205Y0590R090 S1      
317m5648            VIA   -    MD0080PA01X+052451Y+114924X0160Y         S0      
327m5648            U26   -DD16       A01X+052267Y+114819X0177Y    R180 S1      
317m5648            VIA   -    MD0100PA01X+075260Y+124207X0190Y         S0      
327m5648            J29   -140        A01X+075260Y+124207X0205Y0590R090 S1      
317m5649            VIA   -    MD0080PA01X+051710Y+114286X0160Y         S0      
327m5649            U26   -DB18       A01X+051527Y+114181X0177Y    R180 S1      
317m5649            VIA   -    MD0100PA01X+073646Y+122868X0190Y         S0      
327m5649            J29   -280        A01X+073646Y+122868X0205Y0590R090 S1      
317m5650            VIA   -    MD0080PA01X+052266Y+113967X0160Y         S0      
327m5650            U26   -DA16       A01X+052082Y+113862X0177Y    R180 S1      
317m5650            VIA   -    MD0100PA01X+073646Y+122199X0190Y         S0      
327m5650            J29   -278        A01X+073646Y+122199X0205Y0590R090 S1      
317m5651            VIA   -    MD0080PA01X+051896Y+113967X0160Y         S0      
327m5651            U26   -DA17       A01X+051712Y+113862X0177Y    R180 S1      
317m5651            VIA   -    MD0100PA01X+075260Y+122534X0190Y         S0      
327m5651            J29   -135        A01X+075260Y+122534X0205Y0590R090 S1      
317m5652            VIA   -    MD0080PA01X+052451Y+113648X0160Y         S0      
327m5652            U26   -CY16       A01X+052267Y+113543X0177Y    R180 S1      
317m5652            VIA   -    MD0100PA01X+075260Y+121864X0190Y         S0      
327m5652            J29   -133        A01X+075260Y+121864X0205Y0590R090 S1      
317m5653            VIA   -    MD0080PA01X+051710Y+113648X0160Y         S0      
327m5653            U26   -CY18       A01X+051527Y+113543X0177Y    R180 S1      
317m5653            VIA   -    MD0100PA01X+073646Y+121530X0190Y         S0      
327m5653            J29   -276        A01X+073646Y+121530X0205Y0590R090 S1      
317m5654            VIA   -    MD0080PA01X+052266Y+113329X0160Y         S0      
327m5654            U26   -CW16       A01X+052082Y+113225X0177Y    R180 S1      
317m5654            VIA   -    MD0100PA01X+073646Y+120860X0190Y         S0      
327m5654            J29   -274        A01X+073646Y+120860X0205Y0590R090 S1      
317m5655            VIA   -    MD0080PA01X+051896Y+113329X0160Y         S0      
327m5655            U26   -CW17       A01X+051712Y+113225X0177Y    R180 S1      
317m5655            VIA   -    MD0100PA01X+075260Y+121195X0190Y         S0      
327m5655            J29   -131        A01X+075260Y+121195X0205Y0590R090 S1      
317m5656            VIA   -    MD0080PA01X+052451Y+113010X0160Y         S0      
327m5656            U26   -CV16       A01X+052267Y+112906X0177Y    R180 S1      
317m5656            VIA   -    MD0100PA01X+075260Y+120526X0190Y         S0      
327m5656            J29   -129        A01X+075260Y+120526X0205Y0590R090 S1      
317m5657            VIA   -    MD0080PA01X+051896Y+108227X0160Y         S0      
327m5657            U26   -CC17       A01X+051712Y+108122X0177Y    R180 S1      
317m5657            VIA   -    MD0100PA01X+075260Y+111490X0190Y         S0      
327m5657            J29   -102        A01X+075260Y+111490X0205Y0590R090 S1      
317m5658            VIA   -    MD0080PA01X+051710Y+112373X0160Y         S0      
327m5658            U26   -CT18       A01X+051527Y+112268X0177Y    R180 S1      
317m5658            VIA   -    MD0100PA01X+073646Y+119187X0190Y         S0      
327m5658            J29   -269        A01X+073646Y+119187X0205Y0590R090 S1      
317m5659            VIA   -    MD0080PA01X+052266Y+112054X0160Y         S0      
327m5659            U26   -CR16       A01X+052082Y+111949X0177Y    R180 S1      
317m5659            VIA   -    MD0100PA01X+073646Y+118518X0190Y         S0      
327m5659            J29   -267        A01X+073646Y+118518X0205Y0590R090 S1      
317m5660            VIA   -    MD0080PA01X+051896Y+112054X0160Y         S0      
327m5660            U26   -CR17       A01X+051712Y+111949X0177Y    R180 S1      
317m5660            VIA   -    MD0100PA01X+075260Y+118852X0190Y         S0      
327m5660            J29   -124        A01X+075260Y+118852X0205Y0590R090 S1      
317m5661            VIA   -    MD0080PA01X+052451Y+111735X0160Y         S0      
327m5661            U26   -CP16       A01X+052267Y+111630X0177Y    R180 S1      
317m5661            VIA   -    MD0100PA01X+075260Y+118183X0190Y         S0      
327m5661            J29   -122        A01X+075260Y+118183X0205Y0590R090 S1      
317m5662            VIA   -    MD0080PA01X+051710Y+111735X0160Y         S0      
327m5662            U26   -CP18       A01X+051527Y+111630X0177Y    R180 S1      
317m5662            VIA   -    MD0100PA01X+073646Y+117849X0190Y         S0      
327m5662            J29   -265        A01X+073646Y+117849X0205Y0590R090 S1      
317m5663            VIA   -    MD0080PA01X+052266Y+111416X0160Y         S0      
327m5663            U26   -CN16       A01X+052082Y+111311X0177Y    R180 S1      
317m5663            VIA   -    MD0100PA01X+073646Y+117179X0190Y         S0      
327m5663            J29   -263        A01X+073646Y+117179X0205Y0590R090 S1      
317m5664            VIA   -    MD0080PA01X+051896Y+111416X0160Y         S0      
327m5664            U26   -CN17       A01X+051712Y+111311X0177Y    R180 S1      
317m5664            VIA   -    MD0100PA01X+075260Y+117514X0190Y         S0      
327m5664            J29   -120        A01X+075260Y+117514X0205Y0590R090 S1      
317m5665            VIA   -    MD0080PA01X+052451Y+111097X0160Y         S0      
327m5665            U26   -CM16       A01X+052267Y+110992X0177Y    R180 S1      
317m5665            VIA   -    MD0100PA01X+075260Y+116845X0190Y         S0      
327m5665            J29   -118        A01X+075260Y+116845X0205Y0590R090 S1      
317m5666            VIA   -    MD0080PA01X+051710Y+110459X0160Y         S0      
327m5666            U26   -CK18       A01X+051527Y+110354X0177Y    R180 S1      
317m5666            VIA   -    MD0100PA01X+073646Y+115506X0190Y         S0      
327m5666            J29   -258        A01X+073646Y+115506X0205Y0590R090 S1      
317m5667            VIA   -    MD0080PA01X+052266Y+110140X0160Y         S0      
327m5667            U26   -CJ16       A01X+052082Y+110036X0177Y    R180 S1      
317m5667            VIA   -    MD0100PA01X+073646Y+114837X0190Y         S0      
327m5667            J29   -256        A01X+073646Y+114837X0205Y0590R090 S1      
317m5668            VIA   -    MD0080PA01X+052451Y+107908X0160Y         S0      
327m5668            U26   -CB16       A01X+052267Y+107803X0177Y    R180 S1      
317m5668            VIA   -    MD0100PA01X+075260Y+110821X0190Y         S0      
327m5668            J29   -100        A01X+075260Y+110821X0205Y0590R090 S1      
317m5669            VIA   -    MD0080PA01X+052266Y+105038X0160Y         S0      
327m5669            U26   -BN16       A01X+052082Y+104933X0177Y    R180 S1      
317m5669            VIA   -    MD0100PA01X+073646Y+105801X0190Y         S0      
327m5669            J29   -229        A01X+073646Y+105801X0205Y0590R090 S1      
317m5670            VIA   -    MD0080PA01X+051710Y+104719X0160Y         S0      
327m5670            U26   -BM18       A01X+051527Y+104614X0177Y    R180 S1      
317m5670            VIA   -    MD0100PA01X+075260Y+105467X0190Y         S0      
327m5670            J29   -84         A01X+075260Y+105467X0205Y0590R090 S1      
317m5671            VIA   -    MD0080PA01X+051710Y+106632X0160Y         S0      
327m5671            U26   -BV18       A01X+051527Y+106528X0177Y    R180 S1      
317m5671            VIA   -    MD0100PA01X+073646Y+108144X0190Y         S0      
327m5671            J29   -236        A01X+073646Y+108144X0205Y0590R090 S1      
317m5672            VIA   -    MD0080PA01X+052266Y+106314X0160Y         S0      
327m5672            U26   -BU16       A01X+052082Y+106209X0177Y    R180 S1      
317m5672            VIA   -    MD0100PA01X+073646Y+107474X0190Y         S0      
327m5672            J29   -234        A01X+073646Y+107474X0205Y0590R090 S1      
317m5673            VIA   -    MD0080PA01X+051896Y+106314X0160Y         S0      
327m5673            U26   -BU17       A01X+051712Y+106209X0177Y    R180 S1      
317m5673            VIA   -    MD0100PA01X+075260Y+107809X0190Y         S0      
327m5673            J29   -91         A01X+075260Y+107809X0205Y0590R090 S1      
317m5674            VIA   -    MD0080PA01X+052451Y+105995X0160Y         S0      
327m5674            U26   -BT16       A01X+052267Y+105890X0177Y    R180 S1      
317m5674            VIA   -    MD0100PA01X+075260Y+107140X0190Y         S0      
327m5674            J29   -89         A01X+075260Y+107140X0205Y0590R090 S1      
317m5675            VIA   -    MD0080PA01X+051710Y+107908X0160Y         S0      
327m5675            U26   -CB18       A01X+051527Y+107803X0177Y    R180 S1      
317m5675            VIA   -    MD0100PA01X+073646Y+110486X0190Y         S0      
327m5675            J29   -243        A01X+073646Y+110486X0205Y0590R090 S1      
317m5676            VIA   -    MD0080PA01X+052266Y+107589X0160Y         S0      
327m5676            U26   -CA16       A01X+052082Y+107484X0177Y    R180 S1      
317m5676            VIA   -    MD0100PA01X+073646Y+109817X0190Y         S0      
327m5676            J29   -241        A01X+073646Y+109817X0205Y0590R090 S1      
317m5677            VIA   -    MD0080PA01X+051896Y+107589X0160Y         S0      
327m5677            U26   -CA17       A01X+051712Y+107484X0177Y    R180 S1      
317m5677            VIA   -    MD0100PA01X+075260Y+110152X0190Y         S0      
327m5677            J29   -98         A01X+075260Y+110152X0205Y0590R090 S1      
317m5678            VIA   -    MD0080PA01X+052451Y+107270X0160Y         S0      
327m5678            U26   -BY16       A01X+052267Y+107166X0177Y    R180 S1      
317m5678            VIA   -    MD0100PA01X+075260Y+109482X0190Y         S0      
327m5678            J29   -96         A01X+075260Y+109482X0205Y0590R090 S1      
317m5679            VIA   -    MD0080PA01X+052451Y+104081X0160Y         S0      
327m5679            U26   -BK16       A01X+052267Y+103976X0177Y    R180 S1      
317m5679            VIA   -    MD0100PA01X+075260Y+104797X0190Y         S0      
327m5679            J29   -82         A01X+075260Y+104797X0205Y0590R090 S1      
317m5680            VIA   -    MD0080PA01X+051710Y+104081X0160Y         S0      
327m5680            U26   -BK18       A01X+051527Y+103976X0177Y    R180 S1      
317m5680            VIA   -    MD0100PA01X+073646Y+104463X0190Y         S0      
327m5680            J29   -225        A01X+073646Y+104463X0205Y0590R090 S1      
317m5681            VIA   -    MD0080PA01X+051896Y+103762X0160Y         S0      
327m5681            U26   -BJ17       A01X+051712Y+103658X0177Y    R180 S1      
317m5681            VIA   -    MD0100PA01X+075260Y+104128X0190Y         S0      
327m5681            J29   -80         A01X+075260Y+104128X0205Y0590R090 S1      
317m5682            VIA   -    MD0080PA01X+052266Y+103762X0160Y         S0      
327m5682            U26   -BJ16       A01X+052082Y+103658X0177Y    R180 S1      
317m5682            VIA   -    MD0100PA01X+073646Y+103793X0190Y         S0      
327m5682            J29   -223        A01X+073646Y+103793X0205Y0590R090 S1      
317m5683            VIA   -    MD0080PA01X+052451Y+103443X0160Y         S0      
327m5683            U26   -BH16       A01X+052267Y+103339X0177Y    R180 S1      
317m5683            VIA   -    MD0100PA01X+075260Y+103459X0190Y         S0      
327m5683            J29   -78         A01X+075260Y+103459X0205Y0590R090 S1      
317m5684            VIA   -    MD0080PA01X+051710Y+103443X0160Y         S0      
327m5684            U26   -BH18       A01X+051527Y+103339X0177Y    R180 S1      
317m5684            VIA   -    MD0100PA01X+073646Y+103124X0190Y         S0      
327m5684            J29   -221        A01X+073646Y+103124X0205Y0590R090 S1      
317m5685            VIA   -    MD0080PA01X+051896Y+103124X0160Y         S0      
327m5685            U26   -BG17       A01X+051712Y+103020X0177Y    R180 S1      
317m5685            VIA   -    MD0100PA01X+075260Y+102790X0190Y         S0      
327m5685            J29   -76         A01X+075260Y+102790X0205Y0590R090 S1      
317m5686            VIA   -    MD0080PA01X+051896Y+105038X0160Y         S0      
327m5686            U26   -BN17       A01X+051712Y+104933X0177Y    R180 S1      
317m5686            VIA   -    MD0100PA01X+075260Y+106136X0190Y         S0      
327m5686            J29   -86         A01X+075260Y+106136X0205Y0590R090 S1      
317m5687            VIA   -    MD0080PA01X+051778Y+100718X0160Y    R180 S0      
327m5687            U26   -BC17       A01X+051594Y+100823X0177Y    R180 S1      
317m5687            VIA   -    MD0100PA01X+075260Y+100112X0190Y         S0      
327m5687            J29   -74         A01X+075260Y+100112X0205Y0590R090 S1      
317m5688            VIA   -    MD0080PA01X+051778Y+097529X0160Y    R180 S0      
327m5688            U26   -AN17       A01X+051594Y+097634X0177Y    R180 S1      
317m5688            VIA   -    MD0100PA01X+073646Y+094423X0190Y         S0      
327m5688            J29   -201        A01X+073646Y+094423X0205Y0590R090 S1      
317m5689            VIA   -    MD0080PA01X+051778Y+095616X0160Y    R180 S0      
327m5689            U26   -AG17       A01X+051594Y+095721X0177Y    R180 S1      
317m5689            VIA   -    MD0100PA01X+073646Y+090742X0190Y         S0      
327m5689            J29   -190        A01X+073646Y+090742X0205Y0590R090 S1      
317m5690            VIA   -    MD0080PA01X+051778Y+093702X0160Y    R180 S0      
327m5690            U26   -AA17       A01X+051594Y+093807X0177Y    R180 S1      
317m5690            VIA   -    MD0100PA01X+073646Y+087061X0190Y         S0      
327m5690            J29   -179        A01X+073646Y+087061X0205Y0590R090 S1      
317m5691            VIA   -    MD0080PA01X+051778Y+091789X0160Y    R180 S0      
327m5691            U26   -R17        A01X+051594Y+091894X0177Y    R180 S1      
317m5691            VIA   -    MD0100PA01X+073646Y+083380X0190Y         S0      
327m5691            J29   -168        A01X+073646Y+083380X0205Y0590R090 S1      
317m5692            VIA   -    MD0080PA01X+051778Y+089876X0160Y    R180 S0      
327m5692            U26   -J17        A01X+051594Y+089980X0177Y    R180 S1      
317m5692            VIA   -    MD0100PA01X+073646Y+079699X0190Y         S0      
327m5692            J29   -157        A01X+073646Y+079699X0205Y0590R090 S1      
317m5693            VIA   -    MD0080PA01X+052148Y+096892X0160Y    R180 S0      
327m5693            U26   -AL16       A01X+051964Y+096996X0177Y    R180 S1      
317m5693            VIA   -    MD0100PA01X+075260Y+093754X0190Y         S0      
327m5693            J29   -55         A01X+075260Y+093754X0205Y0590R090 S1      
317m5694            VIA   -    MD0080PA01X+052148Y+094978X0160Y    R180 S0      
327m5694            U26   -AE16       A01X+051964Y+095083X0177Y    R180 S1      
317m5694            VIA   -    MD0100PA01X+075260Y+090073X0190Y         S0      
327m5694            J29   -44         A01X+075260Y+090073X0205Y0590R090 S1      
317m5695            VIA   -    MD0080PA01X+052148Y+093065X0160Y    R180 S0      
327m5695            U26   -W16        A01X+051964Y+093169X0177Y    R180 S1      
317m5695            VIA   -    MD0100PA01X+075260Y+086392X0190Y         S0      
327m5695            J29   -33         A01X+075260Y+086392X0205Y0590R090 S1      
317m5696            VIA   -    MD0080PA01X+052148Y+091151X0160Y    R180 S0      
327m5696            U26   -N16        A01X+051964Y+091256X0177Y    R180 S1      
317m5696            VIA   -    MD0100PA01X+075260Y+082711X0190Y         S0      
327m5696            J29   -22         A01X+075260Y+082711X0205Y0590R090 S1      
317m5697            VIA   -    MD0080PA01X+052148Y+089238X0160Y    R180 S0      
327m5697            U26   -G16        A01X+051964Y+089343X0177Y    R180 S1      
317m5697            VIA   -    MD0100PA01X+075260Y+079030X0190Y         S0      
327m5697            J29   -11         A01X+075260Y+079030X0205Y0590R090 S1      
317m5698            VIA   -    MD0080PA01X+051592Y+097210X0160Y    R180 S0      
327m5698            U26   -AM18       A01X+051409Y+097315X0177Y    R180 S1      
317m5698            VIA   -    MD0100PA01X+073646Y+094089X0190Y         S0      
327m5698            J29   -200        A01X+073646Y+094089X0205Y0590R090 S1      
317m5699            VIA   -    MD0080PA01X+051592Y+095297X0160Y    R180 S0      
327m5699            U26   -AF18       A01X+051409Y+095402X0177Y    R180 S1      
317m5699            VIA   -    MD0100PA01X+073646Y+090408X0190Y         S0      
327m5699            J29   -189        A01X+073646Y+090408X0205Y0590R090 S1      
317m5700            VIA   -    MD0080PA01X+051592Y+093384X0160Y    R180 S0      
327m5700            U26   -Y18        A01X+051409Y+093488X0177Y    R180 S1      
317m5700            VIA   -    MD0100PA01X+073646Y+086726X0190Y         S0      
327m5700            J29   -178        A01X+073646Y+086726X0205Y0590R090 S1      
317m5701            VIA   -    MD0080PA01X+051592Y+091470X0160Y    R180 S0      
327m5701            U26   -P18        A01X+051409Y+091575X0177Y    R180 S1      
317m5701            VIA   -    MD0100PA01X+073646Y+083045X0190Y         S0      
327m5701            J29   -167        A01X+073646Y+083045X0205Y0590R090 S1      
317m5702            VIA   -    MD0080PA01X+051592Y+089557X0160Y    R180 S0      
327m5702            U26   -H18        A01X+051409Y+089662X0177Y    R180 S1      
317m5702            VIA   -    MD0100PA01X+073646Y+079364X0190Y         S0      
327m5702            J29   -156        A01X+073646Y+079364X0205Y0590R090 S1      
317m5703            VIA   -    MD0080PA01X+052333Y+097210X0160Y    R180 S0      
327m5703            U26   -AM16       A01X+052149Y+097315X0177Y    R180 S1      
317m5703            VIA   -    MD0100PA01X+075260Y+094089X0190Y         S0      
327m5703            J29   -56         A01X+075260Y+094089X0205Y0590R090 S1      
317m5704            VIA   -    MD0080PA01X+052333Y+095297X0160Y    R180 S0      
327m5704            U26   -AF16       A01X+052149Y+095402X0177Y    R180 S1      
317m5704            VIA   -    MD0100PA01X+075260Y+090408X0190Y         S0      
327m5704            J29   -45         A01X+075260Y+090408X0205Y0590R090 S1      
317m5705            VIA   -    MD0080PA01X+052333Y+093384X0160Y    R180 S0      
327m5705            U26   -Y16        A01X+052149Y+093488X0177Y    R180 S1      
317m5705            VIA   -    MD0100PA01X+075260Y+086726X0190Y         S0      
327m5705            J29   -34         A01X+075260Y+086726X0205Y0590R090 S1      
317m5706            VIA   -    MD0080PA01X+052333Y+091470X0160Y    R180 S0      
327m5706            U26   -P16        A01X+052149Y+091575X0177Y    R180 S1      
317m5706            VIA   -    MD0100PA01X+075260Y+083045X0190Y         S0      
327m5706            J29   -23         A01X+075260Y+083045X0205Y0590R090 S1      
317m5707            VIA   -    MD0080PA01X+052333Y+089557X0160Y    R180 S0      
327m5707            U26   -H16        A01X+052149Y+089662X0177Y    R180 S1      
317m5707            VIA   -    MD0100PA01X+075260Y+079364X0190Y         S0      
327m5707            J29   -12         A01X+075260Y+079364X0205Y0590R090 S1      
317m5708            VIA   -    MD0080PA01X+051592Y+090832X0160Y    R180 S0      
327m5708            U26   -M18        A01X+051409Y+090937X0177Y    R180 S1      
317m5708            VIA   -    MD0100PA01X+075260Y+082042X0190Y         S0      
327m5708            J29   -20         A01X+075260Y+082042X0205Y0590R090 S1      
317m5709            VIA   -    MD0080PA01X+052148Y+090514X0160Y    R180 S0      
327m5709            U26   -L16        A01X+051964Y+090618X0177Y    R180 S1      
317m5709            VIA   -    MD0100PA01X+075260Y+081372X0190Y         S0      
327m5709            J29   -18         A01X+075260Y+081372X0205Y0590R090 S1      
317m5710            VIA   -    MD0080PA01X+051778Y+090514X0160Y    R180 S0      
327m5710            U26   -L17        A01X+051594Y+090618X0177Y    R180 S1      
317m5710            VIA   -    MD0100PA01X+073646Y+081038X0190Y         S0      
327m5710            J29   -161        A01X+073646Y+081038X0205Y0590R090 S1      
317m5711            VIA   -    MD0080PA01X+052333Y+090195X0160Y    R180 S0      
327m5711            U26   -K16        A01X+052149Y+090299X0177Y    R180 S1      
317m5711            VIA   -    MD0100PA01X+073646Y+080368X0190Y         S0      
327m5711            J29   -159        A01X+073646Y+080368X0205Y0590R090 S1      
317m5712            VIA   -    MD0080PA01X+051592Y+090195X0160Y    R180 S0      
327m5712            U26   -K18        A01X+051409Y+090299X0177Y    R180 S1      
317m5712            VIA   -    MD0100PA01X+075260Y+080703X0190Y         S0      
327m5712            J29   -16         A01X+075260Y+080703X0205Y0590R090 S1      
317m5713            VIA   -    MD0080PA01X+052148Y+089876X0160Y    R180 S0      
327m5713            U26   -J16        A01X+051964Y+089980X0177Y    R180 S1      
317m5713            VIA   -    MD0100PA01X+075260Y+080034X0190Y         S0      
327m5713            J29   -14         A01X+075260Y+080034X0205Y0590R090 S1      
317m5714            VIA   -    MD0080PA01X+051778Y+089238X0160Y    R180 S0      
327m5714            U26   -G17        A01X+051594Y+089343X0177Y    R180 S1      
317m5714            VIA   -    MD0100PA01X+073646Y+078695X0190Y         S0      
327m5714            J29   -154        A01X+073646Y+078695X0205Y0590R090 S1      
317m5715            VIA   -    MD0080PA01X+051778Y+096254X0160Y    R180 S0      
327m5715            U26   -AJ17       A01X+051594Y+096358X0177Y    R180 S1      
317m5715            VIA   -    MD0100PA01X+073646Y+092081X0190Y         S0      
327m5715            J29   -194        A01X+073646Y+092081X0205Y0590R090 S1      
317m5716            VIA   -    MD0080PA01X+052333Y+095935X0160Y    R180 S0      
327m5716            U26   -AH16       A01X+052149Y+096040X0177Y    R180 S1      
317m5716            VIA   -    MD0100PA01X+073646Y+091412X0190Y         S0      
327m5716            J29   -192        A01X+073646Y+091412X0205Y0590R090 S1      
317m5717            VIA   -    MD0080PA01X+052333Y+088919X0160Y    R180 S0      
327m5717            U26   -F16        A01X+052149Y+089024X0177Y    R180 S1      
317m5717            VIA   -    MD0100PA01X+073646Y+078026X0190Y         S0      
327m5717            J29   -152        A01X+073646Y+078026X0205Y0590R090 S1      
317m5718            VIA   -    MD0080PA01X+051592Y+095935X0160Y    R180 S0      
327m5718            U26   -AH18       A01X+051409Y+096040X0177Y    R180 S1      
317m5718            VIA   -    MD0100PA01X+075260Y+091746X0190Y         S0      
327m5718            J29   -49         A01X+075260Y+091746X0205Y0590R090 S1      
317m5719            VIA   -    MD0080PA01X+052148Y+095616X0160Y    R180 S0      
327m5719            U26   -AG16       A01X+051964Y+095721X0177Y    R180 S1      
317m5719            VIA   -    MD0100PA01X+075260Y+091077X0190Y         S0      
327m5719            J29   -47         A01X+075260Y+091077X0205Y0590R090 S1      
317m5720            VIA   -    MD0080PA01X+051778Y+094978X0160Y    R180 S0      
327m5720            U26   -AE17       A01X+051594Y+095083X0177Y    R180 S1      
317m5720            VIA   -    MD0100PA01X+073646Y+089738X0190Y         S0      
327m5720            J29   -187        A01X+073646Y+089738X0205Y0590R090 S1      
317m5721            VIA   -    MD0080PA01X+052333Y+094659X0160Y    R180 S0      
327m5721            U26   -AD16       A01X+052149Y+094764X0177Y    R180 S1      
317m5721            VIA   -    MD0100PA01X+073646Y+089069X0190Y         S0      
327m5721            J29   -185        A01X+073646Y+089069X0205Y0590R090 S1      
317m5722            VIA   -    MD0080PA01X+051592Y+094659X0160Y    R180 S0      
327m5722            U26   -AD18       A01X+051409Y+094764X0177Y    R180 S1      
317m5722            VIA   -    MD0100PA01X+075260Y+089404X0190Y         S0      
327m5722            J29   -42         A01X+075260Y+089404X0205Y0590R090 S1      
317m5723            VIA   -    MD0080PA01X+052148Y+094340X0160Y    R180 S0      
327m5723            U26   -AC16       A01X+051964Y+094445X0177Y    R180 S1      
317m5723            VIA   -    MD0100PA01X+075260Y+088734X0190Y         S0      
327m5723            J29   -40         A01X+075260Y+088734X0205Y0590R090 S1      
317m5724            VIA   -    MD0080PA01X+051778Y+094340X0160Y    R180 S0      
327m5724            U26   -AC17       A01X+051594Y+094445X0177Y    R180 S1      
317m5724            VIA   -    MD0100PA01X+073646Y+088400X0190Y         S0      
327m5724            J29   -183        A01X+073646Y+088400X0205Y0590R090 S1      
317m5725            VIA   -    MD0080PA01X+052333Y+094021X0160Y    R180 S0      
327m5725            U26   -AB16       A01X+052149Y+094126X0177Y    R180 S1      
317m5725            VIA   -    MD0100PA01X+073646Y+087730X0190Y         S0      
327m5725            J29   -181        A01X+073646Y+087730X0205Y0590R090 S1      
317m5726            VIA   -    MD0080PA01X+051592Y+094021X0160Y    R180 S0      
327m5726            U26   -AB18       A01X+051409Y+094126X0177Y    R180 S1      
317m5726            VIA   -    MD0100PA01X+075260Y+088065X0190Y         S0      
327m5726            J29   -38         A01X+075260Y+088065X0205Y0590R090 S1      
317m5727            VIA   -    MD0080PA01X+052148Y+093702X0160Y    R180 S0      
327m5727            U26   -AA16       A01X+051964Y+093807X0177Y    R180 S1      
317m5727            VIA   -    MD0100PA01X+075260Y+087396X0190Y         S0      
327m5727            J29   -36         A01X+075260Y+087396X0205Y0590R090 S1      
317m5728            VIA   -    MD0080PA01X+051592Y+088919X0160Y    R180 S0      
327m5728            U26   -F18        A01X+051409Y+089024X0177Y    R180 S1      
317m5728            VIA   -    MD0100PA01X+075260Y+078360X0190Y         S0      
327m5728            J29   -9          A01X+075260Y+078360X0205Y0590R090 S1      
317m5729            VIA   -    MD0080PA01X+051778Y+093065X0160Y    R180 S0      
327m5729            U26   -W17        A01X+051594Y+093169X0177Y    R180 S1      
317m5729            VIA   -    MD0100PA01X+073646Y+086057X0190Y         S0      
327m5729            J29   -176        A01X+073646Y+086057X0205Y0590R090 S1      
317m5730            VIA   -    MD0080PA01X+052333Y+092746X0160Y    R180 S0      
327m5730            U26   -V16        A01X+052149Y+092850X0177Y    R180 S1      
317m5730            VIA   -    MD0100PA01X+073646Y+085388X0190Y         S0      
327m5730            J29   -174        A01X+073646Y+085388X0205Y0590R090 S1      
317m5731            VIA   -    MD0080PA01X+051592Y+092746X0160Y    R180 S0      
327m5731            U26   -V18        A01X+051409Y+092850X0177Y    R180 S1      
317m5731            VIA   -    MD0100PA01X+075260Y+085723X0190Y         S0      
327m5731            J29   -31         A01X+075260Y+085723X0205Y0590R090 S1      
317m5732            VIA   -    MD0080PA01X+052148Y+092427X0160Y    R180 S0      
327m5732            U26   -U16        A01X+051964Y+092532X0177Y    R180 S1      
317m5732            VIA   -    MD0100PA01X+075260Y+085053X0190Y         S0      
327m5732            J29   -29         A01X+075260Y+085053X0205Y0590R090 S1      
317m5733            VIA   -    MD0080PA01X+051778Y+092427X0160Y    R180 S0      
327m5733            U26   -U17        A01X+051594Y+092532X0177Y    R180 S1      
317m5733            VIA   -    MD0100PA01X+073646Y+084719X0190Y         S0      
327m5733            J29   -172        A01X+073646Y+084719X0205Y0590R090 S1      
317m5734            VIA   -    MD0080PA01X+052333Y+092108X0160Y    R180 S0      
327m5734            U26   -T16        A01X+052149Y+092213X0177Y    R180 S1      
317m5734            VIA   -    MD0100PA01X+073646Y+084049X0190Y         S0      
327m5734            J29   -170        A01X+073646Y+084049X0205Y0590R090 S1      
317m5735            VIA   -    MD0080PA01X+051592Y+092108X0160Y    R180 S0      
327m5735            U26   -T18        A01X+051409Y+092213X0177Y    R180 S1      
317m5735            VIA   -    MD0100PA01X+075260Y+084384X0190Y         S0      
327m5735            J29   -27         A01X+075260Y+084384X0205Y0590R090 S1      
317m5736            VIA   -    MD0080PA01X+052148Y+091789X0160Y    R180 S0      
327m5736            U26   -R16        A01X+051964Y+091894X0177Y    R180 S1      
317m5736            VIA   -    MD0100PA01X+075260Y+083715X0190Y         S0      
327m5736            J29   -25         A01X+075260Y+083715X0205Y0590R090 S1      
317m5737            VIA   -    MD0080PA01X+051778Y+091151X0160Y    R180 S0      
327m5737            U26   -N17        A01X+051594Y+091256X0177Y    R180 S1      
317m5737            VIA   -    MD0100PA01X+073646Y+082376X0190Y         S0      
327m5737            J29   -165        A01X+073646Y+082376X0205Y0590R090 S1      
317m5738            VIA   -    MD0080PA01X+052333Y+090832X0160Y    R180 S0      
327m5738            U26   -M16        A01X+052149Y+090937X0177Y    R180 S1      
317m5738            VIA   -    MD0100PA01X+073646Y+081707X0190Y         S0      
327m5738            J29   -163        A01X+073646Y+081707X0205Y0590R090 S1      
317m5739            VIA   -    MD0080PA01X+052148Y+088600X0160Y    R180 S0      
327m5739            U26   -E16        A01X+051964Y+088705X0177Y    R180 S1      
317m5739            VIA   -    MD0100PA01X+075260Y+077691X0190Y         S0      
327m5739            J29   -7          A01X+075260Y+077691X0205Y0590R090 S1      
317m5740            VIA   -    MD0080PA01X+051592Y+099124X0160Y    R180 S0      
327m5740            U26   -AV18       A01X+051409Y+099228X0177Y    R180 S1      
317m5740            VIA   -    MD0100PA01X+073646Y+097100X0190Y         S0      
327m5740            J29   -209        A01X+073646Y+097100X0205Y0590R090 S1      
317m5741            VIA   -    MD0080PA01X+052148Y+098805X0160Y    R180 S0      
327m5741            U26   -AU16       A01X+051964Y+098910X0177Y    R180 S1      
317m5741            VIA   -    MD0100PA01X+075260Y+096766X0190Y         S0      
327m5741            J29   -64         A01X+075260Y+096766X0205Y0590R090 S1      
317m5742            VIA   -    MD0080PA01X+051778Y+098167X0160Y    R180 S0      
327m5742            U26   -AR17       A01X+051594Y+098272X0177Y    R180 S1      
317m5742            VIA   -    MD0100PA01X+073646Y+095762X0190Y         S0      
327m5742            J29   -205        A01X+073646Y+095762X0205Y0590R090 S1      
317m5743            VIA   -    MD0080PA01X+052333Y+097848X0160Y    R180 S0      
327m5743            U26   -AP16       A01X+052149Y+097953X0177Y    R180 S1      
317m5743            VIA   -    MD0100PA01X+073646Y+095093X0190Y         S0      
327m5743            J29   -203        A01X+073646Y+095093X0205Y0590R090 S1      
317m5744            VIA   -    MD0080PA01X+051592Y+097848X0160Y    R180 S0      
327m5744            U26   -AP18       A01X+051409Y+097953X0177Y    R180 S1      
317m5744            VIA   -    MD0100PA01X+075260Y+095427X0190Y         S0      
327m5744            J29   -60         A01X+075260Y+095427X0205Y0590R090 S1      
317m5745            VIA   -    MD0080PA01X+052148Y+097529X0160Y    R180 S0      
327m5745            U26   -AN16       A01X+051964Y+097634X0177Y    R180 S1      
317m5745            VIA   -    MD0100PA01X+075260Y+094758X0190Y         S0      
327m5745            J29   -58         A01X+075260Y+094758X0205Y0590R090 S1      
317m5746            VIA   -    MD0080PA01X+051778Y+096892X0160Y    R180 S0      
327m5746            U26   -AL17       A01X+051594Y+096996X0177Y    R180 S1      
317m5746            VIA   -    MD0100PA01X+073646Y+093419X0190Y         S0      
327m5746            J29   -198        A01X+073646Y+093419X0205Y0590R090 S1      
317m5747            VIA   -    MD0080PA01X+052333Y+096573X0160Y    R180 S0      
327m5747            U26   -AK16       A01X+052149Y+096677X0177Y    R180 S1      
317m5747            VIA   -    MD0100PA01X+073646Y+092750X0190Y         S0      
327m5747            J29   -196        A01X+073646Y+092750X0205Y0590R090 S1      
317m5748            VIA   -    MD0080PA01X+051592Y+096573X0160Y    R180 S0      
327m5748            U26   -AK18       A01X+051409Y+096677X0177Y    R180 S1      
317m5748            VIA   -    MD0100PA01X+075260Y+093085X0190Y         S0      
327m5748            J29   -53         A01X+075260Y+093085X0205Y0590R090 S1      
317m5749            VIA   -    MD0080PA01X+052148Y+096254X0160Y    R180 S0      
327m5749            U26   -AJ16       A01X+051964Y+096358X0177Y    R180 S1      
317m5749            VIA   -    MD0100PA01X+075260Y+092416X0190Y         S0      
327m5749            J29   -51         A01X+075260Y+092416X0205Y0590R090 S1      
317m5750            VIA   -    MD0080PA01X+051592Y+100399X0160Y    R180 S0      
327m5750            U26   -BB18       A01X+051409Y+100504X0177Y    R180 S1      
317m5750            VIA   -    MD0100PA01X+075260Y+099443X0190Y         S0      
327m5750            J29   -72         A01X+075260Y+099443X0205Y0590R090 S1      
317m5751            VIA   -    MD0080PA01X+052333Y+100399X0160Y    R180 S0      
327m5751            U26   -BB16       A01X+052149Y+100504X0177Y    R180 S1      
317m5751            VIA   -    MD0100PA01X+073646Y+099108X0190Y         S0      
327m5751            J29   -215        A01X+073646Y+099108X0205Y0590R090 S1      
317m5752            VIA   -    MD0080PA01X+052148Y+100080X0160Y    R180 S0      
327m5752            U26   -BA16       A01X+051964Y+100185X0177Y    R180 S1      
317m5752            VIA   -    MD0100PA01X+075260Y+098774X0190Y         S0      
327m5752            J29   -70         A01X+075260Y+098774X0205Y0590R090 S1      
317m5753            VIA   -    MD0080PA01X+051778Y+100080X0160Y    R180 S0      
327m5753            U26   -BA17       A01X+051594Y+100185X0177Y    R180 S1      
317m5753            VIA   -    MD0100PA01X+073646Y+098439X0190Y         S0      
327m5753            J29   -213        A01X+073646Y+098439X0205Y0590R090 S1      
317m5754            VIA   -    MD0080PA01X+051592Y+099762X0160Y    R180 S0      
327m5754            U26   -AY18       A01X+051409Y+099866X0177Y    R180 S1      
317m5754            VIA   -    MD0100PA01X+075260Y+098104X0190Y         S0      
327m5754            J29   -68         A01X+075260Y+098104X0205Y0590R090 S1      
317m5755            VIA   -    MD0080PA01X+052333Y+099762X0160Y    R180 S0      
327m5755            U26   -AY16       A01X+052149Y+099866X0177Y    R180 S1      
317m5755            VIA   -    MD0100PA01X+073646Y+097770X0190Y         S0      
327m5755            J29   -211        A01X+073646Y+097770X0205Y0590R090 S1      
317m5756            VIA   -    MD0080PA01X+052148Y+099443X0160Y    R180 S0      
327m5756            U26   -AW16       A01X+051964Y+099547X0177Y    R180 S1      
317m5756            VIA   -    MD0100PA01X+075260Y+097435X0190Y         S0      
327m5756            J29   -66         A01X+075260Y+097435X0205Y0590R090 S1      
317m5757            VIA   -    MD0080PA01X+051778Y+098805X0160Y    R180 S0      
327m5757            U26   -AU17       A01X+051594Y+098910X0177Y    R180 S1      
317m5757            VIA   -    MD0100PA01X+073646Y+096431X0190Y         S0      
327m5757            J29   -207        A01X+073646Y+096431X0205Y0590R090 S1      
317m5758            VIA   -    MD0080PA01X+052148Y+100718X0160Y    R180 S0      
327m5758            U26   -BC16       A01X+051964Y+100823X0177Y    R180 S1      
317m5758            VIA   -    MD0100PA01X+073646Y+099778X0190Y         S0      
327m5758            J29   -217        A01X+073646Y+099778X0205Y0590R090 S1      
317m5759            VIA   -    MD0080PA01X+052333Y+101037X0160Y    R180 S0      
327m5759            U26   -BD16       A01X+052149Y+101142X0177Y    R180 S1      
317m5759            VIA   -    MD0100PA01X+073646Y+100112X0190Y         S0      
327m5759            J29   -218        A01X+073646Y+100112X0205Y0590R090 S1      
317m5760            VIA   -    MD0080PA01X+051592Y+098486X0160Y    R180 S0      
327m5760            U26   -AT18       A01X+051409Y+098591X0177Y    R180 S1      
317m5760            VIA   -    MD0100PA18X+074710Y+096097X0190Y         S0      
327m5760            R509  -2          A18X+074710Y+096097X0198Y0197     S2      
327m5761            J29   -62         A01X+075260Y+096097X0205Y0590R090 S1      
317m5761            VIA   -    MD0100PA00X+075260Y+096097X0190Y         S0      
327m5761            R509  -1          A18X+075025Y+096097X0198Y0197     S2      
317m5762            VIA   -    MD0080PA01X+150065Y+105357X0160Y         S0      
327m5762            U25   -BP16       A01X+149881Y+105252X0177Y    R180 S1      
317m5762            VIA   -    MD0100PA01X+172874Y+106470X0190Y         S0      
327m5762            J68   -87         A01X+172874Y+106470X0205Y0590R090 S1      
317m5763            VIA   -    MD0080PA01X+149510Y+104400X0160Y         S0      
327m5763            U25   -BL17       A01X+149326Y+104295X0177Y    R180 S1      
317m5763            VIA   -    MD0100PA01X+171260Y+105132X0190Y         S0      
327m5763            J68   -227        A01X+171260Y+105132X0205Y0590R090 S1      
317m5764            VIA   -    MD0080PA01X+150065Y+106632X0160Y         S0      
327m5764            U25   -BV16       A01X+149881Y+106528X0177Y    R180 S1      
317m5764            VIA   -    MD0100PA01X+172874Y+108478X0190Y         S0      
327m5764            J68   -93         A01X+172874Y+108478X0205Y0590R090 S1      
317m5765            VIA   -    MD0080PA01X+149325Y+114924X0160Y         S0      
327m5765            U25   -DD18       A01X+149141Y+114819X0177Y    R180 S1      
317m5765            VIA   -    MD0100PA01X+171260Y+123872X0190Y         S0      
327m5765            J68   -283        A01X+171260Y+123872X0205Y0590R090 S1      
317m5766            VIA   -    MD0080PA01X+149325Y+113010X0160Y         S0      
327m5766            U25   -CV18       A01X+149141Y+112906X0177Y    R180 S1      
317m5766            VIA   -    MD0100PA01X+171260Y+120191X0190Y         S0      
327m5766            J68   -272        A01X+171260Y+120191X0205Y0590R090 S1      
317m5767            VIA   -    MD0080PA01X+149325Y+111097X0160Y         S0      
327m5767            U25   -CM18       A01X+149141Y+110992X0177Y    R180 S1      
317m5767            VIA   -    MD0100PA01X+171260Y+116510X0190Y         S0      
327m5767            J68   -261        A01X+171260Y+116510X0205Y0590R090 S1      
317m5768            VIA   -    MD0080PA01X+149325Y+109184X0160Y         S0      
327m5768            U25   -CF18       A01X+149141Y+109079X0177Y    R180 S1      
317m5768            VIA   -    MD0100PA01X+171260Y+112829X0190Y         S0      
327m5768            J68   -250        A01X+171260Y+112829X0205Y0590R090 S1      
317m5769            VIA   -    MD0080PA01X+149325Y+107270X0160Y         S0      
327m5769            U25   -BY18       A01X+149141Y+107165X0177Y    R180 S1      
317m5769            VIA   -    MD0100PA01X+171260Y+109148X0190Y         S0      
327m5769            J68   -239        A01X+171260Y+109148X0205Y0590R090 S1      
317m5770            VIA   -    MD0080PA01X+150065Y+114286X0160Y         S0      
327m5770            U25   -DB16       A01X+149881Y+114181X0177Y    R180 S1      
317m5770            VIA   -    MD0100PA01X+172874Y+123203X0190Y         S0      
327m5770            J68   -137        A01X+172874Y+123203X0205Y0590R090 S1      
317m5771            VIA   -    MD0080PA01X+150065Y+112372X0160Y         S0      
327m5771            U25   -CT16       A01X+149881Y+112268X0177Y    R180 S1      
317m5771            VIA   -    MD0100PA01X+172874Y+119522X0190Y         S0      
327m5771            J68   -126        A01X+172874Y+119522X0205Y0590R090 S1      
317m5772            VIA   -    MD0080PA01X+150065Y+110459X0160Y         S0      
327m5772            U25   -CK16       A01X+149881Y+110354X0177Y    R180 S1      
317m5772            VIA   -    MD0100PA01X+172874Y+115841X0190Y         S0      
327m5772            J68   -115        A01X+172874Y+115841X0205Y0590R090 S1      
317m5773            VIA   -    MD0080PA01X+150065Y+108546X0160Y         S0      
327m5773            U25   -CD16       A01X+149881Y+108441X0177Y    R180 S1      
317m5773            VIA   -    MD0100PA01X+172874Y+112160X0190Y         S0      
327m5773            J68   -104        A01X+172874Y+112160X0205Y0590R090 S1      
317m5774            VIA   -    MD0080PA01X+149880Y+106951X0160Y         S0      
327m5774            U25   -BW16       A01X+149696Y+106846X0177Y    R180 S1      
317m5774            VIA   -    MD0100PA01X+172874Y+108813X0190Y         S0      
327m5774            J68   -94         A01X+172874Y+108813X0205Y0590R090 S1      
317m5775            VIA   -    MD0080PA01X+149510Y+114605X0160Y         S0      
327m5775            U25   -DC17       A01X+149326Y+114500X0177Y    R180 S1      
317m5775            VIA   -    MD0100PA01X+171260Y+123537X0190Y         S0      
327m5775            J68   -282        A01X+171260Y+123537X0205Y0590R090 S1      
317m5776            VIA   -    MD0080PA01X+149510Y+112691X0160Y         S0      
327m5776            U25   -CU17       A01X+149326Y+112587X0177Y    R180 S1      
317m5776            VIA   -    MD0100PA01X+171260Y+119856X0190Y         S0      
327m5776            J68   -271        A01X+171260Y+119856X0205Y0590R090 S1      
317m5777            VIA   -    MD0080PA01X+149510Y+110778X0160Y         S0      
327m5777            U25   -CL17       A01X+149326Y+110673X0177Y    R180 S1      
317m5777            VIA   -    MD0100PA01X+171260Y+116175X0190Y         S0      
327m5777            J68   -260        A01X+171260Y+116175X0205Y0590R090 S1      
317m5778            VIA   -    MD0080PA01X+149510Y+108865X0160Y         S0      
327m5778            U25   -CE17       A01X+149326Y+108760X0177Y    R180 S1      
317m5778            VIA   -    MD0100PA01X+171260Y+112494X0190Y         S0      
327m5778            J68   -249        A01X+171260Y+112494X0205Y0590R090 S1      
317m5779            VIA   -    MD0080PA01X+149510Y+106951X0160Y         S0      
327m5779            U25   -BW17       A01X+149326Y+106846X0177Y    R180 S1      
317m5779            VIA   -    MD0100PA01X+171260Y+108813X0190Y         S0      
327m5779            J68   -238        A01X+171260Y+108813X0205Y0590R090 S1      
317m5780            VIA   -    MD0080PA01X+149880Y+114605X0160Y         S0      
327m5780            U25   -DC16       A01X+149696Y+114500X0177Y    R180 S1      
317m5780            VIA   -    MD0100PA01X+172874Y+123537X0190Y         S0      
327m5780            J68   -138        A01X+172874Y+123537X0205Y0590R090 S1      
317m5781            VIA   -    MD0080PA01X+149880Y+112691X0160Y         S0      
327m5781            U25   -CU16       A01X+149696Y+112587X0177Y    R180 S1      
317m5781            VIA   -    MD0100PA01X+172874Y+119856X0190Y         S0      
327m5781            J68   -127        A01X+172874Y+119856X0205Y0590R090 S1      
317m5782            VIA   -    MD0080PA01X+149880Y+110778X0160Y         S0      
327m5782            U25   -CL16       A01X+149696Y+110673X0177Y    R180 S1      
317m5782            VIA   -    MD0100PA01X+172874Y+116175X0190Y         S0      
327m5782            J68   -116        A01X+172874Y+116175X0205Y0590R090 S1      
317m5783            VIA   -    MD0080PA01X+149880Y+108865X0160Y         S0      
327m5783            U25   -CE16       A01X+149696Y+108760X0177Y    R180 S1      
317m5783            VIA   -    MD0100PA01X+172874Y+112494X0190Y         S0      
327m5783            J68   -105        A01X+172874Y+112494X0205Y0590R090 S1      
317m5784            VIA   -    MD0080PA01X+149510Y+110140X0160Y         S0      
327m5784            U25   -CJ17       A01X+149326Y+110036X0177Y    R180 S1      
317m5784            VIA   -    MD0100PA01X+172874Y+115171X0190Y         S0      
327m5784            J68   -113        A01X+172874Y+115171X0205Y0590R090 S1      
317m5785            VIA   -    MD0080PA01X+150065Y+109821X0160Y         S0      
327m5785            U25   -CH16       A01X+149881Y+109717X0177Y    R180 S1      
317m5785            VIA   -    MD0100PA01X+172874Y+114502X0190Y         S0      
327m5785            J68   -111        A01X+172874Y+114502X0205Y0590R090 S1      
317m5786            VIA   -    MD0080PA01X+149325Y+109821X0160Y         S0      
327m5786            U25   -CH18       A01X+149141Y+109717X0177Y    R180 S1      
317m5786            VIA   -    MD0100PA01X+171260Y+114167X0190Y         S0      
327m5786            J68   -254        A01X+171260Y+114167X0205Y0590R090 S1      
317m5787            VIA   -    MD0080PA01X+149880Y+109502X0160Y         S0      
327m5787            U25   -CG16       A01X+149696Y+109398X0177Y    R180 S1      
317m5787            VIA   -    MD0100PA01X+171260Y+113498X0190Y         S0      
327m5787            J68   -252        A01X+171260Y+113498X0205Y0590R090 S1      
317m5788            VIA   -    MD0080PA01X+149510Y+109502X0160Y         S0      
327m5788            U25   -CG17       A01X+149326Y+109398X0177Y    R180 S1      
317m5788            VIA   -    MD0100PA01X+172874Y+113833X0190Y         S0      
327m5788            J68   -109        A01X+172874Y+113833X0205Y0590R090 S1      
317m5789            VIA   -    MD0080PA01X+150065Y+109184X0160Y         S0      
327m5789            U25   -CF16       A01X+149881Y+109079X0177Y    R180 S1      
317m5789            VIA   -    MD0100PA01X+172874Y+113163X0190Y         S0      
327m5789            J68   -107        A01X+172874Y+113163X0205Y0590R090 S1      
317m5790            VIA   -    MD0080PA01X+149325Y+108546X0160Y         S0      
327m5790            U25   -CD18       A01X+149141Y+108441X0177Y    R180 S1      
317m5790            VIA   -    MD0100PA01X+171260Y+111825X0190Y         S0      
327m5790            J68   -247        A01X+171260Y+111825X0205Y0590R090 S1      
317m5791            VIA   -    MD0080PA01X+150065Y+115561X0160Y         S0      
327m5791            U25   -DF16       A01X+149881Y+115457X0177Y    R180 S1      
317m5791            VIA   -    MD0100PA01X+171260Y+125211X0190Y         S0      
327m5791            J68   -287        A01X+171260Y+125211X0205Y0590R090 S1      
317m5792            VIA   -    MD0080PA01X+149880Y+115242X0160Y         S0      
327m5792            U25   -DE16       A01X+149696Y+115138X0177Y    R180 S1      
317m5792            VIA   -    MD0100PA01X+171260Y+124541X0190Y         S0      
327m5792            J68   -285        A01X+171260Y+124541X0205Y0590R090 S1      
317m5793            VIA   -    MD0080PA01X+149880Y+108227X0160Y         S0      
327m5793            U25   -CC16       A01X+149696Y+108122X0177Y    R180 S1      
317m5793            VIA   -    MD0100PA01X+171260Y+111156X0190Y         S0      
327m5793            J68   -245        A01X+171260Y+111156X0205Y0590R090 S1      
317m5794            VIA   -    MD0080PA01X+149510Y+115242X0160Y         S0      
327m5794            U25   -DE17       A01X+149326Y+115138X0177Y    R180 S1      
317m5794            VIA   -    MD0100PA01X+172874Y+124876X0190Y         S0      
327m5794            J68   -142        A01X+172874Y+124876X0205Y0590R090 S1      
317m5795            VIA   -    MD0080PA01X+150065Y+114924X0160Y         S0      
327m5795            U25   -DD16       A01X+149881Y+114819X0177Y    R180 S1      
317m5795            VIA   -    MD0100PA01X+172874Y+124207X0190Y         S0      
327m5795            J68   -140        A01X+172874Y+124207X0205Y0590R090 S1      
317m5796            VIA   -    MD0080PA01X+149325Y+114286X0160Y         S0      
327m5796            U25   -DB18       A01X+149141Y+114181X0177Y    R180 S1      
317m5796            VIA   -    MD0100PA01X+171260Y+122868X0190Y         S0      
327m5796            J68   -280        A01X+171260Y+122868X0205Y0590R090 S1      
317m5797            VIA   -    MD0080PA01X+149880Y+113967X0160Y         S0      
327m5797            U25   -DA16       A01X+149696Y+113862X0177Y    R180 S1      
317m5797            VIA   -    MD0100PA01X+171260Y+122199X0190Y         S0      
327m5797            J68   -278        A01X+171260Y+122199X0205Y0590R090 S1      
317m5798            VIA   -    MD0080PA01X+149510Y+113967X0160Y         S0      
327m5798            U25   -DA17       A01X+149326Y+113862X0177Y    R180 S1      
317m5798            VIA   -    MD0100PA01X+172874Y+122534X0190Y         S0      
327m5798            J68   -135        A01X+172874Y+122534X0205Y0590R090 S1      
317m5799            VIA   -    MD0080PA01X+150065Y+113648X0160Y         S0      
327m5799            U25   -CY16       A01X+149881Y+113543X0177Y    R180 S1      
317m5799            VIA   -    MD0100PA01X+172874Y+121864X0190Y         S0      
327m5799            J68   -133        A01X+172874Y+121864X0205Y0590R090 S1      
317m5800            VIA   -    MD0080PA01X+149325Y+113648X0160Y         S0      
327m5800            U25   -CY18       A01X+149141Y+113543X0177Y    R180 S1      
317m5800            VIA   -    MD0100PA01X+171260Y+121530X0190Y         S0      
327m5800            J68   -276        A01X+171260Y+121530X0205Y0590R090 S1      
317m5801            VIA   -    MD0080PA01X+149880Y+113329X0160Y         S0      
327m5801            U25   -CW16       A01X+149696Y+113224X0177Y    R180 S1      
317m5801            VIA   -    MD0100PA01X+171260Y+120860X0190Y         S0      
327m5801            J68   -274        A01X+171260Y+120860X0205Y0590R090 S1      
317m5802            VIA   -    MD0080PA01X+149510Y+113329X0160Y         S0      
327m5802            U25   -CW17       A01X+149326Y+113224X0177Y    R180 S1      
317m5802            VIA   -    MD0100PA01X+172874Y+121195X0190Y         S0      
327m5802            J68   -131        A01X+172874Y+121195X0205Y0590R090 S1      
317m5803            VIA   -    MD0080PA01X+150065Y+113010X0160Y         S0      
327m5803            U25   -CV16       A01X+149881Y+112906X0177Y    R180 S1      
317m5803            VIA   -    MD0100PA01X+172874Y+120526X0190Y         S0      
327m5803            J68   -129        A01X+172874Y+120526X0205Y0590R090 S1      
317m5804            VIA   -    MD0080PA01X+149510Y+108227X0160Y         S0      
327m5804            U25   -CC17       A01X+149326Y+108122X0177Y    R180 S1      
317m5804            VIA   -    MD0100PA01X+172874Y+111490X0190Y         S0      
327m5804            J68   -102        A01X+172874Y+111490X0205Y0590R090 S1      
317m5805            VIA   -    MD0080PA01X+149325Y+112372X0160Y         S0      
327m5805            U25   -CT18       A01X+149141Y+112268X0177Y    R180 S1      
317m5805            VIA   -    MD0100PA01X+171260Y+119187X0190Y         S0      
327m5805            J68   -269        A01X+171260Y+119187X0205Y0590R090 S1      
317m5806            VIA   -    MD0080PA01X+149880Y+112054X0160Y         S0      
327m5806            U25   -CR16       A01X+149696Y+111949X0177Y    R180 S1      
317m5806            VIA   -    MD0100PA01X+171260Y+118518X0190Y         S0      
327m5806            J68   -267        A01X+171260Y+118518X0205Y0590R090 S1      
317m5807            VIA   -    MD0080PA01X+149510Y+112054X0160Y         S0      
327m5807            U25   -CR17       A01X+149326Y+111949X0177Y    R180 S1      
317m5807            VIA   -    MD0100PA01X+172874Y+118852X0190Y         S0      
327m5807            J68   -124        A01X+172874Y+118852X0205Y0590R090 S1      
317m5808            VIA   -    MD0080PA01X+150065Y+111735X0160Y         S0      
327m5808            U25   -CP16       A01X+149881Y+111630X0177Y    R180 S1      
317m5808            VIA   -    MD0100PA01X+172874Y+118183X0190Y         S0      
327m5808            J68   -122        A01X+172874Y+118183X0205Y0590R090 S1      
317m5809            VIA   -    MD0080PA01X+149325Y+111735X0160Y         S0      
327m5809            U25   -CP18       A01X+149141Y+111630X0177Y    R180 S1      
317m5809            VIA   -    MD0100PA01X+171260Y+117848X0190Y         S0      
327m5809            J68   -265        A01X+171260Y+117848X0205Y0590R090 S1      
317m5810            VIA   -    MD0080PA01X+149880Y+111416X0160Y         S0      
327m5810            U25   -CN16       A01X+149696Y+111311X0177Y    R180 S1      
317m5810            VIA   -    MD0100PA01X+171260Y+117179X0190Y         S0      
327m5810            J68   -263        A01X+171260Y+117179X0205Y0590R090 S1      
317m5811            VIA   -    MD0080PA01X+149510Y+111416X0160Y         S0      
327m5811            U25   -CN17       A01X+149326Y+111311X0177Y    R180 S1      
317m5811            VIA   -    MD0100PA01X+172874Y+117514X0190Y         S0      
327m5811            J68   -120        A01X+172874Y+117514X0205Y0590R090 S1      
317m5812            VIA   -    MD0080PA01X+150065Y+111097X0160Y         S0      
327m5812            U25   -CM16       A01X+149881Y+110992X0177Y    R180 S1      
317m5812            VIA   -    MD0100PA01X+172874Y+116844X0190Y         S0      
327m5812            J68   -118        A01X+172874Y+116844X0205Y0590R090 S1      
317m5813            VIA   -    MD0080PA01X+149325Y+110459X0160Y         S0      
327m5813            U25   -CK18       A01X+149141Y+110354X0177Y    R180 S1      
317m5813            VIA   -    MD0100PA01X+171260Y+115506X0190Y         S0      
327m5813            J68   -258        A01X+171260Y+115506X0205Y0590R090 S1      
317m5814            VIA   -    MD0080PA01X+149880Y+110140X0160Y         S0      
327m5814            U25   -CJ16       A01X+149696Y+110036X0177Y    R180 S1      
317m5814            VIA   -    MD0100PA01X+171260Y+114837X0190Y         S0      
327m5814            J68   -256        A01X+171260Y+114837X0205Y0590R090 S1      
317m5815            VIA   -    MD0080PA01X+150065Y+107908X0160Y         S0      
327m5815            U25   -CB16       A01X+149881Y+107803X0177Y    R180 S1      
317m5815            VIA   -    MD0100PA01X+172874Y+110821X0190Y         S0      
327m5815            J68   -100        A01X+172874Y+110821X0205Y0590R090 S1      
317m5816            VIA   -    MD0080PA01X+149880Y+105038X0160Y         S0      
327m5816            U25   -BN16       A01X+149696Y+104933X0177Y    R180 S1      
317m5816            VIA   -    MD0100PA01X+171260Y+105801X0190Y         S0      
327m5816            J68   -229        A01X+171260Y+105801X0205Y0590R090 S1      
317m5817            VIA   -    MD0080PA01X+149325Y+104719X0160Y         S0      
327m5817            U25   -BM18       A01X+149141Y+104614X0177Y    R180 S1      
317m5817            VIA   -    MD0100PA01X+172874Y+105467X0190Y         S0      
327m5817            J68   -84         A01X+172874Y+105467X0205Y0590R090 S1      
317m5818            VIA   -    MD0080PA01X+149325Y+106632X0160Y         S0      
327m5818            U25   -BV18       A01X+149141Y+106528X0177Y    R180 S1      
317m5818            VIA   -    MD0100PA01X+171260Y+108144X0190Y         S0      
327m5818            J68   -236        A01X+171260Y+108144X0205Y0590R090 S1      
317m5819            VIA   -    MD0080PA01X+149880Y+106313X0160Y         S0      
327m5819            U25   -BU16       A01X+149696Y+106209X0177Y    R180 S1      
317m5819            VIA   -    MD0100PA01X+171260Y+107474X0190Y         S0      
327m5819            J68   -234        A01X+171260Y+107474X0205Y0590R090 S1      
317m5820            VIA   -    MD0080PA01X+149510Y+106313X0160Y         S0      
327m5820            U25   -BU17       A01X+149326Y+106209X0177Y    R180 S1      
317m5820            VIA   -    MD0100PA01X+172874Y+107809X0190Y         S0      
327m5820            J68   -91         A01X+172874Y+107809X0205Y0590R090 S1      
317m5821            VIA   -    MD0080PA01X+150065Y+105994X0160Y         S0      
327m5821            U25   -BT16       A01X+149881Y+105890X0177Y    R180 S1      
317m5821            VIA   -    MD0100PA01X+172874Y+107140X0190Y         S0      
327m5821            J68   -89         A01X+172874Y+107140X0205Y0590R090 S1      
317m5822            VIA   -    MD0080PA01X+149325Y+107908X0160Y         S0      
327m5822            U25   -CB18       A01X+149141Y+107803X0177Y    R180 S1      
317m5822            VIA   -    MD0100PA01X+171260Y+110486X0190Y         S0      
327m5822            J68   -243        A01X+171260Y+110486X0205Y0590R090 S1      
317m5823            VIA   -    MD0080PA01X+149880Y+107589X0160Y         S0      
327m5823            U25   -CA16       A01X+149696Y+107484X0177Y    R180 S1      
317m5823            VIA   -    MD0100PA01X+171260Y+109817X0190Y         S0      
327m5823            J68   -241        A01X+171260Y+109817X0205Y0590R090 S1      
317m5824            VIA   -    MD0080PA01X+149510Y+107589X0160Y         S0      
327m5824            U25   -CA17       A01X+149326Y+107484X0177Y    R180 S1      
317m5824            VIA   -    MD0100PA01X+172874Y+110152X0190Y         S0      
327m5824            J68   -98         A01X+172874Y+110152X0205Y0590R090 S1      
317m5825            VIA   -    MD0080PA01X+150065Y+107270X0160Y         S0      
327m5825            U25   -BY16       A01X+149881Y+107165X0177Y    R180 S1      
317m5825            VIA   -    MD0100PA01X+172874Y+109482X0190Y         S0      
327m5825            J68   -96         A01X+172874Y+109482X0205Y0590R090 S1      
317m5826            VIA   -    MD0080PA01X+150065Y+104081X0160Y         S0      
327m5826            U25   -BK16       A01X+149881Y+103976X0177Y    R180 S1      
317m5826            VIA   -    MD0100PA01X+172874Y+104797X0190Y         S0      
327m5826            J68   -82         A01X+172874Y+104797X0205Y0590R090 S1      
317m5827            VIA   -    MD0080PA01X+149325Y+104081X0160Y         S0      
327m5827            U25   -BK18       A01X+149141Y+103976X0177Y    R180 S1      
317m5827            VIA   -    MD0100PA01X+171260Y+104463X0190Y         S0      
327m5827            J68   -225        A01X+171260Y+104463X0205Y0590R090 S1      
317m5828            VIA   -    MD0080PA01X+149510Y+103762X0160Y         S0      
327m5828            U25   -BJ17       A01X+149326Y+103658X0177Y    R180 S1      
317m5828            VIA   -    MD0100PA01X+172874Y+104128X0190Y         S0      
327m5828            J68   -80         A01X+172874Y+104128X0205Y0590R090 S1      
317m5829            VIA   -    MD0080PA01X+149880Y+103762X0160Y         S0      
327m5829            U25   -BJ16       A01X+149696Y+103658X0177Y    R180 S1      
317m5829            VIA   -    MD0100PA01X+171260Y+103793X0190Y         S0      
327m5829            J68   -223        A01X+171260Y+103793X0205Y0590R090 S1      
317m5830            VIA   -    MD0080PA01X+150065Y+103443X0160Y         S0      
327m5830            U25   -BH16       A01X+149881Y+103339X0177Y    R180 S1      
317m5830            VIA   -    MD0100PA01X+172874Y+103459X0190Y         S0      
327m5830            J68   -78         A01X+172874Y+103459X0205Y0590R090 S1      
317m5831            VIA   -    MD0080PA01X+149325Y+103443X0160Y         S0      
327m5831            U25   -BH18       A01X+149141Y+103339X0177Y    R180 S1      
317m5831            VIA   -    MD0100PA01X+171260Y+103124X0190Y         S0      
327m5831            J68   -221        A01X+171260Y+103124X0205Y0590R090 S1      
317m5832            VIA   -    MD0080PA01X+149510Y+103124X0160Y         S0      
327m5832            U25   -BG17       A01X+149326Y+103020X0177Y    R180 S1      
317m5832            VIA   -    MD0100PA01X+172874Y+102789X0190Y         S0      
327m5832            J68   -76         A01X+172874Y+102789X0205Y0590R090 S1      
317m5833            VIA   -    MD0080PA01X+149510Y+105038X0160Y         S0      
327m5833            U25   -BN17       A01X+149326Y+104933X0177Y    R180 S1      
317m5833            VIA   -    MD0100PA01X+172874Y+106136X0190Y         S0      
327m5833            J68   -86         A01X+172874Y+106136X0205Y0590R090 S1      
317m5834            VIA   -    MD0080PA01X+149392Y+100718X0160Y    R180 S0      
327m5834            U25   -BC17       A01X+149208Y+100823X0177Y    R180 S1      
317m5834            VIA   -    MD0100PA01X+172874Y+100112X0190Y         S0      
327m5834            J68   -74         A01X+172874Y+100112X0205Y0590R090 S1      
317m5835            VIA   -    MD0080PA01X+149392Y+097529X0160Y    R180 S0      
327m5835            U25   -AN17       A01X+149208Y+097634X0177Y    R180 S1      
317m5835            VIA   -    MD0100PA01X+171260Y+094423X0190Y         S0      
327m5835            J68   -201        A01X+171260Y+094423X0205Y0590R090 S1      
317m5836            VIA   -    MD0080PA01X+149392Y+095616X0160Y    R180 S0      
327m5836            U25   -AG17       A01X+149208Y+095720X0177Y    R180 S1      
317m5836            VIA   -    MD0100PA01X+171260Y+090742X0190Y         S0      
327m5836            J68   -190        A01X+171260Y+090742X0205Y0590R090 S1      
317m5837            VIA   -    MD0080PA01X+149392Y+093702X0160Y    R180 S0      
327m5837            U25   -AA17       A01X+149208Y+093807X0177Y    R180 S1      
317m5837            VIA   -    MD0100PA01X+171260Y+087061X0190Y         S0      
327m5837            J68   -179        A01X+171260Y+087061X0205Y0590R090 S1      
317m5838            VIA   -    MD0080PA01X+149392Y+091789X0160Y    R180 S0      
327m5838            U25   -R17        A01X+149208Y+091894X0177Y    R180 S1      
317m5838            VIA   -    MD0100PA01X+171260Y+083380X0190Y         S0      
327m5838            J68   -168        A01X+171260Y+083380X0205Y0590R090 S1      
317m5839            VIA   -    MD0080PA01X+149392Y+089876X0160Y    R180 S0      
327m5839            U25   -J17        A01X+149208Y+089980X0177Y    R180 S1      
317m5839            VIA   -    MD0100PA01X+171260Y+079699X0190Y         S0      
327m5839            J68   -157        A01X+171260Y+079699X0205Y0590R090 S1      
317m5840            VIA   -    MD0080PA01X+149762Y+096891X0160Y    R180 S0      
327m5840            U25   -AL16       A01X+149578Y+096996X0177Y    R180 S1      
317m5840            VIA   -    MD0100PA01X+172874Y+093754X0190Y         S0      
327m5840            J68   -55         A01X+172874Y+093754X0205Y0590R090 S1      
317m5841            VIA   -    MD0080PA01X+149762Y+094978X0160Y    R180 S0      
327m5841            U25   -AE16       A01X+149578Y+095083X0177Y    R180 S1      
317m5841            VIA   -    MD0100PA01X+172874Y+090073X0190Y         S0      
327m5841            J68   -44         A01X+172874Y+090073X0205Y0590R090 S1      
317m5842            VIA   -    MD0080PA01X+149762Y+093065X0160Y    R180 S0      
327m5842            U25   -W16        A01X+149578Y+093169X0177Y    R180 S1      
317m5842            VIA   -    MD0100PA01X+172874Y+086392X0190Y         S0      
327m5842            J68   -33         A01X+172874Y+086392X0205Y0590R090 S1      
317m5843            VIA   -    MD0080PA01X+149762Y+091151X0160Y    R180 S0      
327m5843            U25   -N16        A01X+149578Y+091256X0177Y    R180 S1      
317m5843            VIA   -    MD0100PA01X+172874Y+082711X0190Y         S0      
327m5843            J68   -22         A01X+172874Y+082711X0205Y0590R090 S1      
317m5844            VIA   -    MD0080PA01X+149762Y+089238X0160Y    R180 S0      
327m5844            U25   -G16        A01X+149578Y+089343X0177Y    R180 S1      
317m5844            VIA   -    MD0100PA01X+172874Y+079030X0190Y         S0      
327m5844            J68   -11         A01X+172874Y+079030X0205Y0590R090 S1      
317m5845            VIA   -    MD0080PA01X+149207Y+097210X0160Y    R180 S0      
327m5845            U25   -AM18       A01X+149023Y+097315X0177Y    R180 S1      
317m5845            VIA   -    MD0100PA01X+171260Y+094089X0190Y         S0      
327m5845            J68   -200        A01X+171260Y+094089X0205Y0590R090 S1      
317m5846            VIA   -    MD0080PA01X+149207Y+095297X0160Y    R180 S0      
327m5846            U25   -AF18       A01X+149023Y+095402X0177Y    R180 S1      
317m5846            VIA   -    MD0100PA01X+171260Y+090408X0190Y         S0      
327m5846            J68   -189        A01X+171260Y+090408X0205Y0590R090 S1      
317m5847            VIA   -    MD0080PA01X+149207Y+093384X0160Y    R180 S0      
327m5847            U25   -Y18        A01X+149023Y+093488X0177Y    R180 S1      
317m5847            VIA   -    MD0100PA01X+171260Y+086726X0190Y         S0      
327m5847            J68   -178        A01X+171260Y+086726X0205Y0590R090 S1      
317m5848            VIA   -    MD0080PA01X+149207Y+091470X0160Y    R180 S0      
327m5848            U25   -P18        A01X+149023Y+091575X0177Y    R180 S1      
317m5848            VIA   -    MD0100PA01X+171260Y+083045X0190Y         S0      
327m5848            J68   -167        A01X+171260Y+083045X0205Y0590R090 S1      
317m5849            VIA   -    MD0080PA01X+149207Y+089557X0160Y    R180 S0      
327m5849            U25   -H18        A01X+149023Y+089662X0177Y    R180 S1      
317m5849            VIA   -    MD0100PA01X+171260Y+079364X0190Y         S0      
327m5849            J68   -156        A01X+171260Y+079364X0205Y0590R090 S1      
317m5850            VIA   -    MD0080PA01X+149947Y+097210X0160Y    R180 S0      
327m5850            U25   -AM16       A01X+149763Y+097315X0177Y    R180 S1      
317m5850            VIA   -    MD0100PA01X+172874Y+094089X0190Y         S0      
327m5850            J68   -56         A01X+172874Y+094089X0205Y0590R090 S1      
317m5851            VIA   -    MD0080PA01X+149947Y+095297X0160Y    R180 S0      
327m5851            U25   -AF16       A01X+149763Y+095402X0177Y    R180 S1      
317m5851            VIA   -    MD0100PA01X+172874Y+090408X0190Y         S0      
327m5851            J68   -45         A01X+172874Y+090408X0205Y0590R090 S1      
317m5852            VIA   -    MD0080PA01X+149947Y+093384X0160Y    R180 S0      
327m5852            U25   -Y16        A01X+149763Y+093488X0177Y    R180 S1      
317m5852            VIA   -    MD0100PA01X+172874Y+086726X0190Y         S0      
327m5852            J68   -34         A01X+172874Y+086726X0205Y0590R090 S1      
317m5853            VIA   -    MD0080PA01X+149947Y+091470X0160Y    R180 S0      
327m5853            U25   -P16        A01X+149763Y+091575X0177Y    R180 S1      
317m5853            VIA   -    MD0100PA01X+172874Y+083045X0190Y         S0      
327m5853            J68   -23         A01X+172874Y+083045X0205Y0590R090 S1      
317m5854            VIA   -    MD0080PA01X+149947Y+089557X0160Y    R180 S0      
327m5854            U25   -H16        A01X+149763Y+089662X0177Y    R180 S1      
317m5854            VIA   -    MD0100PA01X+172874Y+079364X0190Y         S0      
327m5854            J68   -12         A01X+172874Y+079364X0205Y0590R090 S1      
317m5855            VIA   -    MD0080PA01X+149207Y+090832X0160Y    R180 S0      
327m5855            U25   -M18        A01X+149023Y+090937X0177Y    R180 S1      
317m5855            VIA   -    MD0100PA01X+172874Y+082041X0190Y         S0      
327m5855            J68   -20         A01X+172874Y+082041X0205Y0590R090 S1      
317m5856            VIA   -    MD0080PA01X+149762Y+090513X0160Y    R180 S0      
327m5856            U25   -L16        A01X+149578Y+090618X0177Y    R180 S1      
317m5856            VIA   -    MD0100PA01X+172874Y+081372X0190Y         S0      
327m5856            J68   -18         A01X+172874Y+081372X0205Y0590R090 S1      
317m5857            VIA   -    MD0080PA01X+149392Y+090513X0160Y    R180 S0      
327m5857            U25   -L17        A01X+149208Y+090618X0177Y    R180 S1      
317m5857            VIA   -    MD0100PA01X+171260Y+081037X0190Y         S0      
327m5857            J68   -161        A01X+171260Y+081037X0205Y0590R090 S1      
317m5858            VIA   -    MD0080PA01X+149947Y+090195X0160Y    R180 S0      
327m5858            U25   -K16        A01X+149763Y+090299X0177Y    R180 S1      
317m5858            VIA   -    MD0100PA01X+171260Y+080368X0190Y         S0      
327m5858            J68   -159        A01X+171260Y+080368X0205Y0590R090 S1      
317m5859            VIA   -    MD0080PA01X+149207Y+090195X0160Y    R180 S0      
327m5859            U25   -K18        A01X+149023Y+090299X0177Y    R180 S1      
317m5859            VIA   -    MD0100PA01X+172874Y+080703X0190Y         S0      
327m5859            J68   -16         A01X+172874Y+080703X0205Y0590R090 S1      
317m5860            VIA   -    MD0080PA01X+149762Y+089876X0160Y    R180 S0      
327m5860            U25   -J16        A01X+149578Y+089980X0177Y    R180 S1      
317m5860            VIA   -    MD0100PA01X+172874Y+080034X0190Y         S0      
327m5860            J68   -14         A01X+172874Y+080034X0205Y0590R090 S1      
317m5861            VIA   -    MD0080PA01X+149392Y+089238X0160Y    R180 S0      
327m5861            U25   -G17        A01X+149208Y+089343X0177Y    R180 S1      
317m5861            VIA   -    MD0100PA01X+171260Y+078695X0190Y         S0      
327m5861            J68   -154        A01X+171260Y+078695X0205Y0590R090 S1      
317m5862            VIA   -    MD0080PA01X+149392Y+096254X0160Y    R180 S0      
327m5862            U25   -AJ17       A01X+149208Y+096358X0177Y    R180 S1      
317m5862            VIA   -    MD0100PA01X+171260Y+092081X0190Y         S0      
327m5862            J68   -194        A01X+171260Y+092081X0205Y0590R090 S1      
317m5863            VIA   -    MD0080PA01X+149947Y+095935X0160Y    R180 S0      
327m5863            U25   -AH16       A01X+149763Y+096039X0177Y    R180 S1      
317m5863            VIA   -    MD0100PA01X+171260Y+091411X0190Y         S0      
327m5863            J68   -192        A01X+171260Y+091411X0205Y0590R090 S1      
317m5864            VIA   -    MD0080PA01X+149947Y+088919X0160Y    R180 S0      
327m5864            U25   -F16        A01X+149763Y+089024X0177Y    R180 S1      
317m5864            VIA   -    MD0100PA01X+171260Y+078026X0190Y         S0      
327m5864            J68   -152        A01X+171260Y+078026X0205Y0590R090 S1      
317m5865            VIA   -    MD0080PA01X+149207Y+095935X0160Y    R180 S0      
327m5865            U25   -AH18       A01X+149023Y+096039X0177Y    R180 S1      
317m5865            VIA   -    MD0100PA01X+172874Y+091746X0190Y         S0      
327m5865            J68   -49         A01X+172874Y+091746X0205Y0590R090 S1      
317m5866            VIA   -    MD0080PA01X+149762Y+095616X0160Y    R180 S0      
327m5866            U25   -AG16       A01X+149578Y+095720X0177Y    R180 S1      
317m5866            VIA   -    MD0100PA01X+172874Y+091077X0190Y         S0      
327m5866            J68   -47         A01X+172874Y+091077X0205Y0590R090 S1      
317m5867            VIA   -    MD0080PA01X+149392Y+094978X0160Y    R180 S0      
327m5867            U25   -AE17       A01X+149208Y+095083X0177Y    R180 S1      
317m5867            VIA   -    MD0100PA01X+171260Y+089738X0190Y         S0      
327m5867            J68   -187        A01X+171260Y+089738X0205Y0590R090 S1      
317m5868            VIA   -    MD0080PA01X+149947Y+094659X0160Y    R180 S0      
327m5868            U25   -AD16       A01X+149763Y+094764X0177Y    R180 S1      
317m5868            VIA   -    MD0100PA01X+171260Y+089069X0190Y         S0      
327m5868            J68   -185        A01X+171260Y+089069X0205Y0590R090 S1      
317m5869            VIA   -    MD0080PA01X+149207Y+094659X0160Y    R180 S0      
327m5869            U25   -AD18       A01X+149023Y+094764X0177Y    R180 S1      
317m5869            VIA   -    MD0100PA01X+172874Y+089404X0190Y         S0      
327m5869            J68   -42         A01X+172874Y+089404X0205Y0590R090 S1      
317m5870            VIA   -    MD0080PA01X+149762Y+094340X0160Y    R180 S0      
327m5870            U25   -AC16       A01X+149578Y+094445X0177Y    R180 S1      
317m5870            VIA   -    MD0100PA01X+172874Y+088734X0190Y         S0      
327m5870            J68   -40         A01X+172874Y+088734X0205Y0590R090 S1      
317m5871            VIA   -    MD0080PA01X+149392Y+094340X0160Y    R180 S0      
327m5871            U25   -AC17       A01X+149208Y+094445X0177Y    R180 S1      
317m5871            VIA   -    MD0100PA01X+171260Y+088400X0190Y         S0      
327m5871            J68   -183        A01X+171260Y+088400X0205Y0590R090 S1      
317m5872            VIA   -    MD0080PA01X+149947Y+094021X0160Y    R180 S0      
327m5872            U25   -AB16       A01X+149763Y+094126X0177Y    R180 S1      
317m5872            VIA   -    MD0100PA01X+171260Y+087730X0190Y         S0      
327m5872            J68   -181        A01X+171260Y+087730X0205Y0590R090 S1      
317m5873            VIA   -    MD0080PA01X+149207Y+094021X0160Y    R180 S0      
327m5873            U25   -AB18       A01X+149023Y+094126X0177Y    R180 S1      
317m5873            VIA   -    MD0100PA01X+172874Y+088065X0190Y         S0      
327m5873            J68   -38         A01X+172874Y+088065X0205Y0590R090 S1      
317m5874            VIA   -    MD0080PA01X+149762Y+093702X0160Y    R180 S0      
327m5874            U25   -AA16       A01X+149578Y+093807X0177Y    R180 S1      
317m5874            VIA   -    MD0100PA01X+172874Y+087396X0190Y         S0      
327m5874            J68   -36         A01X+172874Y+087396X0205Y0590R090 S1      
317m5875            VIA   -    MD0080PA01X+149207Y+088919X0160Y    R180 S0      
327m5875            U25   -F18        A01X+149023Y+089024X0177Y    R180 S1      
317m5875            VIA   -    MD0100PA01X+172874Y+078360X0190Y         S0      
327m5875            J68   -9          A01X+172874Y+078360X0205Y0590R090 S1      
317m5876            VIA   -    MD0080PA01X+149392Y+093065X0160Y    R180 S0      
327m5876            U25   -W17        A01X+149208Y+093169X0177Y    R180 S1      
317m5876            VIA   -    MD0100PA01X+171260Y+086057X0190Y         S0      
327m5876            J68   -176        A01X+171260Y+086057X0205Y0590R090 S1      
317m5877            VIA   -    MD0080PA01X+149947Y+092746X0160Y    R180 S0      
327m5877            U25   -V16        A01X+149763Y+092850X0177Y    R180 S1      
317m5877            VIA   -    MD0100PA01X+171260Y+085388X0190Y         S0      
327m5877            J68   -174        A01X+171260Y+085388X0205Y0590R090 S1      
317m5878            VIA   -    MD0080PA01X+149207Y+092746X0160Y    R180 S0      
327m5878            U25   -V18        A01X+149023Y+092850X0177Y    R180 S1      
317m5878            VIA   -    MD0100PA01X+172874Y+085722X0190Y         S0      
327m5878            J68   -31         A01X+172874Y+085722X0205Y0590R090 S1      
317m5879            VIA   -    MD0080PA01X+149762Y+092427X0160Y    R180 S0      
327m5879            U25   -U16        A01X+149578Y+092532X0177Y    R180 S1      
317m5879            VIA   -    MD0100PA01X+172874Y+085053X0190Y         S0      
327m5879            J68   -29         A01X+172874Y+085053X0205Y0590R090 S1      
317m5880            VIA   -    MD0080PA01X+149392Y+092427X0160Y    R180 S0      
327m5880            U25   -U17        A01X+149208Y+092532X0177Y    R180 S1      
317m5880            VIA   -    MD0100PA01X+171260Y+084718X0190Y         S0      
327m5880            J68   -172        A01X+171260Y+084718X0205Y0590R090 S1      
317m5881            VIA   -    MD0080PA01X+149947Y+092108X0160Y    R180 S0      
327m5881            U25   -T16        A01X+149763Y+092213X0177Y    R180 S1      
317m5881            VIA   -    MD0100PA01X+171260Y+084049X0190Y         S0      
327m5881            J68   -170        A01X+171260Y+084049X0205Y0590R090 S1      
317m5882            VIA   -    MD0080PA01X+149207Y+092108X0160Y    R180 S0      
327m5882            U25   -T18        A01X+149023Y+092213X0177Y    R180 S1      
317m5882            VIA   -    MD0100PA01X+172874Y+084384X0190Y         S0      
327m5882            J68   -27         A01X+172874Y+084384X0205Y0590R090 S1      
317m5883            VIA   -    MD0080PA01X+149762Y+091789X0160Y    R180 S0      
327m5883            U25   -R16        A01X+149578Y+091894X0177Y    R180 S1      
317m5883            VIA   -    MD0100PA01X+172874Y+083715X0190Y         S0      
327m5883            J68   -25         A01X+172874Y+083715X0205Y0590R090 S1      
317m5884            VIA   -    MD0080PA01X+149392Y+091151X0160Y    R180 S0      
327m5884            U25   -N17        A01X+149208Y+091256X0177Y    R180 S1      
317m5884            VIA   -    MD0100PA01X+171260Y+082376X0190Y         S0      
327m5884            J68   -165        A01X+171260Y+082376X0205Y0590R090 S1      
317m5885            VIA   -    MD0080PA01X+149947Y+090832X0160Y    R180 S0      
327m5885            U25   -M16        A01X+149763Y+090937X0177Y    R180 S1      
317m5885            VIA   -    MD0100PA01X+171260Y+081707X0190Y         S0      
327m5885            J68   -163        A01X+171260Y+081707X0205Y0590R090 S1      
317m5886            VIA   -    MD0080PA01X+149762Y+088600X0160Y    R180 S0      
327m5886            U25   -E16        A01X+149578Y+088705X0177Y    R180 S1      
317m5886            VIA   -    MD0100PA01X+172874Y+077691X0190Y         S0      
327m5886            J68   -7          A01X+172874Y+077691X0205Y0590R090 S1      
317m5887            VIA   -    MD0080PA01X+149207Y+099124X0160Y    R180 S0      
327m5887            U25   -AV18       A01X+149023Y+099228X0177Y    R180 S1      
317m5887            VIA   -    MD0100PA01X+171260Y+097100X0190Y         S0      
327m5887            J68   -209        A01X+171260Y+097100X0205Y0590R090 S1      
317m5888            VIA   -    MD0080PA01X+149762Y+098805X0160Y    R180 S0      
327m5888            U25   -AU16       A01X+149578Y+098910X0177Y    R180 S1      
317m5888            VIA   -    MD0100PA01X+172874Y+096766X0190Y         S0      
327m5888            J68   -64         A01X+172874Y+096766X0205Y0590R090 S1      
317m5889            VIA   -    MD0080PA01X+149392Y+098167X0160Y    R180 S0      
327m5889            U25   -AR17       A01X+149208Y+098272X0177Y    R180 S1      
317m5889            VIA   -    MD0100PA01X+171260Y+095762X0190Y         S0      
327m5889            J68   -205        A01X+171260Y+095762X0205Y0590R090 S1      
317m5890            VIA   -    MD0080PA01X+149947Y+097848X0160Y    R180 S0      
327m5890            U25   -AP16       A01X+149763Y+097953X0177Y    R180 S1      
317m5890            VIA   -    MD0100PA01X+171260Y+095092X0190Y         S0      
327m5890            J68   -203        A01X+171260Y+095092X0205Y0590R090 S1      
317m5891            VIA   -    MD0080PA01X+149207Y+097848X0160Y    R180 S0      
327m5891            U25   -AP18       A01X+149023Y+097953X0177Y    R180 S1      
317m5891            VIA   -    MD0100PA01X+172874Y+095427X0190Y         S0      
327m5891            J68   -60         A01X+172874Y+095427X0205Y0590R090 S1      
317m5892            VIA   -    MD0080PA01X+149762Y+097529X0160Y    R180 S0      
327m5892            U25   -AN16       A01X+149578Y+097634X0177Y    R180 S1      
317m5892            VIA   -    MD0100PA01X+172874Y+094758X0190Y         S0      
327m5892            J68   -58         A01X+172874Y+094758X0205Y0590R090 S1      
317m5893            VIA   -    MD0080PA01X+149392Y+096891X0160Y    R180 S0      
327m5893            U25   -AL17       A01X+149208Y+096996X0177Y    R180 S1      
317m5893            VIA   -    MD0100PA01X+171260Y+093419X0190Y         S0      
327m5893            J68   -198        A01X+171260Y+093419X0205Y0590R090 S1      
317m5894            VIA   -    MD0080PA01X+149947Y+096572X0160Y    R180 S0      
327m5894            U25   -AK16       A01X+149763Y+096677X0177Y    R180 S1      
317m5894            VIA   -    MD0100PA01X+171260Y+092750X0190Y         S0      
327m5894            J68   -196        A01X+171260Y+092750X0205Y0590R090 S1      
317m5895            VIA   -    MD0080PA01X+149207Y+096572X0160Y    R180 S0      
327m5895            U25   -AK18       A01X+149023Y+096677X0177Y    R180 S1      
317m5895            VIA   -    MD0100PA01X+172874Y+093085X0190Y         S0      
327m5895            J68   -53         A01X+172874Y+093085X0205Y0590R090 S1      
317m5896            VIA   -    MD0080PA01X+149762Y+096254X0160Y    R180 S0      
327m5896            U25   -AJ16       A01X+149578Y+096358X0177Y    R180 S1      
317m5896            VIA   -    MD0100PA01X+172874Y+092415X0190Y         S0      
327m5896            J68   -51         A01X+172874Y+092415X0205Y0590R090 S1      
317m5897            VIA   -    MD0080PA01X+149207Y+100399X0160Y    R180 S0      
327m5897            U25   -BB18       A01X+149023Y+100504X0177Y    R180 S1      
317m5897            VIA   -    MD0100PA01X+172874Y+099443X0190Y         S0      
327m5897            J68   -72         A01X+172874Y+099443X0205Y0590R090 S1      
317m5898            VIA   -    MD0080PA01X+149947Y+100399X0160Y    R180 S0      
327m5898            U25   -BB16       A01X+149763Y+100504X0177Y    R180 S1      
317m5898            VIA   -    MD0100PA01X+171260Y+099108X0190Y         S0      
327m5898            J68   -215        A01X+171260Y+099108X0205Y0590R090 S1      
317m5899            VIA   -    MD0080PA01X+149762Y+100080X0160Y    R180 S0      
327m5899            U25   -BA16       A01X+149578Y+100185X0177Y    R180 S1      
317m5899            VIA   -    MD0100PA01X+172874Y+098774X0190Y         S0      
327m5899            J68   -70         A01X+172874Y+098774X0205Y0590R090 S1      
317m5900            VIA   -    MD0080PA01X+149392Y+100080X0160Y    R180 S0      
327m5900            U25   -BA17       A01X+149208Y+100185X0177Y    R180 S1      
317m5900            VIA   -    MD0100PA01X+171260Y+098439X0190Y         S0      
327m5900            J68   -213        A01X+171260Y+098439X0205Y0590R090 S1      
317m5901            VIA   -    MD0080PA01X+149207Y+099762X0160Y    R180 S0      
327m5901            U25   -AY18       A01X+149023Y+099866X0177Y    R180 S1      
317m5901            VIA   -    MD0100PA01X+172874Y+098104X0190Y         S0      
327m5901            J68   -68         A01X+172874Y+098104X0205Y0590R090 S1      
317m5902            VIA   -    MD0080PA01X+149947Y+099762X0160Y    R180 S0      
327m5902            U25   -AY16       A01X+149763Y+099866X0177Y    R180 S1      
317m5902            VIA   -    MD0100PA01X+171260Y+097770X0190Y         S0      
327m5902            J68   -211        A01X+171260Y+097770X0205Y0590R090 S1      
317m5903            VIA   -    MD0080PA01X+149762Y+099443X0160Y    R180 S0      
327m5903            U25   -AW16       A01X+149578Y+099547X0177Y    R180 S1      
317m5903            VIA   -    MD0100PA01X+172874Y+097435X0190Y         S0      
327m5903            J68   -66         A01X+172874Y+097435X0205Y0590R090 S1      
317m5904            VIA   -    MD0080PA01X+149392Y+098805X0160Y    R180 S0      
327m5904            U25   -AU17       A01X+149208Y+098910X0177Y    R180 S1      
317m5904            VIA   -    MD0100PA01X+171260Y+096431X0190Y         S0      
327m5904            J68   -207        A01X+171260Y+096431X0205Y0590R090 S1      
317m5905            VIA   -    MD0080PA01X+149762Y+100718X0160Y    R180 S0      
327m5905            U25   -BC16       A01X+149578Y+100823X0177Y    R180 S1      
317m5905            VIA   -    MD0100PA01X+171260Y+099778X0190Y         S0      
327m5905            J68   -217        A01X+171260Y+099778X0205Y0590R090 S1      
317m5906            VIA   -    MD0080PA01X+149947Y+101037X0160Y    R180 S0      
327m5906            U25   -BD16       A01X+149763Y+101142X0177Y    R180 S1      
317m5906            VIA   -    MD0100PA01X+171260Y+100112X0190Y         S0      
327m5906            J68   -218        A01X+171260Y+100112X0205Y0590R090 S1      
317m5907            VIA   -    MD0080PA01X+149207Y+098486X0160Y    R180 S0      
327m5907            U25   -AT18       A01X+149023Y+098591X0177Y    R180 S1      
317m5907            VIA   -    MD0100PA18X+172324Y+096096X0190Y         S0      
327m5907            R384  -2          A18X+172324Y+096096X0198Y0197     S2      
327m5908            J68   -62         A01X+172874Y+096096X0205Y0590R090 S1      
317m5908            VIA   -    MD0100PA00X+172874Y+096096X0190Y         S0      
327m5908            R384  -1          A18X+172639Y+096096X0198Y0197     S2      
317m5909            VIA   -    MD0080PA01X+050970Y+105357X0160Y         S0      
327m5909            U26   -BP20       A01X+050787Y+105252X0177Y    R180 S1      
317m5909            VIA   -    MD0100PA01X+072290Y+106471X0190Y         S0      
327m5909            J100  -87         A01X+072290Y+106471X0205Y0590R090 S1      
317m5910            VIA   -    MD0080PA01X+050415Y+104400X0160Y         S0      
327m5910            U26   -BL21       A01X+050232Y+104295X0177Y    R180 S1      
317m5910            VIA   -    MD0100PA01X+070676Y+105132X0190Y         S0      
327m5910            J100  -227        A01X+070676Y+105132X0205Y0590R090 S1      
317m5911            VIA   -    MD0080PA01X+050970Y+106632X0160Y         S0      
327m5911            U26   -BV20       A01X+050787Y+106528X0177Y    R180 S1      
317m5911            VIA   -    MD0100PA01X+072290Y+108478X0190Y         S0      
327m5911            J100  -93         A01X+072290Y+108478X0205Y0590R090 S1      
317m5912            VIA   -    MD0080PA01X+050600Y+114924X0160Y         S0      
327m5912            U26   -DD21       A01X+050416Y+114819X0177Y    R180 S1      
317m5912            VIA   -    MD0100PA01X+070676Y+123872X0190Y         S0      
327m5912            J100  -283        A01X+070676Y+123872X0205Y0590R090 S1      
317m5913            VIA   -    MD0080PA01X+050600Y+113010X0160Y         S0      
327m5913            U26   -CV21       A01X+050416Y+112906X0177Y    R180 S1      
317m5913            VIA   -    MD0100PA01X+070676Y+120191X0190Y         S0      
327m5913            J100  -272        A01X+070676Y+120191X0205Y0590R090 S1      
317m5914            VIA   -    MD0080PA01X+050600Y+111097X0160Y         S0      
327m5914            U26   -CM21       A01X+050416Y+110992X0177Y    R180 S1      
317m5914            VIA   -    MD0100PA01X+070676Y+116510X0190Y         S0      
327m5914            J100  -261        A01X+070676Y+116510X0205Y0590R090 S1      
317m5915            VIA   -    MD0080PA01X+050600Y+109184X0160Y         S0      
327m5915            U26   -CF21       A01X+050416Y+109079X0177Y    R180 S1      
317m5915            VIA   -    MD0100PA01X+070676Y+112829X0190Y         S0      
327m5915            J100  -250        A01X+070676Y+112829X0205Y0590R090 S1      
317m5916            VIA   -    MD0080PA01X+050600Y+107270X0160Y         S0      
327m5916            U26   -BY21       A01X+050416Y+107166X0177Y    R180 S1      
317m5916            VIA   -    MD0100PA01X+070676Y+109148X0190Y         S0      
327m5916            J100  -239        A01X+070676Y+109148X0205Y0590R090 S1      
317m5917            VIA   -    MD0080PA01X+050970Y+114286X0160Y         S0      
327m5917            U26   -DB20       A01X+050787Y+114181X0177Y    R180 S1      
317m5917            VIA   -    MD0100PA01X+072290Y+123203X0190Y         S0      
327m5917            J100  -137        A01X+072290Y+123203X0205Y0590R090 S1      
317m5918            VIA   -    MD0080PA01X+050970Y+112373X0160Y         S0      
327m5918            U26   -CT20       A01X+050787Y+112268X0177Y    R180 S1      
317m5918            VIA   -    MD0100PA01X+072290Y+119522X0190Y         S0      
327m5918            J100  -126        A01X+072290Y+119522X0205Y0590R090 S1      
317m5919            VIA   -    MD0080PA01X+050970Y+110459X0160Y         S0      
327m5919            U26   -CK20       A01X+050787Y+110354X0177Y    R180 S1      
317m5919            VIA   -    MD0100PA01X+072290Y+115841X0190Y         S0      
327m5919            J100  -115        A01X+072290Y+115841X0205Y0590R090 S1      
317m5920            VIA   -    MD0080PA01X+050970Y+108546X0160Y         S0      
327m5920            U26   -CD20       A01X+050787Y+108441X0177Y    R180 S1      
317m5920            VIA   -    MD0100PA01X+072290Y+112160X0190Y         S0      
327m5920            J100  -104        A01X+072290Y+112160X0205Y0590R090 S1      
317m5921            VIA   -    MD0080PA01X+051155Y+106951X0160Y         S0      
327m5921            U26   -BW19       A01X+050972Y+106847X0177Y    R180 S1      
317m5921            VIA   -    MD0100PA01X+072290Y+108813X0190Y         S0      
327m5921            J100  -94         A01X+072290Y+108813X0205Y0590R090 S1      
317m5922            VIA   -    MD0080PA01X+050415Y+114605X0160Y         S0      
327m5922            U26   -DC21       A01X+050232Y+114500X0177Y    R180 S1      
317m5922            VIA   -    MD0100PA01X+070676Y+123538X0190Y         S0      
327m5922            J100  -282        A01X+070676Y+123538X0205Y0590R090 S1      
317m5923            VIA   -    MD0080PA01X+050415Y+112692X0160Y         S0      
327m5923            U26   -CU21       A01X+050232Y+112587X0177Y    R180 S1      
317m5923            VIA   -    MD0100PA01X+070676Y+119856X0190Y         S0      
327m5923            J100  -271        A01X+070676Y+119856X0205Y0590R090 S1      
317m5924            VIA   -    MD0080PA01X+050415Y+110778X0160Y         S0      
327m5924            U26   -CL21       A01X+050232Y+110673X0177Y    R180 S1      
317m5924            VIA   -    MD0100PA01X+070676Y+116175X0190Y         S0      
327m5924            J100  -260        A01X+070676Y+116175X0205Y0590R090 S1      
317m5925            VIA   -    MD0080PA01X+050415Y+108865X0160Y         S0      
327m5925            U26   -CE21       A01X+050232Y+108760X0177Y    R180 S1      
317m5925            VIA   -    MD0100PA01X+070676Y+112494X0190Y         S0      
327m5925            J100  -249        A01X+070676Y+112494X0205Y0590R090 S1      
317m5926            VIA   -    MD0080PA01X+050415Y+106951X0160Y         S0      
327m5926            U26   -BW21       A01X+050232Y+106847X0177Y    R180 S1      
317m5926            VIA   -    MD0100PA01X+070676Y+108813X0190Y         S0      
327m5926            J100  -238        A01X+070676Y+108813X0205Y0590R090 S1      
317m5927            VIA   -    MD0080PA01X+051155Y+114605X0160Y         S0      
327m5927            U26   -DC19       A01X+050972Y+114500X0177Y    R180 S1      
317m5927            VIA   -    MD0100PA01X+072290Y+123538X0190Y         S0      
327m5927            J100  -138        A01X+072290Y+123538X0205Y0590R090 S1      
317m5928            VIA   -    MD0080PA01X+051155Y+112692X0160Y         S0      
327m5928            U26   -CU19       A01X+050972Y+112587X0177Y    R180 S1      
317m5928            VIA   -    MD0100PA01X+072290Y+119856X0190Y         S0      
327m5928            J100  -127        A01X+072290Y+119856X0205Y0590R090 S1      
317m5929            VIA   -    MD0080PA01X+051155Y+110778X0160Y         S0      
327m5929            U26   -CL19       A01X+050972Y+110673X0177Y    R180 S1      
317m5929            VIA   -    MD0100PA01X+072290Y+116175X0190Y         S0      
327m5929            J100  -116        A01X+072290Y+116175X0205Y0590R090 S1      
317m5930            VIA   -    MD0080PA01X+051155Y+108865X0160Y         S0      
327m5930            U26   -CE19       A01X+050972Y+108760X0177Y    R180 S1      
317m5930            VIA   -    MD0100PA01X+072290Y+112494X0190Y         S0      
327m5930            J100  -105        A01X+072290Y+112494X0205Y0590R090 S1      
317m5931            VIA   -    MD0080PA01X+050415Y+110140X0160Y         S0      
327m5931            U26   -CJ21       A01X+050232Y+110036X0177Y    R180 S1      
317m5931            VIA   -    MD0100PA01X+072290Y+115171X0190Y         S0      
327m5931            J100  -113        A01X+072290Y+115171X0205Y0590R090 S1      
317m5932            VIA   -    MD0080PA01X+050970Y+109821X0160Y         S0      
327m5932            U26   -CH20       A01X+050787Y+109717X0177Y    R180 S1      
317m5932            VIA   -    MD0100PA01X+072290Y+114502X0190Y         S0      
327m5932            J100  -111        A01X+072290Y+114502X0205Y0590R090 S1      
317m5933            VIA   -    MD0080PA01X+050600Y+109821X0160Y         S0      
327m5933            U26   -CH21       A01X+050416Y+109717X0177Y    R180 S1      
317m5933            VIA   -    MD0100PA01X+070676Y+114168X0190Y         S0      
327m5933            J100  -254        A01X+070676Y+114168X0205Y0590R090 S1      
317m5934            VIA   -    MD0080PA01X+051155Y+109502X0160Y         S0      
327m5934            U26   -CG19       A01X+050972Y+109398X0177Y    R180 S1      
317m5934            VIA   -    MD0100PA01X+070676Y+113498X0190Y         S0      
327m5934            J100  -252        A01X+070676Y+113498X0205Y0590R090 S1      
317m5935            VIA   -    MD0080PA01X+050415Y+109502X0160Y         S0      
327m5935            U26   -CG21       A01X+050232Y+109398X0177Y    R180 S1      
317m5935            VIA   -    MD0100PA01X+072290Y+113833X0190Y         S0      
327m5935            J100  -109        A01X+072290Y+113833X0205Y0590R090 S1      
317m5936            VIA   -    MD0080PA01X+050970Y+109184X0160Y         S0      
327m5936            U26   -CF20       A01X+050787Y+109079X0177Y    R180 S1      
317m5936            VIA   -    MD0100PA01X+072290Y+113164X0190Y         S0      
327m5936            J100  -107        A01X+072290Y+113164X0205Y0590R090 S1      
317m5937            VIA   -    MD0080PA01X+050600Y+108546X0160Y         S0      
327m5937            U26   -CD21       A01X+050416Y+108441X0177Y    R180 S1      
317m5937            VIA   -    MD0100PA01X+070676Y+111825X0190Y         S0      
327m5937            J100  -247        A01X+070676Y+111825X0205Y0590R090 S1      
317m5938            VIA   -    MD0080PA01X+050600Y+115562X0160Y         S0      
327m5938            U26   -DF21       A01X+050416Y+115457X0177Y    R180 S1      
317m5938            VIA   -    MD0100PA01X+070676Y+125211X0190Y         S0      
327m5938            J100  -287        A01X+070676Y+125211X0205Y0590R090 S1      
317m5939            VIA   -    MD0080PA01X+051155Y+115243X0160Y         S0      
327m5939            U26   -DE19       A01X+050972Y+115138X0177Y    R180 S1      
317m5939            VIA   -    MD0100PA01X+070676Y+124542X0190Y         S0      
327m5939            J100  -285        A01X+070676Y+124542X0205Y0590R090 S1      
317m5940            VIA   -    MD0080PA01X+051155Y+108227X0160Y         S0      
327m5940            U26   -CC19       A01X+050972Y+108122X0177Y    R180 S1      
317m5940            VIA   -    MD0100PA01X+070676Y+111156X0190Y         S0      
327m5940            J100  -245        A01X+070676Y+111156X0205Y0590R090 S1      
317m5941            VIA   -    MD0080PA01X+050415Y+115243X0160Y         S0      
327m5941            U26   -DE21       A01X+050232Y+115138X0177Y    R180 S1      
317m5941            VIA   -    MD0100PA01X+072290Y+124876X0190Y         S0      
327m5941            J100  -142        A01X+072290Y+124876X0205Y0590R090 S1      
317m5942            VIA   -    MD0080PA01X+050970Y+114924X0160Y         S0      
327m5942            U26   -DD20       A01X+050787Y+114819X0177Y    R180 S1      
317m5942            VIA   -    MD0100PA01X+072290Y+124207X0190Y         S0      
327m5942            J100  -140        A01X+072290Y+124207X0205Y0590R090 S1      
317m5943            VIA   -    MD0080PA01X+050600Y+114286X0160Y         S0      
327m5943            U26   -DB21       A01X+050416Y+114181X0177Y    R180 S1      
317m5943            VIA   -    MD0100PA01X+070676Y+122868X0190Y         S0      
327m5943            J100  -280        A01X+070676Y+122868X0205Y0590R090 S1      
317m5944            VIA   -    MD0080PA01X+051155Y+113967X0160Y         S0      
327m5944            U26   -DA19       A01X+050972Y+113862X0177Y    R180 S1      
317m5944            VIA   -    MD0100PA01X+070676Y+122199X0190Y         S0      
327m5944            J100  -278        A01X+070676Y+122199X0205Y0590R090 S1      
317m5945            VIA   -    MD0080PA01X+050415Y+113967X0160Y         S0      
327m5945            U26   -DA21       A01X+050232Y+113862X0177Y    R180 S1      
317m5945            VIA   -    MD0100PA01X+072290Y+122534X0190Y         S0      
327m5945            J100  -135        A01X+072290Y+122534X0205Y0590R090 S1      
317m5946            VIA   -    MD0080PA01X+050970Y+113648X0160Y         S0      
327m5946            U26   -CY20       A01X+050787Y+113543X0177Y    R180 S1      
317m5946            VIA   -    MD0100PA01X+072290Y+121864X0190Y         S0      
327m5946            J100  -133        A01X+072290Y+121864X0205Y0590R090 S1      
317m5947            VIA   -    MD0080PA01X+050600Y+113648X0160Y         S0      
327m5947            U26   -CY21       A01X+050416Y+113543X0177Y    R180 S1      
317m5947            VIA   -    MD0100PA01X+070676Y+121530X0190Y         S0      
327m5947            J100  -276        A01X+070676Y+121530X0205Y0590R090 S1      
317m5948            VIA   -    MD0080PA01X+051155Y+113329X0160Y         S0      
327m5948            U26   -CW19       A01X+050972Y+113225X0177Y    R180 S1      
317m5948            VIA   -    MD0100PA01X+070676Y+120860X0190Y         S0      
327m5948            J100  -274        A01X+070676Y+120860X0205Y0590R090 S1      
317m5949            VIA   -    MD0080PA01X+050415Y+113329X0160Y         S0      
327m5949            U26   -CW21       A01X+050232Y+113225X0177Y    R180 S1      
317m5949            VIA   -    MD0100PA01X+072290Y+121195X0190Y         S0      
327m5949            J100  -131        A01X+072290Y+121195X0205Y0590R090 S1      
317m5950            VIA   -    MD0080PA01X+050970Y+113010X0160Y         S0      
327m5950            U26   -CV20       A01X+050787Y+112906X0177Y    R180 S1      
317m5950            VIA   -    MD0100PA01X+072290Y+120526X0190Y         S0      
327m5950            J100  -129        A01X+072290Y+120526X0205Y0590R090 S1      
317m5951            VIA   -    MD0080PA01X+050415Y+108227X0160Y         S0      
327m5951            U26   -CC21       A01X+050232Y+108122X0177Y    R180 S1      
317m5951            VIA   -    MD0100PA01X+072290Y+111490X0190Y         S0      
327m5951            J100  -102        A01X+072290Y+111490X0205Y0590R090 S1      
317m5952            VIA   -    MD0080PA01X+050600Y+112373X0160Y         S0      
327m5952            U26   -CT21       A01X+050416Y+112268X0177Y    R180 S1      
317m5952            VIA   -    MD0100PA01X+070676Y+119187X0190Y         S0      
327m5952            J100  -269        A01X+070676Y+119187X0205Y0590R090 S1      
317m5953            VIA   -    MD0080PA01X+051155Y+112054X0160Y         S0      
327m5953            U26   -CR19       A01X+050972Y+111949X0177Y    R180 S1      
317m5953            VIA   -    MD0100PA01X+070676Y+118518X0190Y         S0      
327m5953            J100  -267        A01X+070676Y+118518X0205Y0590R090 S1      
317m5954            VIA   -    MD0080PA01X+050415Y+112054X0160Y         S0      
327m5954            U26   -CR21       A01X+050232Y+111949X0177Y    R180 S1      
317m5954            VIA   -    MD0100PA01X+072290Y+118852X0190Y         S0      
327m5954            J100  -124        A01X+072290Y+118852X0205Y0590R090 S1      
317m5955            VIA   -    MD0080PA01X+050970Y+111735X0160Y         S0      
327m5955            U26   -CP20       A01X+050787Y+111630X0177Y    R180 S1      
317m5955            VIA   -    MD0100PA01X+072290Y+118183X0190Y         S0      
327m5955            J100  -122        A01X+072290Y+118183X0205Y0590R090 S1      
317m5956            VIA   -    MD0080PA01X+050600Y+111735X0160Y         S0      
327m5956            U26   -CP21       A01X+050416Y+111630X0177Y    R180 S1      
317m5956            VIA   -    MD0100PA01X+070676Y+117849X0190Y         S0      
327m5956            J100  -265        A01X+070676Y+117849X0205Y0590R090 S1      
317m5957            VIA   -    MD0080PA01X+051155Y+111416X0160Y         S0      
327m5957            U26   -CN19       A01X+050972Y+111311X0177Y    R180 S1      
317m5957            VIA   -    MD0100PA01X+070676Y+117179X0190Y         S0      
327m5957            J100  -263        A01X+070676Y+117179X0205Y0590R090 S1      
317m5958            VIA   -    MD0080PA01X+050415Y+111416X0160Y         S0      
327m5958            U26   -CN21       A01X+050232Y+111311X0177Y    R180 S1      
317m5958            VIA   -    MD0100PA01X+072290Y+117514X0190Y         S0      
327m5958            J100  -120        A01X+072290Y+117514X0205Y0590R090 S1      
317m5959            VIA   -    MD0080PA01X+050970Y+111097X0160Y         S0      
327m5959            U26   -CM20       A01X+050787Y+110992X0177Y    R180 S1      
317m5959            VIA   -    MD0100PA01X+072290Y+116845X0190Y         S0      
327m5959            J100  -118        A01X+072290Y+116845X0205Y0590R090 S1      
317m5960            VIA   -    MD0080PA01X+050600Y+110459X0160Y         S0      
327m5960            U26   -CK21       A01X+050416Y+110354X0177Y    R180 S1      
317m5960            VIA   -    MD0100PA01X+070676Y+115506X0190Y         S0      
327m5960            J100  -258        A01X+070676Y+115506X0205Y0590R090 S1      
317m5961            VIA   -    MD0080PA01X+051155Y+110140X0160Y         S0      
327m5961            U26   -CJ19       A01X+050972Y+110036X0177Y    R180 S1      
317m5961            VIA   -    MD0100PA01X+070676Y+114837X0190Y         S0      
327m5961            J100  -256        A01X+070676Y+114837X0205Y0590R090 S1      
317m5962            VIA   -    MD0080PA01X+050970Y+107908X0160Y         S0      
327m5962            U26   -CB20       A01X+050787Y+107803X0177Y    R180 S1      
317m5962            VIA   -    MD0100PA01X+072290Y+110821X0190Y         S0      
327m5962            J100  -100        A01X+072290Y+110821X0205Y0590R090 S1      
317m5963            VIA   -    MD0080PA01X+051155Y+105038X0160Y         S0      
327m5963            U26   -BN19       A01X+050972Y+104933X0177Y    R180 S1      
317m5963            VIA   -    MD0100PA01X+070676Y+105801X0190Y         S0      
327m5963            J100  -229        A01X+070676Y+105801X0205Y0590R090 S1      
317m5964            VIA   -    MD0080PA01X+050600Y+104719X0160Y         S0      
327m5964            U26   -BM21       A01X+050416Y+104614X0177Y    R180 S1      
317m5964            VIA   -    MD0100PA01X+072290Y+105467X0190Y         S0      
327m5964            J100  -84         A01X+072290Y+105467X0205Y0590R090 S1      
317m5965            VIA   -    MD0080PA01X+050600Y+106632X0160Y         S0      
327m5965            U26   -BV21       A01X+050416Y+106528X0177Y    R180 S1      
317m5965            VIA   -    MD0100PA01X+070676Y+108144X0190Y         S0      
327m5965            J100  -236        A01X+070676Y+108144X0205Y0590R090 S1      
317m5966            VIA   -    MD0080PA01X+051155Y+106314X0160Y         S0      
327m5966            U26   -BU19       A01X+050972Y+106209X0177Y    R180 S1      
317m5966            VIA   -    MD0100PA01X+070676Y+107474X0190Y         S0      
327m5966            J100  -234        A01X+070676Y+107474X0205Y0590R090 S1      
317m5967            VIA   -    MD0080PA01X+050415Y+106314X0160Y         S0      
327m5967            U26   -BU21       A01X+050232Y+106209X0177Y    R180 S1      
317m5967            VIA   -    MD0100PA01X+072290Y+107809X0190Y         S0      
327m5967            J100  -91         A01X+072290Y+107809X0205Y0590R090 S1      
317m5968            VIA   -    MD0080PA01X+050970Y+105995X0160Y         S0      
327m5968            U26   -BT20       A01X+050787Y+105890X0177Y    R180 S1      
317m5968            VIA   -    MD0100PA01X+072290Y+107140X0190Y         S0      
327m5968            J100  -89         A01X+072290Y+107140X0205Y0590R090 S1      
317m5969            VIA   -    MD0080PA01X+050600Y+107908X0160Y         S0      
327m5969            U26   -CB21       A01X+050416Y+107803X0177Y    R180 S1      
317m5969            VIA   -    MD0100PA01X+070676Y+110486X0190Y         S0      
327m5969            J100  -243        A01X+070676Y+110486X0205Y0590R090 S1      
317m5970            VIA   -    MD0080PA01X+051155Y+107589X0160Y         S0      
327m5970            U26   -CA19       A01X+050972Y+107484X0177Y    R180 S1      
317m5970            VIA   -    MD0100PA01X+070676Y+109817X0190Y         S0      
327m5970            J100  -241        A01X+070676Y+109817X0205Y0590R090 S1      
317m5971            VIA   -    MD0080PA01X+050415Y+107589X0160Y         S0      
327m5971            U26   -CA21       A01X+050232Y+107484X0177Y    R180 S1      
317m5971            VIA   -    MD0100PA01X+072290Y+110152X0190Y         S0      
327m5971            J100  -98         A01X+072290Y+110152X0205Y0590R090 S1      
317m5972            VIA   -    MD0080PA01X+050970Y+107270X0160Y         S0      
327m5972            U26   -BY20       A01X+050787Y+107166X0177Y    R180 S1      
317m5972            VIA   -    MD0100PA01X+072290Y+109482X0190Y         S0      
327m5972            J100  -96         A01X+072290Y+109482X0205Y0590R090 S1      
317m5973            VIA   -    MD0080PA01X+050970Y+104081X0160Y         S0      
327m5973            U26   -BK20       A01X+050787Y+103976X0177Y    R180 S1      
317m5973            VIA   -    MD0100PA01X+072290Y+104797X0190Y         S0      
327m5973            J100  -82         A01X+072290Y+104797X0205Y0590R090 S1      
317m5974            VIA   -    MD0080PA01X+050600Y+104081X0160Y         S0      
327m5974            U26   -BK21       A01X+050416Y+103976X0177Y    R180 S1      
317m5974            VIA   -    MD0100PA01X+070676Y+104463X0190Y         S0      
327m5974            J100  -225        A01X+070676Y+104463X0205Y0590R090 S1      
317m5975            VIA   -    MD0080PA01X+050415Y+103762X0160Y         S0      
327m5975            U26   -BJ21       A01X+050232Y+103658X0177Y    R180 S1      
317m5975            VIA   -    MD0100PA01X+072290Y+104128X0190Y         S0      
327m5975            J100  -80         A01X+072290Y+104128X0205Y0590R090 S1      
317m5976            VIA   -    MD0080PA01X+051155Y+103762X0160Y         S0      
327m5976            U26   -BJ19       A01X+050972Y+103658X0177Y    R180 S1      
317m5976            VIA   -    MD0100PA01X+070676Y+103793X0190Y         S0      
327m5976            J100  -223        A01X+070676Y+103793X0205Y0590R090 S1      
317m5977            VIA   -    MD0080PA01X+050970Y+103443X0160Y         S0      
327m5977            U26   -BH20       A01X+050787Y+103339X0177Y    R180 S1      
317m5977            VIA   -    MD0100PA01X+072290Y+103459X0190Y         S0      
327m5977            J100  -78         A01X+072290Y+103459X0205Y0590R090 S1      
317m5978            VIA   -    MD0080PA01X+050600Y+103443X0160Y         S0      
327m5978            U26   -BH21       A01X+050416Y+103339X0177Y    R180 S1      
317m5978            VIA   -    MD0100PA01X+070676Y+103124X0190Y         S0      
327m5978            J100  -221        A01X+070676Y+103124X0205Y0590R090 S1      
317m5979            VIA   -    MD0080PA01X+050415Y+103124X0160Y         S0      
327m5979            U26   -BG21       A01X+050232Y+103020X0177Y    R180 S1      
317m5979            VIA   -    MD0100PA01X+072290Y+102790X0190Y         S0      
327m5979            J100  -76         A01X+072290Y+102790X0205Y0590R090 S1      
317m5980            VIA   -    MD0080PA01X+050415Y+105038X0160Y         S0      
327m5980            U26   -BN21       A01X+050232Y+104933X0177Y    R180 S1      
317m5980            VIA   -    MD0100PA01X+072290Y+106136X0190Y         S0      
327m5980            J100  -86         A01X+072290Y+106136X0205Y0590R090 S1      
317m5981            VIA   -    MD0080PA01X+050297Y+100718X0160Y    R180 S0      
327m5981            U26   -BC21       A01X+050113Y+100823X0177Y    R180 S1      
317m5981            VIA   -    MD0100PA01X+072290Y+100112X0190Y         S0      
327m5981            J100  -74         A01X+072290Y+100112X0205Y0590R090 S1      
317m5982            VIA   -    MD0080PA01X+050297Y+097529X0160Y    R180 S0      
327m5982            U26   -AN21       A01X+050113Y+097634X0177Y    R180 S1      
317m5982            VIA   -    MD0100PA01X+070676Y+094423X0190Y         S0      
327m5982            J100  -201        A01X+070676Y+094423X0205Y0590R090 S1      
317m5983            VIA   -    MD0080PA01X+050297Y+095616X0160Y    R180 S0      
327m5983            U26   -AG21       A01X+050113Y+095721X0177Y    R180 S1      
317m5983            VIA   -    MD0100PA01X+070676Y+090742X0190Y         S0      
327m5983            J100  -190        A01X+070676Y+090742X0205Y0590R090 S1      
317m5984            VIA   -    MD0080PA01X+050297Y+093702X0160Y    R180 S0      
327m5984            U26   -AA21       A01X+050113Y+093807X0177Y    R180 S1      
317m5984            VIA   -    MD0100PA01X+070676Y+087061X0190Y         S0      
327m5984            J100  -179        A01X+070676Y+087061X0205Y0590R090 S1      
317m5985            VIA   -    MD0080PA01X+050297Y+091789X0160Y    R180 S0      
327m5985            U26   -R21        A01X+050113Y+091894X0177Y    R180 S1      
317m5985            VIA   -    MD0100PA01X+070676Y+083380X0190Y         S0      
327m5985            J100  -168        A01X+070676Y+083380X0205Y0590R090 S1      
317m5986            VIA   -    MD0080PA01X+050297Y+089876X0160Y    R180 S0      
327m5986            U26   -J21        A01X+050113Y+089980X0177Y    R180 S1      
317m5986            VIA   -    MD0100PA01X+070676Y+079699X0190Y         S0      
327m5986            J100  -157        A01X+070676Y+079699X0205Y0590R090 S1      
317m5987            VIA   -    MD0080PA01X+051037Y+096892X0160Y    R180 S0      
327m5987            U26   -AL19       A01X+050854Y+096996X0177Y    R180 S1      
317m5987            VIA   -    MD0100PA01X+072290Y+093754X0190Y         S0      
327m5987            J100  -55         A01X+072290Y+093754X0205Y0590R090 S1      
317m5988            VIA   -    MD0080PA01X+051037Y+094978X0160Y    R180 S0      
327m5988            U26   -AE19       A01X+050854Y+095083X0177Y    R180 S1      
317m5988            VIA   -    MD0100PA01X+072290Y+090073X0190Y         S0      
327m5988            J100  -44         A01X+072290Y+090073X0205Y0590R090 S1      
317m5989            VIA   -    MD0080PA01X+051037Y+093065X0160Y    R180 S0      
327m5989            U26   -W19        A01X+050854Y+093169X0177Y    R180 S1      
317m5989            VIA   -    MD0100PA01X+072290Y+086392X0190Y         S0      
327m5989            J100  -33         A01X+072290Y+086392X0205Y0590R090 S1      
317m5990            VIA   -    MD0080PA01X+051037Y+091151X0160Y    R180 S0      
327m5990            U26   -N19        A01X+050854Y+091256X0177Y    R180 S1      
317m5990            VIA   -    MD0100PA01X+072290Y+082711X0190Y         S0      
327m5990            J100  -22         A01X+072290Y+082711X0205Y0590R090 S1      
317m5991            VIA   -    MD0080PA01X+051037Y+089238X0160Y    R180 S0      
327m5991            U26   -G19        A01X+050854Y+089343X0177Y    R180 S1      
317m5991            VIA   -    MD0100PA01X+072290Y+079030X0190Y         S0      
327m5991            J100  -11         A01X+072290Y+079030X0205Y0590R090 S1      
317m5992            VIA   -    MD0080PA01X+050482Y+097210X0160Y    R180 S0      
327m5992            U26   -AM21       A01X+050298Y+097315X0177Y    R180 S1      
317m5992            VIA   -    MD0100PA01X+070676Y+094089X0190Y         S0      
327m5992            J100  -200        A01X+070676Y+094089X0205Y0590R090 S1      
317m5993            VIA   -    MD0080PA01X+050482Y+095297X0160Y    R180 S0      
327m5993            U26   -AF21       A01X+050298Y+095402X0177Y    R180 S1      
317m5993            VIA   -    MD0100PA01X+070676Y+090408X0190Y         S0      
327m5993            J100  -189        A01X+070676Y+090408X0205Y0590R090 S1      
317m5994            VIA   -    MD0080PA01X+050482Y+093384X0160Y    R180 S0      
327m5994            U26   -Y21        A01X+050298Y+093488X0177Y    R180 S1      
317m5994            VIA   -    MD0100PA01X+070676Y+086726X0190Y         S0      
327m5994            J100  -178        A01X+070676Y+086726X0205Y0590R090 S1      
317m5995            VIA   -    MD0080PA01X+050482Y+091470X0160Y    R180 S0      
327m5995            U26   -P21        A01X+050298Y+091575X0177Y    R180 S1      
317m5995            VIA   -    MD0100PA01X+070676Y+083045X0190Y         S0      
327m5995            J100  -167        A01X+070676Y+083045X0205Y0590R090 S1      
317m5996            VIA   -    MD0080PA01X+050482Y+089557X0160Y    R180 S0      
327m5996            U26   -H21        A01X+050298Y+089662X0177Y    R180 S1      
317m5996            VIA   -    MD0100PA01X+070676Y+079364X0190Y         S0      
327m5996            J100  -156        A01X+070676Y+079364X0205Y0590R090 S1      
317m5997            VIA   -    MD0080PA01X+050852Y+097210X0160Y    R180 S0      
327m5997            U26   -AM20       A01X+050668Y+097315X0177Y    R180 S1      
317m5997            VIA   -    MD0100PA01X+072290Y+094089X0190Y         S0      
327m5997            J100  -56         A01X+072290Y+094089X0205Y0590R090 S1      
317m5998            VIA   -    MD0080PA01X+050852Y+095297X0160Y    R180 S0      
327m5998            U26   -AF20       A01X+050668Y+095402X0177Y    R180 S1      
317m5998            VIA   -    MD0100PA01X+072290Y+090408X0190Y         S0      
327m5998            J100  -45         A01X+072290Y+090408X0205Y0590R090 S1      
317m5999            VIA   -    MD0080PA01X+050852Y+093384X0160Y    R180 S0      
327m5999            U26   -Y20        A01X+050668Y+093488X0177Y    R180 S1      
317m5999            VIA   -    MD0100PA01X+072290Y+086726X0190Y         S0      
327m5999            J100  -34         A01X+072290Y+086726X0205Y0590R090 S1      
317m6000            VIA   -    MD0080PA01X+050852Y+091470X0160Y    R180 S0      
327m6000            U26   -P20        A01X+050668Y+091575X0177Y    R180 S1      
317m6000            VIA   -    MD0100PA01X+072290Y+083045X0190Y         S0      
327m6000            J100  -23         A01X+072290Y+083045X0205Y0590R090 S1      
317m6001            VIA   -    MD0080PA01X+050852Y+089557X0160Y    R180 S0      
327m6001            U26   -H20        A01X+050668Y+089662X0177Y    R180 S1      
317m6001            VIA   -    MD0100PA01X+072290Y+079364X0190Y         S0      
327m6001            J100  -12         A01X+072290Y+079364X0205Y0590R090 S1      
317m6002            VIA   -    MD0080PA01X+050482Y+090832X0160Y    R180 S0      
327m6002            U26   -M21        A01X+050298Y+090937X0177Y    R180 S1      
317m6002            VIA   -    MD0100PA01X+072290Y+082042X0190Y         S0      
327m6002            J100  -20         A01X+072290Y+082042X0205Y0590R090 S1      
317m6003            VIA   -    MD0080PA01X+051037Y+090514X0160Y    R180 S0      
327m6003            U26   -L19        A01X+050854Y+090618X0177Y    R180 S1      
317m6003            VIA   -    MD0100PA01X+072290Y+081372X0190Y         S0      
327m6003            J100  -18         A01X+072290Y+081372X0205Y0590R090 S1      
317m6004            VIA   -    MD0080PA01X+050297Y+090514X0160Y    R180 S0      
327m6004            U26   -L21        A01X+050113Y+090618X0177Y    R180 S1      
317m6004            VIA   -    MD0100PA01X+070676Y+081038X0190Y         S0      
327m6004            J100  -161        A01X+070676Y+081038X0205Y0590R090 S1      
317m6005            VIA   -    MD0080PA01X+050852Y+090195X0160Y    R180 S0      
327m6005            U26   -K20        A01X+050668Y+090299X0177Y    R180 S1      
317m6005            VIA   -    MD0100PA01X+070676Y+080368X0190Y         S0      
327m6005            J100  -159        A01X+070676Y+080368X0205Y0590R090 S1      
317m6006            VIA   -    MD0080PA01X+050482Y+090195X0160Y    R180 S0      
327m6006            U26   -K21        A01X+050298Y+090299X0177Y    R180 S1      
317m6006            VIA   -    MD0100PA01X+072290Y+080703X0190Y         S0      
327m6006            J100  -16         A01X+072290Y+080703X0205Y0590R090 S1      
317m6007            VIA   -    MD0080PA01X+051037Y+089876X0160Y    R180 S0      
327m6007            U26   -J19        A01X+050854Y+089980X0177Y    R180 S1      
317m6007            VIA   -    MD0100PA01X+072290Y+080034X0190Y         S0      
327m6007            J100  -14         A01X+072290Y+080034X0205Y0590R090 S1      
317m6008            VIA   -    MD0080PA01X+050297Y+089238X0160Y    R180 S0      
327m6008            U26   -G21        A01X+050113Y+089343X0177Y    R180 S1      
317m6008            VIA   -    MD0100PA01X+070676Y+078695X0190Y         S0      
327m6008            J100  -154        A01X+070676Y+078695X0205Y0590R090 S1      
317m6009            VIA   -    MD0080PA01X+050297Y+096254X0160Y    R180 S0      
327m6009            U26   -AJ21       A01X+050113Y+096358X0177Y    R180 S1      
317m6009            VIA   -    MD0100PA01X+070676Y+092081X0190Y         S0      
327m6009            J100  -194        A01X+070676Y+092081X0205Y0590R090 S1      
317m6010            VIA   -    MD0080PA01X+050852Y+095935X0160Y    R180 S0      
327m6010            U26   -AH20       A01X+050668Y+096040X0177Y    R180 S1      
317m6010            VIA   -    MD0100PA01X+070676Y+091412X0190Y         S0      
327m6010            J100  -192        A01X+070676Y+091412X0205Y0590R090 S1      
317m6011            VIA   -    MD0080PA01X+050852Y+088919X0160Y    R180 S0      
327m6011            U26   -F20        A01X+050668Y+089024X0177Y    R180 S1      
317m6011            VIA   -    MD0100PA01X+070676Y+078026X0190Y         S0      
327m6011            J100  -152        A01X+070676Y+078026X0205Y0590R090 S1      
317m6012            VIA   -    MD0080PA01X+050482Y+095935X0160Y    R180 S0      
327m6012            U26   -AH21       A01X+050298Y+096040X0177Y    R180 S1      
317m6012            VIA   -    MD0100PA01X+072290Y+091746X0190Y         S0      
327m6012            J100  -49         A01X+072290Y+091746X0205Y0590R090 S1      
317m6013            VIA   -    MD0080PA01X+051037Y+095616X0160Y    R180 S0      
327m6013            U26   -AG19       A01X+050854Y+095721X0177Y    R180 S1      
317m6013            VIA   -    MD0100PA01X+072290Y+091077X0190Y         S0      
327m6013            J100  -47         A01X+072290Y+091077X0205Y0590R090 S1      
317m6014            VIA   -    MD0080PA01X+050297Y+094978X0160Y    R180 S0      
327m6014            U26   -AE21       A01X+050113Y+095083X0177Y    R180 S1      
317m6014            VIA   -    MD0100PA01X+070676Y+089738X0190Y         S0      
327m6014            J100  -187        A01X+070676Y+089738X0205Y0590R090 S1      
317m6015            VIA   -    MD0080PA01X+050852Y+094659X0160Y    R180 S0      
327m6015            U26   -AD20       A01X+050668Y+094764X0177Y    R180 S1      
317m6015            VIA   -    MD0100PA01X+070676Y+089069X0190Y         S0      
327m6015            J100  -185        A01X+070676Y+089069X0205Y0590R090 S1      
317m6016            VIA   -    MD0080PA01X+050482Y+094659X0160Y    R180 S0      
327m6016            U26   -AD21       A01X+050298Y+094764X0177Y    R180 S1      
317m6016            VIA   -    MD0100PA01X+072290Y+089404X0190Y         S0      
327m6016            J100  -42         A01X+072290Y+089404X0205Y0590R090 S1      
317m6017            VIA   -    MD0080PA01X+051037Y+094340X0160Y    R180 S0      
327m6017            U26   -AC19       A01X+050854Y+094445X0177Y    R180 S1      
317m6017            VIA   -    MD0100PA01X+072290Y+088734X0190Y         S0      
327m6017            J100  -40         A01X+072290Y+088734X0205Y0590R090 S1      
317m6018            VIA   -    MD0080PA01X+050297Y+094340X0160Y    R180 S0      
327m6018            U26   -AC21       A01X+050113Y+094445X0177Y    R180 S1      
317m6018            VIA   -    MD0100PA01X+070676Y+088400X0190Y         S0      
327m6018            J100  -183        A01X+070676Y+088400X0205Y0590R090 S1      
317m6019            VIA   -    MD0080PA01X+050852Y+094021X0160Y    R180 S0      
327m6019            U26   -AB20       A01X+050668Y+094126X0177Y    R180 S1      
317m6019            VIA   -    MD0100PA01X+070676Y+087730X0190Y         S0      
327m6019            J100  -181        A01X+070676Y+087730X0205Y0590R090 S1      
317m6020            VIA   -    MD0080PA01X+050482Y+094021X0160Y    R180 S0      
327m6020            U26   -AB21       A01X+050298Y+094126X0177Y    R180 S1      
317m6020            VIA   -    MD0100PA01X+072290Y+088065X0190Y         S0      
327m6020            J100  -38         A01X+072290Y+088065X0205Y0590R090 S1      
317m6021            VIA   -    MD0080PA01X+051037Y+093702X0160Y    R180 S0      
327m6021            U26   -AA19       A01X+050854Y+093807X0177Y    R180 S1      
317m6021            VIA   -    MD0100PA01X+072290Y+087396X0190Y         S0      
327m6021            J100  -36         A01X+072290Y+087396X0205Y0590R090 S1      
317m6022            VIA   -    MD0080PA01X+050482Y+088919X0160Y    R180 S0      
327m6022            U26   -F21        A01X+050298Y+089024X0177Y    R180 S1      
317m6022            VIA   -    MD0100PA01X+072290Y+078360X0190Y         S0      
327m6022            J100  -9          A01X+072290Y+078360X0205Y0590R090 S1      
317m6023            VIA   -    MD0080PA01X+050297Y+093065X0160Y    R180 S0      
327m6023            U26   -W21        A01X+050113Y+093169X0177Y    R180 S1      
317m6023            VIA   -    MD0100PA01X+070676Y+086057X0190Y         S0      
327m6023            J100  -176        A01X+070676Y+086057X0205Y0590R090 S1      
317m6024            VIA   -    MD0080PA01X+050852Y+092746X0160Y    R180 S0      
327m6024            U26   -V20        A01X+050668Y+092850X0177Y    R180 S1      
317m6024            VIA   -    MD0100PA01X+070676Y+085388X0190Y         S0      
327m6024            J100  -174        A01X+070676Y+085388X0205Y0590R090 S1      
317m6025            VIA   -    MD0080PA01X+050482Y+092746X0160Y    R180 S0      
327m6025            U26   -V21        A01X+050298Y+092850X0177Y    R180 S1      
317m6025            VIA   -    MD0100PA01X+072290Y+085723X0190Y         S0      
327m6025            J100  -31         A01X+072290Y+085723X0205Y0590R090 S1      
317m6026            VIA   -    MD0080PA01X+051037Y+092427X0160Y    R180 S0      
327m6026            U26   -U19        A01X+050854Y+092532X0177Y    R180 S1      
317m6026            VIA   -    MD0100PA01X+072290Y+085053X0190Y         S0      
327m6026            J100  -29         A01X+072290Y+085053X0205Y0590R090 S1      
317m6027            VIA   -    MD0080PA01X+050297Y+092427X0160Y    R180 S0      
327m6027            U26   -U21        A01X+050113Y+092532X0177Y    R180 S1      
317m6027            VIA   -    MD0100PA01X+070676Y+084719X0190Y         S0      
327m6027            J100  -172        A01X+070676Y+084719X0205Y0590R090 S1      
317m6028            VIA   -    MD0080PA01X+050852Y+092108X0160Y    R180 S0      
327m6028            U26   -T20        A01X+050668Y+092213X0177Y    R180 S1      
317m6028            VIA   -    MD0100PA01X+070676Y+084049X0190Y         S0      
327m6028            J100  -170        A01X+070676Y+084049X0205Y0590R090 S1      
317m6029            VIA   -    MD0080PA01X+050482Y+092108X0160Y    R180 S0      
327m6029            U26   -T21        A01X+050298Y+092213X0177Y    R180 S1      
317m6029            VIA   -    MD0100PA01X+072290Y+084384X0190Y         S0      
327m6029            J100  -27         A01X+072290Y+084384X0205Y0590R090 S1      
317m6030            VIA   -    MD0080PA01X+051037Y+091789X0160Y    R180 S0      
327m6030            U26   -R19        A01X+050854Y+091894X0177Y    R180 S1      
317m6030            VIA   -    MD0100PA01X+072290Y+083715X0190Y         S0      
327m6030            J100  -25         A01X+072290Y+083715X0205Y0590R090 S1      
317m6031            VIA   -    MD0080PA01X+050297Y+091151X0160Y    R180 S0      
327m6031            U26   -N21        A01X+050113Y+091256X0177Y    R180 S1      
317m6031            VIA   -    MD0100PA01X+070676Y+082376X0190Y         S0      
327m6031            J100  -165        A01X+070676Y+082376X0205Y0590R090 S1      
317m6032            VIA   -    MD0080PA01X+050852Y+090832X0160Y    R180 S0      
327m6032            U26   -M20        A01X+050668Y+090937X0177Y    R180 S1      
327m6032            J100  -163        A01X+070676Y+081707X0205Y0590R090 S1      
317m6032            VIA   -    MD0100PA01X+070676Y+081707X0190Y         S0      
317m6033            VIA   -    MD0080PA01X+051037Y+088600X0160Y    R180 S0      
327m6033            U26   -E19        A01X+050854Y+088705X0177Y    R180 S1      
317m6033            VIA   -    MD0100PA01X+072290Y+077691X0190Y         S0      
327m6033            J100  -7          A01X+072290Y+077691X0205Y0590R090 S1      
317m6034            VIA   -    MD0080PA01X+050482Y+099124X0160Y    R180 S0      
327m6034            U26   -AV21       A01X+050298Y+099228X0177Y    R180 S1      
317m6034            VIA   -    MD0100PA01X+070676Y+097100X0190Y         S0      
327m6034            J100  -209        A01X+070676Y+097100X0205Y0590R090 S1      
317m6035            VIA   -    MD0080PA01X+051037Y+098805X0160Y    R180 S0      
327m6035            U26   -AU19       A01X+050854Y+098910X0177Y    R180 S1      
317m6035            VIA   -    MD0100PA01X+072290Y+096766X0190Y         S0      
327m6035            J100  -64         A01X+072290Y+096766X0205Y0590R090 S1      
317m6036            VIA   -    MD0080PA01X+050297Y+098167X0160Y    R180 S0      
327m6036            U26   -AR21       A01X+050113Y+098272X0177Y    R180 S1      
317m6036            VIA   -    MD0100PA01X+070676Y+095762X0190Y         S0      
327m6036            J100  -205        A01X+070676Y+095762X0205Y0590R090 S1      
317m6037            VIA   -    MD0080PA01X+050852Y+097848X0160Y    R180 S0      
327m6037            U26   -AP20       A01X+050668Y+097953X0177Y    R180 S1      
317m6037            VIA   -    MD0100PA01X+070676Y+095093X0190Y         S0      
327m6037            J100  -203        A01X+070676Y+095093X0205Y0590R090 S1      
317m6038            VIA   -    MD0080PA01X+050482Y+097848X0160Y    R180 S0      
327m6038            U26   -AP21       A01X+050298Y+097953X0177Y    R180 S1      
317m6038            VIA   -    MD0100PA01X+072290Y+095427X0190Y         S0      
327m6038            J100  -60         A01X+072290Y+095427X0205Y0590R090 S1      
317m6039            VIA   -    MD0080PA01X+051037Y+097529X0160Y    R180 S0      
327m6039            U26   -AN19       A01X+050854Y+097634X0177Y    R180 S1      
317m6039            VIA   -    MD0100PA01X+072290Y+094758X0190Y         S0      
327m6039            J100  -58         A01X+072290Y+094758X0205Y0590R090 S1      
317m6040            VIA   -    MD0080PA01X+050297Y+096892X0160Y    R180 S0      
327m6040            U26   -AL21       A01X+050113Y+096996X0177Y    R180 S1      
317m6040            VIA   -    MD0100PA01X+070676Y+093419X0190Y         S0      
327m6040            J100  -198        A01X+070676Y+093419X0205Y0590R090 S1      
317m6041            VIA   -    MD0080PA01X+050852Y+096573X0160Y    R180 S0      
327m6041            U26   -AK20       A01X+050668Y+096677X0177Y    R180 S1      
317m6041            VIA   -    MD0100PA01X+070676Y+092750X0190Y         S0      
327m6041            J100  -196        A01X+070676Y+092750X0205Y0590R090 S1      
317m6042            VIA   -    MD0080PA01X+050482Y+096573X0160Y    R180 S0      
327m6042            U26   -AK21       A01X+050298Y+096677X0177Y    R180 S1      
317m6042            VIA   -    MD0100PA01X+072290Y+093085X0190Y         S0      
327m6042            J100  -53         A01X+072290Y+093085X0205Y0590R090 S1      
317m6043            VIA   -    MD0080PA01X+051037Y+096254X0160Y    R180 S0      
327m6043            U26   -AJ19       A01X+050854Y+096358X0177Y    R180 S1      
317m6043            VIA   -    MD0100PA01X+072290Y+092416X0190Y         S0      
327m6043            J100  -51         A01X+072290Y+092416X0205Y0590R090 S1      
317m6044            VIA   -    MD0080PA01X+050482Y+100399X0160Y    R180 S0      
327m6044            U26   -BB21       A01X+050298Y+100504X0177Y    R180 S1      
317m6044            VIA   -    MD0100PA01X+072290Y+099443X0190Y         S0      
327m6044            J100  -72         A01X+072290Y+099443X0205Y0590R090 S1      
317m6045            VIA   -    MD0080PA01X+050852Y+100399X0160Y    R180 S0      
327m6045            U26   -BB20       A01X+050668Y+100504X0177Y    R180 S1      
317m6045            VIA   -    MD0100PA01X+070676Y+099108X0190Y         S0      
327m6045            J100  -215        A01X+070676Y+099108X0205Y0590R090 S1      
317m6046            VIA   -    MD0080PA01X+051037Y+100080X0160Y    R180 S0      
327m6046            U26   -BA19       A01X+050854Y+100185X0177Y    R180 S1      
317m6046            VIA   -    MD0100PA01X+072290Y+098774X0190Y         S0      
327m6046            J100  -70         A01X+072290Y+098774X0205Y0590R090 S1      
317m6047            VIA   -    MD0080PA01X+050297Y+100080X0160Y    R180 S0      
327m6047            U26   -BA21       A01X+050113Y+100185X0177Y    R180 S1      
317m6047            VIA   -    MD0100PA01X+070676Y+098439X0190Y         S0      
327m6047            J100  -213        A01X+070676Y+098439X0205Y0590R090 S1      
317m6048            VIA   -    MD0080PA01X+050482Y+099762X0160Y    R180 S0      
327m6048            U26   -AY21       A01X+050298Y+099866X0177Y    R180 S1      
317m6048            VIA   -    MD0100PA01X+072290Y+098104X0190Y         S0      
327m6048            J100  -68         A01X+072290Y+098104X0205Y0590R090 S1      
317m6049            VIA   -    MD0080PA01X+050852Y+099762X0160Y    R180 S0      
327m6049            U26   -AY20       A01X+050668Y+099866X0177Y    R180 S1      
317m6049            VIA   -    MD0100PA01X+070676Y+097770X0190Y         S0      
327m6049            J100  -211        A01X+070676Y+097770X0205Y0590R090 S1      
317m6050            VIA   -    MD0080PA01X+051037Y+099443X0160Y    R180 S0      
327m6050            U26   -AW19       A01X+050854Y+099547X0177Y    R180 S1      
317m6050            VIA   -    MD0100PA01X+072290Y+097435X0190Y         S0      
327m6050            J100  -66         A01X+072290Y+097435X0205Y0590R090 S1      
317m6051            VIA   -    MD0080PA01X+050297Y+098805X0160Y    R180 S0      
327m6051            U26   -AU21       A01X+050113Y+098910X0177Y    R180 S1      
317m6051            VIA   -    MD0100PA01X+070676Y+096431X0190Y         S0      
327m6051            J100  -207        A01X+070676Y+096431X0205Y0590R090 S1      
317m6052            VIA   -    MD0080PA01X+051037Y+100718X0160Y    R180 S0      
327m6052            U26   -BC19       A01X+050854Y+100823X0177Y    R180 S1      
317m6052            VIA   -    MD0100PA01X+070676Y+099778X0190Y         S0      
327m6052            J100  -217        A01X+070676Y+099778X0205Y0590R090 S1      
317m6053            VIA   -    MD0080PA01X+050852Y+101037X0160Y    R180 S0      
327m6053            U26   -BD20       A01X+050668Y+101142X0177Y    R180 S1      
317m6053            VIA   -    MD0100PA01X+070676Y+100112X0190Y         S0      
327m6053            J100  -218        A01X+070676Y+100112X0205Y0590R090 S1      
317m6054            VIA   -    MD0080PA01X+050482Y+098486X0160Y    R180 S0      
327m6054            U26   -AT21       A01X+050298Y+098591X0177Y    R180 S1      
317m6054            VIA   -    MD0100PA18X+071740Y+096097X0190Y         S0      
327m6054            R508  -2          A18X+071740Y+096097X0198Y0197     S2      
327m6055            J100  -62         A01X+072290Y+096097X0205Y0590R090 S1      
317m6055            VIA   -    MD0100PA00X+072290Y+096097X0190Y         S0      
327m6055            R508  -1          A18X+072055Y+096097X0198Y0197     S2      
317m6056            VIA   -    MD0080PA01X+148585Y+105357X0160Y         S0      
327m6056            U25   -BP20       A01X+148401Y+105252X0177Y    R180 S1      
317m6056            VIA   -    MD0100PA01X+169904Y+106470X0190Y         S0      
327m6056            J18   -87         A01X+169904Y+106470X0205Y0590R090 S1      
317m6057            VIA   -    MD0080PA01X+148030Y+104400X0160Y         S0      
327m6057            U25   -BL21       A01X+147846Y+104295X0177Y    R180 S1      
317m6057            VIA   -    MD0100PA01X+168290Y+105132X0190Y         S0      
327m6057            J18   -227        A01X+168290Y+105132X0205Y0590R090 S1      
317m6058            VIA   -    MD0080PA01X+148585Y+106632X0160Y         S0      
327m6058            U25   -BV20       A01X+148401Y+106528X0177Y    R180 S1      
317m6058            VIA   -    MD0100PA01X+169904Y+108478X0190Y         S0      
327m6058            J18   -93         A01X+169904Y+108478X0205Y0590R090 S1      
317m6059            VIA   -    MD0080PA01X+148214Y+114924X0160Y         S0      
327m6059            U25   -DD21       A01X+148031Y+114819X0177Y    R180 S1      
317m6059            VIA   -    MD0100PA01X+168290Y+123872X0190Y         S0      
327m6059            J18   -283        A01X+168290Y+123872X0205Y0590R090 S1      
317m6060            VIA   -    MD0080PA01X+148214Y+113010X0160Y         S0      
327m6060            U25   -CV21       A01X+148031Y+112906X0177Y    R180 S1      
317m6060            VIA   -    MD0100PA01X+168290Y+120191X0190Y         S0      
327m6060            J18   -272        A01X+168290Y+120191X0205Y0590R090 S1      
317m6061            VIA   -    MD0080PA01X+148214Y+111097X0160Y         S0      
327m6061            U25   -CM21       A01X+148031Y+110992X0177Y    R180 S1      
317m6061            VIA   -    MD0100PA01X+168290Y+116510X0190Y         S0      
327m6061            J18   -261        A01X+168290Y+116510X0205Y0590R090 S1      
317m6062            VIA   -    MD0080PA01X+148214Y+109184X0160Y         S0      
327m6062            U25   -CF21       A01X+148031Y+109079X0177Y    R180 S1      
317m6062            VIA   -    MD0100PA01X+168290Y+112829X0190Y         S0      
327m6062            J18   -250        A01X+168290Y+112829X0205Y0590R090 S1      
317m6063            VIA   -    MD0080PA01X+148214Y+107270X0160Y         S0      
327m6063            U25   -BY21       A01X+148031Y+107165X0177Y    R180 S1      
317m6063            VIA   -    MD0100PA01X+168290Y+109148X0190Y         S0      
327m6063            J18   -239        A01X+168290Y+109148X0205Y0590R090 S1      
317m6064            VIA   -    MD0080PA01X+148585Y+114286X0160Y         S0      
327m6064            U25   -DB20       A01X+148401Y+114181X0177Y    R180 S1      
317m6064            VIA   -    MD0100PA01X+169904Y+123203X0190Y         S0      
327m6064            J18   -137        A01X+169904Y+123203X0205Y0590R090 S1      
317m6065            VIA   -    MD0080PA01X+148585Y+112372X0160Y         S0      
327m6065            U25   -CT20       A01X+148401Y+112268X0177Y    R180 S1      
317m6065            VIA   -    MD0100PA01X+169904Y+119522X0190Y         S0      
327m6065            J18   -126        A01X+169904Y+119522X0205Y0590R090 S1      
317m6066            VIA   -    MD0080PA01X+148585Y+110459X0160Y         S0      
327m6066            U25   -CK20       A01X+148401Y+110354X0177Y    R180 S1      
317m6066            VIA   -    MD0100PA01X+169904Y+115841X0190Y         S0      
327m6066            J18   -115        A01X+169904Y+115841X0205Y0590R090 S1      
317m6067            VIA   -    MD0080PA01X+148585Y+108546X0160Y         S0      
327m6067            U25   -CD20       A01X+148401Y+108441X0177Y    R180 S1      
317m6067            VIA   -    MD0100PA01X+169904Y+112160X0190Y         S0      
327m6067            J18   -104        A01X+169904Y+112160X0205Y0590R090 S1      
317m6068            VIA   -    MD0080PA01X+148770Y+106951X0160Y         S0      
327m6068            U25   -BW19       A01X+148586Y+106846X0177Y    R180 S1      
317m6068            VIA   -    MD0100PA01X+169904Y+108813X0190Y         S0      
327m6068            J18   -94         A01X+169904Y+108813X0205Y0590R090 S1      
317m6069            VIA   -    MD0080PA01X+148030Y+114605X0160Y         S0      
327m6069            U25   -DC21       A01X+147846Y+114500X0177Y    R180 S1      
317m6069            VIA   -    MD0100PA01X+168290Y+123537X0190Y         S0      
327m6069            J18   -282        A01X+168290Y+123537X0205Y0590R090 S1      
317m6070            VIA   -    MD0080PA01X+148030Y+112691X0160Y         S0      
327m6070            U25   -CU21       A01X+147846Y+112587X0177Y    R180 S1      
317m6070            VIA   -    MD0100PA01X+168290Y+119856X0190Y         S0      
327m6070            J18   -271        A01X+168290Y+119856X0205Y0590R090 S1      
317m6071            VIA   -    MD0080PA01X+148030Y+110778X0160Y         S0      
327m6071            U25   -CL21       A01X+147846Y+110673X0177Y    R180 S1      
317m6071            VIA   -    MD0100PA01X+168290Y+116175X0190Y         S0      
327m6071            J18   -260        A01X+168290Y+116175X0205Y0590R090 S1      
317m6072            VIA   -    MD0080PA01X+148030Y+108865X0160Y         S0      
327m6072            U25   -CE21       A01X+147846Y+108760X0177Y    R180 S1      
317m6072            VIA   -    MD0100PA01X+168290Y+112494X0190Y         S0      
327m6072            J18   -249        A01X+168290Y+112494X0205Y0590R090 S1      
317m6073            VIA   -    MD0080PA01X+148030Y+106951X0160Y         S0      
327m6073            U25   -BW21       A01X+147846Y+106846X0177Y    R180 S1      
317m6073            VIA   -    MD0100PA01X+168290Y+108813X0190Y         S0      
327m6073            J18   -238        A01X+168290Y+108813X0205Y0590R090 S1      
317m6074            VIA   -    MD0080PA01X+148770Y+114605X0160Y         S0      
327m6074            U25   -DC19       A01X+148586Y+114500X0177Y    R180 S1      
317m6074            VIA   -    MD0100PA01X+169904Y+123537X0190Y         S0      
327m6074            J18   -138        A01X+169904Y+123537X0205Y0590R090 S1      
317m6075            VIA   -    MD0080PA01X+148770Y+112691X0160Y         S0      
327m6075            U25   -CU19       A01X+148586Y+112587X0177Y    R180 S1      
317m6075            VIA   -    MD0100PA01X+169904Y+119856X0190Y         S0      
327m6075            J18   -127        A01X+169904Y+119856X0205Y0590R090 S1      
317m6076            VIA   -    MD0080PA01X+148770Y+110778X0160Y         S0      
327m6076            U25   -CL19       A01X+148586Y+110673X0177Y    R180 S1      
317m6076            VIA   -    MD0100PA01X+169904Y+116175X0190Y         S0      
327m6076            J18   -116        A01X+169904Y+116175X0205Y0590R090 S1      
317m6077            VIA   -    MD0080PA01X+148770Y+108865X0160Y         S0      
327m6077            U25   -CE19       A01X+148586Y+108760X0177Y    R180 S1      
317m6077            VIA   -    MD0100PA01X+169904Y+112494X0190Y         S0      
327m6077            J18   -105        A01X+169904Y+112494X0205Y0590R090 S1      
317m6078            VIA   -    MD0080PA01X+148030Y+110140X0160Y         S0      
327m6078            U25   -CJ21       A01X+147846Y+110036X0177Y    R180 S1      
317m6078            VIA   -    MD0100PA01X+169904Y+115171X0190Y         S0      
327m6078            J18   -113        A01X+169904Y+115171X0205Y0590R090 S1      
317m6079            VIA   -    MD0080PA01X+148585Y+109821X0160Y         S0      
327m6079            U25   -CH20       A01X+148401Y+109717X0177Y    R180 S1      
317m6079            VIA   -    MD0100PA01X+169904Y+114502X0190Y         S0      
327m6079            J18   -111        A01X+169904Y+114502X0205Y0590R090 S1      
317m6080            VIA   -    MD0080PA01X+148214Y+109821X0160Y         S0      
327m6080            U25   -CH21       A01X+148031Y+109717X0177Y    R180 S1      
317m6080            VIA   -    MD0100PA01X+168290Y+114167X0190Y         S0      
327m6080            J18   -254        A01X+168290Y+114167X0205Y0590R090 S1      
317m6081            VIA   -    MD0080PA01X+148770Y+109502X0160Y         S0      
327m6081            U25   -CG19       A01X+148586Y+109398X0177Y    R180 S1      
317m6081            VIA   -    MD0100PA01X+168290Y+113498X0190Y         S0      
327m6081            J18   -252        A01X+168290Y+113498X0205Y0590R090 S1      
317m6082            VIA   -    MD0080PA01X+148030Y+109502X0160Y         S0      
327m6082            U25   -CG21       A01X+147846Y+109398X0177Y    R180 S1      
317m6082            VIA   -    MD0100PA01X+169904Y+113833X0190Y         S0      
327m6082            J18   -109        A01X+169904Y+113833X0205Y0590R090 S1      
317m6083            VIA   -    MD0080PA01X+148585Y+109184X0160Y         S0      
327m6083            U25   -CF20       A01X+148401Y+109079X0177Y    R180 S1      
317m6083            VIA   -    MD0100PA01X+169904Y+113163X0190Y         S0      
327m6083            J18   -107        A01X+169904Y+113163X0205Y0590R090 S1      
317m6084            VIA   -    MD0080PA01X+148214Y+108546X0160Y         S0      
327m6084            U25   -CD21       A01X+148031Y+108441X0177Y    R180 S1      
317m6084            VIA   -    MD0100PA01X+168290Y+111825X0190Y         S0      
327m6084            J18   -247        A01X+168290Y+111825X0205Y0590R090 S1      
317m6085            VIA   -    MD0080PA01X+148214Y+115561X0160Y         S0      
327m6085            U25   -DF21       A01X+148031Y+115457X0177Y    R180 S1      
317m6085            VIA   -    MD0100PA01X+168290Y+125211X0190Y         S0      
327m6085            J18   -287        A01X+168290Y+125211X0205Y0590R090 S1      
317m6086            VIA   -    MD0080PA01X+148770Y+115242X0160Y         S0      
327m6086            U25   -DE19       A01X+148586Y+115138X0177Y    R180 S1      
317m6086            VIA   -    MD0100PA01X+168290Y+124541X0190Y         S0      
327m6086            J18   -285        A01X+168290Y+124541X0205Y0590R090 S1      
317m6087            VIA   -    MD0080PA01X+148770Y+108227X0160Y         S0      
327m6087            U25   -CC19       A01X+148586Y+108122X0177Y    R180 S1      
317m6087            VIA   -    MD0100PA01X+168290Y+111156X0190Y         S0      
327m6087            J18   -245        A01X+168290Y+111156X0205Y0590R090 S1      
317m6088            VIA   -    MD0080PA01X+148030Y+115242X0160Y         S0      
327m6088            U25   -DE21       A01X+147846Y+115138X0177Y    R180 S1      
317m6088            VIA   -    MD0100PA01X+169904Y+124876X0190Y         S0      
327m6088            J18   -142        A01X+169904Y+124876X0205Y0590R090 S1      
317m6089            VIA   -    MD0080PA01X+148585Y+114924X0160Y         S0      
327m6089            U25   -DD20       A01X+148401Y+114819X0177Y    R180 S1      
317m6089            VIA   -    MD0100PA01X+169904Y+124207X0190Y         S0      
327m6089            J18   -140        A01X+169904Y+124207X0205Y0590R090 S1      
317m6090            VIA   -    MD0080PA01X+148214Y+114286X0160Y         S0      
327m6090            U25   -DB21       A01X+148031Y+114181X0177Y    R180 S1      
317m6090            VIA   -    MD0100PA01X+168290Y+122868X0190Y         S0      
327m6090            J18   -280        A01X+168290Y+122868X0205Y0590R090 S1      
317m6091            VIA   -    MD0080PA01X+148770Y+113967X0160Y         S0      
327m6091            U25   -DA19       A01X+148586Y+113862X0177Y    R180 S1      
317m6091            VIA   -    MD0100PA01X+168290Y+122199X0190Y         S0      
327m6091            J18   -278        A01X+168290Y+122199X0205Y0590R090 S1      
317m6092            VIA   -    MD0080PA01X+148030Y+113967X0160Y         S0      
327m6092            U25   -DA21       A01X+147846Y+113862X0177Y    R180 S1      
317m6092            VIA   -    MD0100PA01X+169904Y+122534X0190Y         S0      
327m6092            J18   -135        A01X+169904Y+122534X0205Y0590R090 S1      
317m6093            VIA   -    MD0080PA01X+148585Y+113648X0160Y         S0      
327m6093            U25   -CY20       A01X+148401Y+113543X0177Y    R180 S1      
317m6093            VIA   -    MD0100PA01X+169904Y+121864X0190Y         S0      
327m6093            J18   -133        A01X+169904Y+121864X0205Y0590R090 S1      
317m6094            VIA   -    MD0080PA01X+148214Y+113648X0160Y         S0      
327m6094            U25   -CY21       A01X+148031Y+113543X0177Y    R180 S1      
317m6094            VIA   -    MD0100PA01X+168290Y+121530X0190Y         S0      
327m6094            J18   -276        A01X+168290Y+121530X0205Y0590R090 S1      
317m6095            VIA   -    MD0080PA01X+148770Y+113329X0160Y         S0      
327m6095            U25   -CW19       A01X+148586Y+113224X0177Y    R180 S1      
317m6095            VIA   -    MD0100PA01X+168290Y+120860X0190Y         S0      
327m6095            J18   -274        A01X+168290Y+120860X0205Y0590R090 S1      
317m6096            VIA   -    MD0080PA01X+148030Y+113329X0160Y         S0      
327m6096            U25   -CW21       A01X+147846Y+113224X0177Y    R180 S1      
317m6096            VIA   -    MD0100PA01X+169904Y+121195X0190Y         S0      
327m6096            J18   -131        A01X+169904Y+121195X0205Y0590R090 S1      
317m6097            VIA   -    MD0080PA01X+148585Y+113010X0160Y         S0      
327m6097            U25   -CV20       A01X+148401Y+112906X0177Y    R180 S1      
317m6097            VIA   -    MD0100PA01X+169904Y+120526X0190Y         S0      
327m6097            J18   -129        A01X+169904Y+120526X0205Y0590R090 S1      
317m6098            VIA   -    MD0080PA01X+148030Y+108227X0160Y         S0      
327m6098            U25   -CC21       A01X+147846Y+108122X0177Y    R180 S1      
317m6098            VIA   -    MD0100PA01X+169904Y+111490X0190Y         S0      
327m6098            J18   -102        A01X+169904Y+111490X0205Y0590R090 S1      
317m6099            VIA   -    MD0080PA01X+148214Y+112372X0160Y         S0      
327m6099            U25   -CT21       A01X+148031Y+112268X0177Y    R180 S1      
317m6099            VIA   -    MD0100PA01X+168290Y+119187X0190Y         S0      
327m6099            J18   -269        A01X+168290Y+119187X0205Y0590R090 S1      
317m6100            VIA   -    MD0080PA01X+148770Y+112054X0160Y         S0      
327m6100            U25   -CR19       A01X+148586Y+111949X0177Y    R180 S1      
317m6100            VIA   -    MD0100PA01X+168290Y+118518X0190Y         S0      
327m6100            J18   -267        A01X+168290Y+118518X0205Y0590R090 S1      
317m6101            VIA   -    MD0080PA01X+148030Y+112054X0160Y         S0      
327m6101            U25   -CR21       A01X+147846Y+111949X0177Y    R180 S1      
317m6101            VIA   -    MD0100PA01X+169904Y+118852X0190Y         S0      
327m6101            J18   -124        A01X+169904Y+118852X0205Y0590R090 S1      
317m6102            VIA   -    MD0080PA01X+148585Y+111735X0160Y         S0      
327m6102            U25   -CP20       A01X+148401Y+111630X0177Y    R180 S1      
317m6102            VIA   -    MD0100PA01X+169904Y+118183X0190Y         S0      
327m6102            J18   -122        A01X+169904Y+118183X0205Y0590R090 S1      
317m6103            VIA   -    MD0080PA01X+148214Y+111735X0160Y         S0      
327m6103            U25   -CP21       A01X+148031Y+111630X0177Y    R180 S1      
317m6103            VIA   -    MD0100PA01X+168290Y+117848X0190Y         S0      
327m6103            J18   -265        A01X+168290Y+117848X0205Y0590R090 S1      
317m6104            VIA   -    MD0080PA01X+148770Y+111416X0160Y         S0      
327m6104            U25   -CN19       A01X+148586Y+111311X0177Y    R180 S1      
317m6104            VIA   -    MD0100PA01X+168290Y+117179X0190Y         S0      
327m6104            J18   -263        A01X+168290Y+117179X0205Y0590R090 S1      
317m6105            VIA   -    MD0080PA01X+148030Y+111416X0160Y         S0      
327m6105            U25   -CN21       A01X+147846Y+111311X0177Y    R180 S1      
317m6105            VIA   -    MD0100PA01X+169904Y+117514X0190Y         S0      
327m6105            J18   -120        A01X+169904Y+117514X0205Y0590R090 S1      
317m6106            VIA   -    MD0080PA01X+148585Y+111097X0160Y         S0      
327m6106            U25   -CM20       A01X+148401Y+110992X0177Y    R180 S1      
317m6106            VIA   -    MD0100PA01X+169904Y+116844X0190Y         S0      
327m6106            J18   -118        A01X+169904Y+116844X0205Y0590R090 S1      
317m6107            VIA   -    MD0080PA01X+148214Y+110459X0160Y         S0      
327m6107            U25   -CK21       A01X+148031Y+110354X0177Y    R180 S1      
317m6107            VIA   -    MD0100PA01X+168290Y+115506X0190Y         S0      
327m6107            J18   -258        A01X+168290Y+115506X0205Y0590R090 S1      
317m6108            VIA   -    MD0080PA01X+148770Y+110140X0160Y         S0      
327m6108            U25   -CJ19       A01X+148586Y+110036X0177Y    R180 S1      
317m6108            VIA   -    MD0100PA01X+168290Y+114837X0190Y         S0      
327m6108            J18   -256        A01X+168290Y+114837X0205Y0590R090 S1      
317m6109            VIA   -    MD0080PA01X+148585Y+107908X0160Y         S0      
327m6109            U25   -CB20       A01X+148401Y+107803X0177Y    R180 S1      
317m6109            VIA   -    MD0100PA01X+169904Y+110821X0190Y         S0      
327m6109            J18   -100        A01X+169904Y+110821X0205Y0590R090 S1      
317m6110            VIA   -    MD0080PA01X+148770Y+105038X0160Y         S0      
327m6110            U25   -BN19       A01X+148586Y+104933X0177Y    R180 S1      
317m6110            VIA   -    MD0100PA01X+168290Y+105801X0190Y         S0      
327m6110            J18   -229        A01X+168290Y+105801X0205Y0590R090 S1      
317m6111            VIA   -    MD0080PA01X+148214Y+104719X0160Y         S0      
327m6111            U25   -BM21       A01X+148031Y+104614X0177Y    R180 S1      
317m6111            VIA   -    MD0100PA01X+169904Y+105467X0190Y         S0      
327m6111            J18   -84         A01X+169904Y+105467X0205Y0590R090 S1      
317m6112            VIA   -    MD0080PA01X+148214Y+106632X0160Y         S0      
327m6112            U25   -BV21       A01X+148031Y+106528X0177Y    R180 S1      
317m6112            VIA   -    MD0100PA01X+168290Y+108144X0190Y         S0      
327m6112            J18   -236        A01X+168290Y+108144X0205Y0590R090 S1      
317m6113            VIA   -    MD0080PA01X+148770Y+106313X0160Y         S0      
327m6113            U25   -BU19       A01X+148586Y+106209X0177Y    R180 S1      
317m6113            VIA   -    MD0100PA01X+168290Y+107474X0190Y         S0      
327m6113            J18   -234        A01X+168290Y+107474X0205Y0590R090 S1      
317m6114            VIA   -    MD0080PA01X+148030Y+106313X0160Y         S0      
327m6114            U25   -BU21       A01X+147846Y+106209X0177Y    R180 S1      
317m6114            VIA   -    MD0100PA01X+169904Y+107809X0190Y         S0      
327m6114            J18   -91         A01X+169904Y+107809X0205Y0590R090 S1      
317m6115            VIA   -    MD0080PA01X+148585Y+105994X0160Y         S0      
327m6115            U25   -BT20       A01X+148401Y+105890X0177Y    R180 S1      
317m6115            VIA   -    MD0100PA01X+169904Y+107140X0190Y         S0      
327m6115            J18   -89         A01X+169904Y+107140X0205Y0590R090 S1      
317m6116            VIA   -    MD0080PA01X+148214Y+107908X0160Y         S0      
327m6116            U25   -CB21       A01X+148031Y+107803X0177Y    R180 S1      
317m6116            VIA   -    MD0100PA01X+168290Y+110486X0190Y         S0      
327m6116            J18   -243        A01X+168290Y+110486X0205Y0590R090 S1      
317m6117            VIA   -    MD0080PA01X+148770Y+107589X0160Y         S0      
327m6117            U25   -CA19       A01X+148586Y+107484X0177Y    R180 S1      
317m6117            VIA   -    MD0100PA01X+168290Y+109817X0190Y         S0      
327m6117            J18   -241        A01X+168290Y+109817X0205Y0590R090 S1      
317m6118            VIA   -    MD0080PA01X+148030Y+107589X0160Y         S0      
327m6118            U25   -CA21       A01X+147846Y+107484X0177Y    R180 S1      
317m6118            VIA   -    MD0100PA01X+169904Y+110152X0190Y         S0      
327m6118            J18   -98         A01X+169904Y+110152X0205Y0590R090 S1      
317m6119            VIA   -    MD0080PA01X+148585Y+107270X0160Y         S0      
327m6119            U25   -BY20       A01X+148401Y+107165X0177Y    R180 S1      
317m6119            VIA   -    MD0100PA01X+169904Y+109482X0190Y         S0      
327m6119            J18   -96         A01X+169904Y+109482X0205Y0590R090 S1      
317m6120            VIA   -    MD0080PA01X+148585Y+104081X0160Y         S0      
327m6120            U25   -BK20       A01X+148401Y+103976X0177Y    R180 S1      
317m6120            VIA   -    MD0100PA01X+169904Y+104797X0190Y         S0      
327m6120            J18   -82         A01X+169904Y+104797X0205Y0590R090 S1      
317m6121            VIA   -    MD0080PA01X+148214Y+104081X0160Y         S0      
327m6121            U25   -BK21       A01X+148031Y+103976X0177Y    R180 S1      
317m6121            VIA   -    MD0100PA01X+168290Y+104463X0190Y         S0      
327m6121            J18   -225        A01X+168290Y+104463X0205Y0590R090 S1      
317m6122            VIA   -    MD0080PA01X+148030Y+103762X0160Y         S0      
327m6122            U25   -BJ21       A01X+147846Y+103658X0177Y    R180 S1      
317m6122            VIA   -    MD0100PA01X+169904Y+104128X0190Y         S0      
327m6122            J18   -80         A01X+169904Y+104128X0205Y0590R090 S1      
317m6123            VIA   -    MD0080PA01X+148770Y+103762X0160Y         S0      
327m6123            U25   -BJ19       A01X+148586Y+103658X0177Y    R180 S1      
317m6123            VIA   -    MD0100PA01X+168290Y+103793X0190Y         S0      
327m6123            J18   -223        A01X+168290Y+103793X0205Y0590R090 S1      
317m6124            VIA   -    MD0080PA01X+148585Y+103443X0160Y         S0      
327m6124            U25   -BH20       A01X+148401Y+103339X0177Y    R180 S1      
317m6124            VIA   -    MD0100PA01X+169904Y+103459X0190Y         S0      
327m6124            J18   -78         A01X+169904Y+103459X0205Y0590R090 S1      
317m6125            VIA   -    MD0080PA01X+148214Y+103443X0160Y         S0      
327m6125            U25   -BH21       A01X+148031Y+103339X0177Y    R180 S1      
317m6125            VIA   -    MD0100PA01X+168290Y+103124X0190Y         S0      
327m6125            J18   -221        A01X+168290Y+103124X0205Y0590R090 S1      
317m6126            VIA   -    MD0080PA01X+148030Y+103124X0160Y         S0      
327m6126            U25   -BG21       A01X+147846Y+103020X0177Y    R180 S1      
317m6126            VIA   -    MD0100PA01X+169904Y+102789X0190Y         S0      
327m6126            J18   -76         A01X+169904Y+102789X0205Y0590R090 S1      
317m6127            VIA   -    MD0080PA01X+148030Y+105038X0160Y         S0      
327m6127            U25   -BN21       A01X+147846Y+104933X0177Y    R180 S1      
317m6127            VIA   -    MD0100PA01X+169904Y+106136X0190Y         S0      
327m6127            J18   -86         A01X+169904Y+106136X0205Y0590R090 S1      
317m6128            VIA   -    MD0080PA01X+147911Y+100718X0160Y    R180 S0      
327m6128            U25   -BC21       A01X+147728Y+100823X0177Y    R180 S1      
317m6128            VIA   -    MD0100PA01X+169904Y+100112X0190Y         S0      
327m6128            J18   -74         A01X+169904Y+100112X0205Y0590R090 S1      
317m6129            VIA   -    MD0080PA01X+147911Y+097529X0160Y    R180 S0      
327m6129            U25   -AN21       A01X+147728Y+097634X0177Y    R180 S1      
317m6129            VIA   -    MD0100PA01X+168290Y+094423X0190Y         S0      
327m6129            J18   -201        A01X+168290Y+094423X0205Y0590R090 S1      
317m6130            VIA   -    MD0080PA01X+147911Y+095616X0160Y    R180 S0      
327m6130            U25   -AG21       A01X+147728Y+095720X0177Y    R180 S1      
317m6130            VIA   -    MD0100PA01X+168290Y+090742X0190Y         S0      
327m6130            J18   -190        A01X+168290Y+090742X0205Y0590R090 S1      
317m6131            VIA   -    MD0080PA01X+147911Y+093702X0160Y    R180 S0      
327m6131            U25   -AA21       A01X+147728Y+093807X0177Y    R180 S1      
317m6131            VIA   -    MD0100PA01X+168290Y+087061X0190Y         S0      
327m6131            J18   -179        A01X+168290Y+087061X0205Y0590R090 S1      
317m6132            VIA   -    MD0080PA01X+147911Y+091789X0160Y    R180 S0      
327m6132            U25   -R21        A01X+147728Y+091894X0177Y    R180 S1      
317m6132            VIA   -    MD0100PA01X+168290Y+083380X0190Y         S0      
327m6132            J18   -168        A01X+168290Y+083380X0205Y0590R090 S1      
317m6133            VIA   -    MD0080PA01X+147911Y+089876X0160Y    R180 S0      
327m6133            U25   -J21        A01X+147728Y+089980X0177Y    R180 S1      
317m6133            VIA   -    MD0100PA01X+168290Y+079699X0190Y         S0      
327m6133            J18   -157        A01X+168290Y+079699X0205Y0590R090 S1      
317m6134            VIA   -    MD0080PA01X+148652Y+096891X0160Y    R180 S0      
327m6134            U25   -AL19       A01X+148468Y+096996X0177Y    R180 S1      
317m6134            VIA   -    MD0100PA01X+169904Y+093754X0190Y         S0      
327m6134            J18   -55         A01X+169904Y+093754X0205Y0590R090 S1      
317m6135            VIA   -    MD0080PA01X+148652Y+094978X0160Y    R180 S0      
327m6135            U25   -AE19       A01X+148468Y+095083X0177Y    R180 S1      
317m6135            VIA   -    MD0100PA01X+169904Y+090073X0190Y         S0      
327m6135            J18   -44         A01X+169904Y+090073X0205Y0590R090 S1      
317m6136            VIA   -    MD0080PA01X+148652Y+093065X0160Y    R180 S0      
327m6136            U25   -W19        A01X+148468Y+093169X0177Y    R180 S1      
317m6136            VIA   -    MD0100PA01X+169904Y+086392X0190Y         S0      
327m6136            J18   -33         A01X+169904Y+086392X0205Y0590R090 S1      
317m6137            VIA   -    MD0080PA01X+148652Y+091151X0160Y    R180 S0      
327m6137            U25   -N19        A01X+148468Y+091256X0177Y    R180 S1      
317m6137            VIA   -    MD0100PA01X+169904Y+082711X0190Y         S0      
327m6137            J18   -22         A01X+169904Y+082711X0205Y0590R090 S1      
317m6138            VIA   -    MD0080PA01X+148652Y+089238X0160Y    R180 S0      
327m6138            U25   -G19        A01X+148468Y+089343X0177Y    R180 S1      
317m6138            VIA   -    MD0100PA01X+169904Y+079030X0190Y         S0      
327m6138            J18   -11         A01X+169904Y+079030X0205Y0590R090 S1      
317m6139            VIA   -    MD0080PA01X+148096Y+097210X0160Y    R180 S0      
327m6139            U25   -AM21       A01X+147913Y+097315X0177Y    R180 S1      
317m6139            VIA   -    MD0100PA01X+168290Y+094089X0190Y         S0      
327m6139            J18   -200        A01X+168290Y+094089X0205Y0590R090 S1      
317m6140            VIA   -    MD0080PA01X+148096Y+095297X0160Y    R180 S0      
327m6140            U25   -AF21       A01X+147913Y+095402X0177Y    R180 S1      
317m6140            VIA   -    MD0100PA01X+168290Y+090408X0190Y         S0      
327m6140            J18   -189        A01X+168290Y+090408X0205Y0590R090 S1      
317m6141            VIA   -    MD0080PA01X+148096Y+093384X0160Y    R180 S0      
327m6141            U25   -Y21        A01X+147913Y+093488X0177Y    R180 S1      
317m6141            VIA   -    MD0100PA01X+168290Y+086726X0190Y         S0      
327m6141            J18   -178        A01X+168290Y+086726X0205Y0590R090 S1      
317m6142            VIA   -    MD0080PA01X+148096Y+091470X0160Y    R180 S0      
327m6142            U25   -P21        A01X+147913Y+091575X0177Y    R180 S1      
317m6142            VIA   -    MD0100PA01X+168290Y+083045X0190Y         S0      
327m6142            J18   -167        A01X+168290Y+083045X0205Y0590R090 S1      
317m6143            VIA   -    MD0080PA01X+148096Y+089557X0160Y    R180 S0      
327m6143            U25   -H21        A01X+147913Y+089662X0177Y    R180 S1      
317m6143            VIA   -    MD0100PA01X+168290Y+079364X0190Y         S0      
327m6143            J18   -156        A01X+168290Y+079364X0205Y0590R090 S1      
317m6144            VIA   -    MD0080PA01X+148466Y+097210X0160Y    R180 S0      
327m6144            U25   -AM20       A01X+148283Y+097315X0177Y    R180 S1      
317m6144            VIA   -    MD0100PA01X+169904Y+094089X0190Y         S0      
327m6144            J18   -56         A01X+169904Y+094089X0205Y0590R090 S1      
317m6145            VIA   -    MD0080PA01X+148466Y+095297X0160Y    R180 S0      
327m6145            U25   -AF20       A01X+148283Y+095402X0177Y    R180 S1      
317m6145            VIA   -    MD0100PA01X+169904Y+090408X0190Y         S0      
327m6145            J18   -45         A01X+169904Y+090408X0205Y0590R090 S1      
317m6146            VIA   -    MD0080PA01X+148466Y+093384X0160Y    R180 S0      
327m6146            U25   -Y20        A01X+148283Y+093488X0177Y    R180 S1      
317m6146            VIA   -    MD0100PA01X+169904Y+086726X0190Y         S0      
327m6146            J18   -34         A01X+169904Y+086726X0205Y0590R090 S1      
317m6147            VIA   -    MD0080PA01X+148466Y+091470X0160Y    R180 S0      
327m6147            U25   -P20        A01X+148283Y+091575X0177Y    R180 S1      
317m6147            VIA   -    MD0100PA01X+169904Y+083045X0190Y         S0      
327m6147            J18   -23         A01X+169904Y+083045X0205Y0590R090 S1      
317m6148            VIA   -    MD0080PA01X+148466Y+089557X0160Y    R180 S0      
327m6148            U25   -H20        A01X+148283Y+089662X0177Y    R180 S1      
317m6148            VIA   -    MD0100PA01X+169904Y+079364X0190Y         S0      
327m6148            J18   -12         A01X+169904Y+079364X0205Y0590R090 S1      
317m6149            VIA   -    MD0080PA01X+148096Y+090832X0160Y    R180 S0      
327m6149            U25   -M21        A01X+147913Y+090937X0177Y    R180 S1      
317m6149            VIA   -    MD0100PA01X+169904Y+082041X0190Y         S0      
327m6149            J18   -20         A01X+169904Y+082041X0205Y0590R090 S1      
317m6150            VIA   -    MD0080PA01X+148652Y+090513X0160Y    R180 S0      
327m6150            U25   -L19        A01X+148468Y+090618X0177Y    R180 S1      
317m6150            VIA   -    MD0100PA01X+169904Y+081372X0190Y         S0      
327m6150            J18   -18         A01X+169904Y+081372X0205Y0590R090 S1      
317m6151            VIA   -    MD0080PA01X+147911Y+090513X0160Y    R180 S0      
327m6151            U25   -L21        A01X+147728Y+090618X0177Y    R180 S1      
317m6151            VIA   -    MD0100PA01X+168290Y+081037X0190Y         S0      
327m6151            J18   -161        A01X+168290Y+081037X0205Y0590R090 S1      
317m6152            VIA   -    MD0080PA01X+148466Y+090195X0160Y    R180 S0      
327m6152            U25   -K20        A01X+148283Y+090299X0177Y    R180 S1      
317m6152            VIA   -    MD0100PA01X+168290Y+080368X0190Y         S0      
327m6152            J18   -159        A01X+168290Y+080368X0205Y0590R090 S1      
317m6153            VIA   -    MD0080PA01X+148096Y+090195X0160Y    R180 S0      
327m6153            U25   -K21        A01X+147913Y+090299X0177Y    R180 S1      
317m6153            VIA   -    MD0100PA01X+169904Y+080703X0190Y         S0      
327m6153            J18   -16         A01X+169904Y+080703X0205Y0590R090 S1      
317m6154            VIA   -    MD0080PA01X+148652Y+089876X0160Y    R180 S0      
327m6154            U25   -J19        A01X+148468Y+089980X0177Y    R180 S1      
317m6154            VIA   -    MD0100PA01X+169904Y+080034X0190Y         S0      
327m6154            J18   -14         A01X+169904Y+080034X0205Y0590R090 S1      
317m6155            VIA   -    MD0080PA01X+147911Y+089238X0160Y    R180 S0      
327m6155            U25   -G21        A01X+147728Y+089343X0177Y    R180 S1      
317m6155            VIA   -    MD0100PA01X+168290Y+078695X0190Y         S0      
327m6155            J18   -154        A01X+168290Y+078695X0205Y0590R090 S1      
317m6156            VIA   -    MD0080PA01X+147911Y+096254X0160Y    R180 S0      
327m6156            U25   -AJ21       A01X+147728Y+096358X0177Y    R180 S1      
317m6156            VIA   -    MD0100PA01X+168290Y+092081X0190Y         S0      
327m6156            J18   -194        A01X+168290Y+092081X0205Y0590R090 S1      
317m6157            VIA   -    MD0080PA01X+148466Y+095935X0160Y    R180 S0      
327m6157            U25   -AH20       A01X+148283Y+096039X0177Y    R180 S1      
317m6157            VIA   -    MD0100PA01X+168290Y+091411X0190Y         S0      
327m6157            J18   -192        A01X+168290Y+091411X0205Y0590R090 S1      
317m6158            VIA   -    MD0080PA01X+148466Y+088919X0160Y    R180 S0      
327m6158            U25   -F20        A01X+148283Y+089024X0177Y    R180 S1      
317m6158            VIA   -    MD0100PA01X+168290Y+078026X0190Y         S0      
327m6158            J18   -152        A01X+168290Y+078026X0205Y0590R090 S1      
317m6159            VIA   -    MD0080PA01X+148096Y+095935X0160Y    R180 S0      
327m6159            U25   -AH21       A01X+147913Y+096039X0177Y    R180 S1      
317m6159            VIA   -    MD0100PA01X+169904Y+091746X0190Y         S0      
327m6159            J18   -49         A01X+169904Y+091746X0205Y0590R090 S1      
317m6160            VIA   -    MD0080PA01X+148652Y+095616X0160Y    R180 S0      
327m6160            U25   -AG19       A01X+148468Y+095720X0177Y    R180 S1      
317m6160            VIA   -    MD0100PA01X+169904Y+091077X0190Y         S0      
327m6160            J18   -47         A01X+169904Y+091077X0205Y0590R090 S1      
317m6161            VIA   -    MD0080PA01X+147911Y+094978X0160Y    R180 S0      
327m6161            U25   -AE21       A01X+147728Y+095083X0177Y    R180 S1      
317m6161            VIA   -    MD0100PA01X+168290Y+089738X0190Y         S0      
327m6161            J18   -187        A01X+168290Y+089738X0205Y0590R090 S1      
317m6162            VIA   -    MD0080PA01X+148466Y+094659X0160Y    R180 S0      
327m6162            U25   -AD20       A01X+148283Y+094764X0177Y    R180 S1      
317m6162            VIA   -    MD0100PA01X+168290Y+089069X0190Y         S0      
327m6162            J18   -185        A01X+168290Y+089069X0205Y0590R090 S1      
317m6163            VIA   -    MD0080PA01X+148096Y+094659X0160Y    R180 S0      
327m6163            U25   -AD21       A01X+147913Y+094764X0177Y    R180 S1      
317m6163            VIA   -    MD0100PA01X+169904Y+089404X0190Y         S0      
327m6163            J18   -42         A01X+169904Y+089404X0205Y0590R090 S1      
317m6164            VIA   -    MD0080PA01X+148652Y+094340X0160Y    R180 S0      
327m6164            U25   -AC19       A01X+148468Y+094445X0177Y    R180 S1      
317m6164            VIA   -    MD0100PA01X+169904Y+088734X0190Y         S0      
327m6164            J18   -40         A01X+169904Y+088734X0205Y0590R090 S1      
317m6165            VIA   -    MD0080PA01X+147911Y+094340X0160Y    R180 S0      
327m6165            U25   -AC21       A01X+147728Y+094445X0177Y    R180 S1      
317m6165            VIA   -    MD0100PA01X+168290Y+088400X0190Y         S0      
327m6165            J18   -183        A01X+168290Y+088400X0205Y0590R090 S1      
317m6166            VIA   -    MD0080PA01X+148466Y+094021X0160Y    R180 S0      
327m6166            U25   -AB20       A01X+148283Y+094126X0177Y    R180 S1      
317m6166            VIA   -    MD0100PA01X+168290Y+087730X0190Y         S0      
327m6166            J18   -181        A01X+168290Y+087730X0205Y0590R090 S1      
317m6167            VIA   -    MD0080PA01X+148096Y+094021X0160Y    R180 S0      
327m6167            U25   -AB21       A01X+147913Y+094126X0177Y    R180 S1      
317m6167            VIA   -    MD0100PA01X+169904Y+088065X0190Y         S0      
327m6167            J18   -38         A01X+169904Y+088065X0205Y0590R090 S1      
317m6168            VIA   -    MD0080PA01X+148652Y+093702X0160Y    R180 S0      
327m6168            U25   -AA19       A01X+148468Y+093807X0177Y    R180 S1      
317m6168            VIA   -    MD0100PA01X+169904Y+087396X0190Y         S0      
327m6168            J18   -36         A01X+169904Y+087396X0205Y0590R090 S1      
317m6169            VIA   -    MD0080PA01X+148096Y+088919X0160Y    R180 S0      
327m6169            U25   -F21        A01X+147913Y+089024X0177Y    R180 S1      
317m6169            VIA   -    MD0100PA01X+169904Y+078360X0190Y         S0      
327m6169            J18   -9          A01X+169904Y+078360X0205Y0590R090 S1      
317m6170            VIA   -    MD0080PA01X+147911Y+093065X0160Y    R180 S0      
327m6170            U25   -W21        A01X+147728Y+093169X0177Y    R180 S1      
317m6170            VIA   -    MD0100PA01X+168290Y+086057X0190Y         S0      
327m6170            J18   -176        A01X+168290Y+086057X0205Y0590R090 S1      
317m6171            VIA   -    MD0080PA01X+148466Y+092746X0160Y    R180 S0      
327m6171            U25   -V20        A01X+148283Y+092850X0177Y    R180 S1      
317m6171            VIA   -    MD0100PA01X+168290Y+085388X0190Y         S0      
327m6171            J18   -174        A01X+168290Y+085388X0205Y0590R090 S1      
317m6172            VIA   -    MD0080PA01X+148096Y+092746X0160Y    R180 S0      
327m6172            U25   -V21        A01X+147913Y+092850X0177Y    R180 S1      
317m6172            VIA   -    MD0100PA01X+169904Y+085722X0190Y         S0      
327m6172            J18   -31         A01X+169904Y+085722X0205Y0590R090 S1      
317m6173            VIA   -    MD0080PA01X+148652Y+092427X0160Y    R180 S0      
327m6173            U25   -U19        A01X+148468Y+092532X0177Y    R180 S1      
317m6173            VIA   -    MD0100PA01X+169904Y+085053X0190Y         S0      
327m6173            J18   -29         A01X+169904Y+085053X0205Y0590R090 S1      
317m6174            VIA   -    MD0080PA01X+147911Y+092427X0160Y    R180 S0      
327m6174            U25   -U21        A01X+147728Y+092532X0177Y    R180 S1      
317m6174            VIA   -    MD0100PA01X+168290Y+084718X0190Y         S0      
327m6174            J18   -172        A01X+168290Y+084718X0205Y0590R090 S1      
317m6175            VIA   -    MD0080PA01X+148466Y+092108X0160Y    R180 S0      
327m6175            U25   -T20        A01X+148283Y+092213X0177Y    R180 S1      
317m6175            VIA   -    MD0100PA01X+168290Y+084049X0190Y         S0      
327m6175            J18   -170        A01X+168290Y+084049X0205Y0590R090 S1      
317m6176            VIA   -    MD0080PA01X+148096Y+092108X0160Y    R180 S0      
327m6176            U25   -T21        A01X+147913Y+092213X0177Y    R180 S1      
317m6176            VIA   -    MD0100PA01X+169904Y+084384X0190Y         S0      
327m6176            J18   -27         A01X+169904Y+084384X0205Y0590R090 S1      
317m6177            VIA   -    MD0080PA01X+148652Y+091789X0160Y    R180 S0      
327m6177            U25   -R19        A01X+148468Y+091894X0177Y    R180 S1      
317m6177            VIA   -    MD0100PA01X+169904Y+083715X0190Y         S0      
327m6177            J18   -25         A01X+169904Y+083715X0205Y0590R090 S1      
317m6178            VIA   -    MD0080PA01X+147911Y+091151X0160Y    R180 S0      
327m6178            U25   -N21        A01X+147728Y+091256X0177Y    R180 S1      
317m6178            VIA   -    MD0100PA01X+168290Y+082376X0190Y         S0      
327m6178            J18   -165        A01X+168290Y+082376X0205Y0590R090 S1      
317m6179            VIA   -    MD0080PA01X+148466Y+090832X0160Y    R180 S0      
327m6179            U25   -M20        A01X+148283Y+090937X0177Y    R180 S1      
327m6179            J18   -163        A01X+168290Y+081707X0205Y0590R090 S1      
317m6179            VIA   -    MD0100PA01X+168290Y+081707X0190Y         S0      
317m6180            VIA   -    MD0080PA01X+148652Y+088600X0160Y    R180 S0      
327m6180            U25   -E19        A01X+148468Y+088705X0177Y    R180 S1      
317m6180            VIA   -    MD0100PA01X+169904Y+077691X0190Y         S0      
327m6180            J18   -7          A01X+169904Y+077691X0205Y0590R090 S1      
317m6181            VIA   -    MD0080PA01X+148096Y+099124X0160Y    R180 S0      
327m6181            U25   -AV21       A01X+147913Y+099228X0177Y    R180 S1      
317m6181            VIA   -    MD0100PA01X+168290Y+097100X0190Y         S0      
327m6181            J18   -209        A01X+168290Y+097100X0205Y0590R090 S1      
317m6182            VIA   -    MD0080PA01X+148652Y+098805X0160Y    R180 S0      
327m6182            U25   -AU19       A01X+148468Y+098910X0177Y    R180 S1      
317m6182            VIA   -    MD0100PA01X+169904Y+096766X0190Y         S0      
327m6182            J18   -64         A01X+169904Y+096766X0205Y0590R090 S1      
317m6183            VIA   -    MD0080PA01X+147911Y+098167X0160Y    R180 S0      
327m6183            U25   -AR21       A01X+147728Y+098272X0177Y    R180 S1      
317m6183            VIA   -    MD0100PA01X+168290Y+095762X0190Y         S0      
327m6183            J18   -205        A01X+168290Y+095762X0205Y0590R090 S1      
317m6184            VIA   -    MD0080PA01X+148466Y+097848X0160Y    R180 S0      
327m6184            U25   -AP20       A01X+148283Y+097953X0177Y    R180 S1      
317m6184            VIA   -    MD0100PA01X+168290Y+095092X0190Y         S0      
327m6184            J18   -203        A01X+168290Y+095092X0205Y0590R090 S1      
317m6185            VIA   -    MD0080PA01X+148096Y+097848X0160Y    R180 S0      
327m6185            U25   -AP21       A01X+147913Y+097953X0177Y    R180 S1      
317m6185            VIA   -    MD0100PA01X+169904Y+095427X0190Y         S0      
327m6185            J18   -60         A01X+169904Y+095427X0205Y0590R090 S1      
317m6186            VIA   -    MD0080PA01X+148652Y+097529X0160Y    R180 S0      
327m6186            U25   -AN19       A01X+148468Y+097634X0177Y    R180 S1      
317m6186            VIA   -    MD0100PA01X+169904Y+094758X0190Y         S0      
327m6186            J18   -58         A01X+169904Y+094758X0205Y0590R090 S1      
317m6187            VIA   -    MD0080PA01X+147911Y+096891X0160Y    R180 S0      
327m6187            U25   -AL21       A01X+147728Y+096996X0177Y    R180 S1      
317m6187            VIA   -    MD0100PA01X+168290Y+093419X0190Y         S0      
327m6187            J18   -198        A01X+168290Y+093419X0205Y0590R090 S1      
317m6188            VIA   -    MD0080PA01X+148466Y+096572X0160Y    R180 S0      
327m6188            U25   -AK20       A01X+148283Y+096677X0177Y    R180 S1      
317m6188            VIA   -    MD0100PA01X+168290Y+092750X0190Y         S0      
327m6188            J18   -196        A01X+168290Y+092750X0205Y0590R090 S1      
317m6189            VIA   -    MD0080PA01X+148096Y+096572X0160Y    R180 S0      
327m6189            U25   -AK21       A01X+147913Y+096677X0177Y    R180 S1      
317m6189            VIA   -    MD0100PA01X+169904Y+093085X0190Y         S0      
327m6189            J18   -53         A01X+169904Y+093085X0205Y0590R090 S1      
317m6190            VIA   -    MD0080PA01X+148652Y+096254X0160Y    R180 S0      
327m6190            U25   -AJ19       A01X+148468Y+096358X0177Y    R180 S1      
317m6190            VIA   -    MD0100PA01X+169904Y+092415X0190Y         S0      
327m6190            J18   -51         A01X+169904Y+092415X0205Y0590R090 S1      
317m6191            VIA   -    MD0080PA01X+148096Y+100399X0160Y    R180 S0      
327m6191            U25   -BB21       A01X+147913Y+100504X0177Y    R180 S1      
317m6191            VIA   -    MD0100PA01X+169904Y+099443X0190Y         S0      
327m6191            J18   -72         A01X+169904Y+099443X0205Y0590R090 S1      
317m6192            VIA   -    MD0080PA01X+148466Y+100399X0160Y    R180 S0      
327m6192            U25   -BB20       A01X+148283Y+100504X0177Y    R180 S1      
317m6192            VIA   -    MD0100PA01X+168290Y+099108X0190Y         S0      
327m6192            J18   -215        A01X+168290Y+099108X0205Y0590R090 S1      
317m6193            VIA   -    MD0080PA01X+148652Y+100080X0160Y    R180 S0      
327m6193            U25   -BA19       A01X+148468Y+100185X0177Y    R180 S1      
317m6193            VIA   -    MD0100PA01X+169904Y+098774X0190Y         S0      
327m6193            J18   -70         A01X+169904Y+098774X0205Y0590R090 S1      
317m6194            VIA   -    MD0080PA01X+147911Y+100080X0160Y    R180 S0      
327m6194            U25   -BA21       A01X+147728Y+100185X0177Y    R180 S1      
317m6194            VIA   -    MD0100PA01X+168290Y+098439X0190Y         S0      
327m6194            J18   -213        A01X+168290Y+098439X0205Y0590R090 S1      
317m6195            VIA   -    MD0080PA01X+148096Y+099762X0160Y    R180 S0      
327m6195            U25   -AY21       A01X+147913Y+099866X0177Y    R180 S1      
317m6195            VIA   -    MD0100PA01X+169904Y+098104X0190Y         S0      
327m6195            J18   -68         A01X+169904Y+098104X0205Y0590R090 S1      
317m6196            VIA   -    MD0080PA01X+148466Y+099762X0160Y    R180 S0      
327m6196            U25   -AY20       A01X+148283Y+099866X0177Y    R180 S1      
317m6196            VIA   -    MD0100PA01X+168290Y+097770X0190Y         S0      
327m6196            J18   -211        A01X+168290Y+097770X0205Y0590R090 S1      
317m6197            VIA   -    MD0080PA01X+148652Y+099443X0160Y    R180 S0      
327m6197            U25   -AW19       A01X+148468Y+099547X0177Y    R180 S1      
317m6197            VIA   -    MD0100PA01X+169904Y+097435X0190Y         S0      
327m6197            J18   -66         A01X+169904Y+097435X0205Y0590R090 S1      
317m6198            VIA   -    MD0080PA01X+147911Y+098805X0160Y    R180 S0      
327m6198            U25   -AU21       A01X+147728Y+098910X0177Y    R180 S1      
317m6198            VIA   -    MD0100PA01X+168290Y+096431X0190Y         S0      
327m6198            J18   -207        A01X+168290Y+096431X0205Y0590R090 S1      
317m6199            VIA   -    MD0080PA01X+148652Y+100718X0160Y    R180 S0      
327m6199            U25   -BC19       A01X+148468Y+100823X0177Y    R180 S1      
317m6199            VIA   -    MD0100PA01X+168290Y+099778X0190Y         S0      
327m6199            J18   -217        A01X+168290Y+099778X0205Y0590R090 S1      
317m6200            VIA   -    MD0080PA01X+148466Y+101037X0160Y    R180 S0      
327m6200            U25   -BD20       A01X+148283Y+101142X0177Y    R180 S1      
317m6200            VIA   -    MD0100PA01X+168290Y+100112X0190Y         S0      
327m6200            J18   -218        A01X+168290Y+100112X0205Y0590R090 S1      
317m6201            VIA   -    MD0080PA01X+148096Y+098486X0160Y    R180 S0      
327m6201            U25   -AT21       A01X+147913Y+098591X0177Y    R180 S1      
317m6201            VIA   -    MD0100PA18X+169354Y+096096X0190Y         S0      
327m6201            R383  -2          A18X+169354Y+096096X0198Y0197     S2      
327m6202            J18   -62         A01X+169904Y+096096X0205Y0590R090 S1      
317m6202            VIA   -    MD0100PA00X+169904Y+096096X0190Y         S0      
327m6202            R383  -1          A18X+169669Y+096096X0198Y0197     S2      
317m6203            VIA   -    MD0080PA01X+053561Y+105357X0160Y         S0      
327m6203            U26   -BP13       A01X+053377Y+105252X0177Y    R180 S1      
317m6203            VIA   -    MD0100PA01X+069320Y+106471X0190Y         S0      
327m6203            J27   -87         A01X+069320Y+106471X0205Y0590R090 S1      
317m6204            VIA   -    MD0080PA01X+053006Y+104400X0160Y         S0      
327m6204            U26   -BL14       A01X+052822Y+104295X0177Y    R180 S1      
317m6204            VIA   -    MD0100PA01X+067706Y+105132X0190Y         S0      
327m6204            J27   -227        A01X+067706Y+105132X0205Y0590R090 S1      
317m6205            VIA   -    MD0080PA01X+053561Y+106632X0160Y         S0      
327m6205            U26   -BV13       A01X+053377Y+106528X0177Y    R180 S1      
317m6205            VIA   -    MD0100PA01X+069320Y+108478X0190Y         S0      
327m6205            J27   -93         A01X+069320Y+108478X0205Y0590R090 S1      
317m6206            VIA   -    MD0080PA01X+053191Y+114924X0160Y         S0      
327m6206            U26   -DD14       A01X+053007Y+114819X0177Y    R180 S1      
317m6206            VIA   -    MD0100PA01X+067706Y+123872X0190Y         S0      
327m6206            J27   -283        A01X+067706Y+123872X0205Y0590R090 S1      
317m6207            VIA   -    MD0080PA01X+053191Y+113010X0160Y         S0      
327m6207            U26   -CV14       A01X+053007Y+112906X0177Y    R180 S1      
317m6207            VIA   -    MD0100PA01X+067706Y+120191X0190Y         S0      
327m6207            J27   -272        A01X+067706Y+120191X0205Y0590R090 S1      
317m6208            VIA   -    MD0080PA01X+053191Y+111097X0160Y         S0      
327m6208            U26   -CM14       A01X+053007Y+110992X0177Y    R180 S1      
317m6208            VIA   -    MD0100PA01X+067706Y+116510X0190Y         S0      
327m6208            J27   -261        A01X+067706Y+116510X0205Y0590R090 S1      
317m6209            VIA   -    MD0080PA01X+053191Y+109184X0160Y         S0      
327m6209            U26   -CF14       A01X+053007Y+109079X0177Y    R180 S1      
317m6209            VIA   -    MD0100PA01X+067706Y+112829X0190Y         S0      
327m6209            J27   -250        A01X+067706Y+112829X0205Y0590R090 S1      
317m6210            VIA   -    MD0080PA01X+053191Y+107270X0160Y         S0      
327m6210            U26   -BY14       A01X+053007Y+107166X0177Y    R180 S1      
317m6210            VIA   -    MD0100PA01X+067706Y+109148X0190Y         S0      
327m6210            J27   -239        A01X+067706Y+109148X0205Y0590R090 S1      
317m6211            VIA   -    MD0080PA01X+053561Y+114286X0160Y         S0      
327m6211            U26   -DB13       A01X+053377Y+114181X0177Y    R180 S1      
317m6211            VIA   -    MD0100PA01X+069320Y+123203X0190Y         S0      
327m6211            J27   -137        A01X+069320Y+123203X0205Y0590R090 S1      
317m6212            VIA   -    MD0080PA01X+053561Y+112373X0160Y         S0      
327m6212            U26   -CT13       A01X+053377Y+112268X0177Y    R180 S1      
317m6212            VIA   -    MD0100PA01X+069320Y+119522X0190Y         S0      
327m6212            J27   -126        A01X+069320Y+119522X0205Y0590R090 S1      
317m6213            VIA   -    MD0080PA01X+053561Y+110459X0160Y         S0      
327m6213            U26   -CK13       A01X+053377Y+110354X0177Y    R180 S1      
317m6213            VIA   -    MD0100PA01X+069320Y+115841X0190Y         S0      
327m6213            J27   -115        A01X+069320Y+115841X0205Y0590R090 S1      
317m6214            VIA   -    MD0080PA01X+053561Y+108546X0160Y         S0      
327m6214            U26   -CD13       A01X+053377Y+108441X0177Y    R180 S1      
317m6214            VIA   -    MD0100PA01X+069320Y+112160X0190Y         S0      
327m6214            J27   -104        A01X+069320Y+112160X0205Y0590R090 S1      
317m6215            VIA   -    MD0080PA01X+053746Y+106951X0160Y         S0      
327m6215            U26   -BW12       A01X+053562Y+106847X0177Y    R180 S1      
317m6215            VIA   -    MD0100PA01X+069320Y+108813X0190Y         S0      
327m6215            J27   -94         A01X+069320Y+108813X0205Y0590R090 S1      
317m6216            VIA   -    MD0080PA01X+053006Y+114605X0160Y         S0      
327m6216            U26   -DC14       A01X+052822Y+114500X0177Y    R180 S1      
317m6216            VIA   -    MD0100PA01X+067706Y+123538X0190Y         S0      
327m6216            J27   -282        A01X+067706Y+123538X0205Y0590R090 S1      
317m6217            VIA   -    MD0080PA01X+053006Y+112692X0160Y         S0      
327m6217            U26   -CU14       A01X+052822Y+112587X0177Y    R180 S1      
317m6217            VIA   -    MD0100PA01X+067706Y+119856X0190Y         S0      
327m6217            J27   -271        A01X+067706Y+119856X0205Y0590R090 S1      
317m6218            VIA   -    MD0080PA01X+053006Y+110778X0160Y         S0      
327m6218            U26   -CL14       A01X+052822Y+110673X0177Y    R180 S1      
317m6218            VIA   -    MD0100PA01X+067706Y+116175X0190Y         S0      
327m6218            J27   -260        A01X+067706Y+116175X0205Y0590R090 S1      
317m6219            VIA   -    MD0080PA01X+053006Y+108865X0160Y         S0      
327m6219            U26   -CE14       A01X+052822Y+108760X0177Y    R180 S1      
317m6219            VIA   -    MD0100PA01X+067706Y+112494X0190Y         S0      
327m6219            J27   -249        A01X+067706Y+112494X0205Y0590R090 S1      
317m6220            VIA   -    MD0080PA01X+053006Y+106951X0160Y         S0      
327m6220            U26   -BW14       A01X+052822Y+106847X0177Y    R180 S1      
317m6220            VIA   -    MD0100PA01X+067706Y+108813X0190Y         S0      
327m6220            J27   -238        A01X+067706Y+108813X0205Y0590R090 S1      
317m6221            VIA   -    MD0080PA01X+053746Y+114605X0160Y         S0      
327m6221            U26   -DC12       A01X+053562Y+114500X0177Y    R180 S1      
317m6221            VIA   -    MD0100PA01X+069320Y+123538X0190Y         S0      
327m6221            J27   -138        A01X+069320Y+123538X0205Y0590R090 S1      
317m6222            VIA   -    MD0080PA01X+053746Y+112692X0160Y         S0      
327m6222            U26   -CU12       A01X+053562Y+112587X0177Y    R180 S1      
317m6222            VIA   -    MD0100PA01X+069320Y+119856X0190Y         S0      
327m6222            J27   -127        A01X+069320Y+119856X0205Y0590R090 S1      
317m6223            VIA   -    MD0080PA01X+053746Y+110778X0160Y         S0      
327m6223            U26   -CL12       A01X+053562Y+110673X0177Y    R180 S1      
317m6223            VIA   -    MD0100PA01X+069320Y+116175X0190Y         S0      
327m6223            J27   -116        A01X+069320Y+116175X0205Y0590R090 S1      
317m6224            VIA   -    MD0080PA01X+053746Y+108865X0160Y         S0      
327m6224            U26   -CE12       A01X+053562Y+108760X0177Y    R180 S1      
317m6224            VIA   -    MD0100PA01X+069320Y+112494X0190Y         S0      
327m6224            J27   -105        A01X+069320Y+112494X0205Y0590R090 S1      
317m6225            VIA   -    MD0080PA01X+053006Y+110140X0160Y         S0      
327m6225            U26   -CJ14       A01X+052822Y+110036X0177Y    R180 S1      
317m6225            VIA   -    MD0100PA01X+069320Y+115171X0190Y         S0      
327m6225            J27   -113        A01X+069320Y+115171X0205Y0590R090 S1      
317m6226            VIA   -    MD0080PA01X+053561Y+109821X0160Y         S0      
327m6226            U26   -CH13       A01X+053377Y+109717X0177Y    R180 S1      
317m6226            VIA   -    MD0100PA01X+069320Y+114502X0190Y         S0      
327m6226            J27   -111        A01X+069320Y+114502X0205Y0590R090 S1      
317m6227            VIA   -    MD0080PA01X+053191Y+109821X0160Y         S0      
327m6227            U26   -CH14       A01X+053007Y+109717X0177Y    R180 S1      
317m6227            VIA   -    MD0100PA01X+067706Y+114168X0190Y         S0      
327m6227            J27   -254        A01X+067706Y+114168X0205Y0590R090 S1      
317m6228            VIA   -    MD0080PA01X+053746Y+109502X0160Y         S0      
327m6228            U26   -CG12       A01X+053562Y+109398X0177Y    R180 S1      
317m6228            VIA   -    MD0100PA01X+067706Y+113498X0190Y         S0      
327m6228            J27   -252        A01X+067706Y+113498X0205Y0590R090 S1      
317m6229            VIA   -    MD0080PA01X+053006Y+109502X0160Y         S0      
327m6229            U26   -CG14       A01X+052822Y+109398X0177Y    R180 S1      
317m6229            VIA   -    MD0100PA01X+069320Y+113833X0190Y         S0      
327m6229            J27   -109        A01X+069320Y+113833X0205Y0590R090 S1      
317m6230            VIA   -    MD0080PA01X+053561Y+109184X0160Y         S0      
327m6230            U26   -CF13       A01X+053377Y+109079X0177Y    R180 S1      
317m6230            VIA   -    MD0100PA01X+069320Y+113164X0190Y         S0      
327m6230            J27   -107        A01X+069320Y+113164X0205Y0590R090 S1      
317m6231            VIA   -    MD0080PA01X+053191Y+108546X0160Y         S0      
327m6231            U26   -CD14       A01X+053007Y+108441X0177Y    R180 S1      
317m6231            VIA   -    MD0100PA01X+067706Y+111825X0190Y         S0      
327m6231            J27   -247        A01X+067706Y+111825X0205Y0590R090 S1      
317m6232            VIA   -    MD0080PA01X+053191Y+115562X0160Y         S0      
327m6232            U26   -DF14       A01X+053007Y+115457X0177Y    R180 S1      
317m6232            VIA   -    MD0100PA01X+067706Y+125211X0190Y         S0      
327m6232            J27   -287        A01X+067706Y+125211X0205Y0590R090 S1      
317m6233            VIA   -    MD0080PA01X+053746Y+115243X0160Y         S0      
327m6233            U26   -DE12       A01X+053562Y+115138X0177Y    R180 S1      
317m6233            VIA   -    MD0100PA01X+067706Y+124542X0190Y         S0      
327m6233            J27   -285        A01X+067706Y+124542X0205Y0590R090 S1      
317m6234            VIA   -    MD0080PA01X+053746Y+108227X0160Y         S0      
327m6234            U26   -CC12       A01X+053562Y+108122X0177Y    R180 S1      
317m6234            VIA   -    MD0100PA01X+067706Y+111156X0190Y         S0      
327m6234            J27   -245        A01X+067706Y+111156X0205Y0590R090 S1      
317m6235            VIA   -    MD0080PA01X+053006Y+115243X0160Y         S0      
327m6235            U26   -DE14       A01X+052822Y+115138X0177Y    R180 S1      
317m6235            VIA   -    MD0100PA01X+069320Y+124876X0190Y         S0      
327m6235            J27   -142        A01X+069320Y+124876X0205Y0590R090 S1      
317m6236            VIA   -    MD0080PA01X+053561Y+114924X0160Y         S0      
327m6236            U26   -DD13       A01X+053377Y+114819X0177Y    R180 S1      
317m6236            VIA   -    MD0100PA01X+069320Y+124207X0190Y         S0      
327m6236            J27   -140        A01X+069320Y+124207X0205Y0590R090 S1      
317m6237            VIA   -    MD0080PA01X+053191Y+114286X0160Y         S0      
327m6237            U26   -DB14       A01X+053007Y+114181X0177Y    R180 S1      
317m6237            VIA   -    MD0100PA01X+067706Y+122868X0190Y         S0      
327m6237            J27   -280        A01X+067706Y+122868X0205Y0590R090 S1      
317m6238            VIA   -    MD0080PA01X+053746Y+113967X0160Y         S0      
327m6238            U26   -DA12       A01X+053562Y+113862X0177Y    R180 S1      
317m6238            VIA   -    MD0100PA01X+067706Y+122199X0190Y         S0      
327m6238            J27   -278        A01X+067706Y+122199X0205Y0590R090 S1      
317m6239            VIA   -    MD0080PA01X+053006Y+113967X0160Y         S0      
327m6239            U26   -DA14       A01X+052822Y+113862X0177Y    R180 S1      
317m6239            VIA   -    MD0100PA01X+069320Y+122534X0190Y         S0      
327m6239            J27   -135        A01X+069320Y+122534X0205Y0590R090 S1      
317m6240            VIA   -    MD0080PA01X+053561Y+113648X0160Y         S0      
327m6240            U26   -CY13       A01X+053377Y+113543X0177Y    R180 S1      
317m6240            VIA   -    MD0100PA01X+069320Y+121864X0190Y         S0      
327m6240            J27   -133        A01X+069320Y+121864X0205Y0590R090 S1      
317m6241            VIA   -    MD0080PA01X+053191Y+113648X0160Y         S0      
327m6241            U26   -CY14       A01X+053007Y+113543X0177Y    R180 S1      
317m6241            VIA   -    MD0100PA01X+067706Y+121530X0190Y         S0      
327m6241            J27   -276        A01X+067706Y+121530X0205Y0590R090 S1      
317m6242            VIA   -    MD0080PA01X+053746Y+113329X0160Y         S0      
327m6242            U26   -CW12       A01X+053562Y+113225X0177Y    R180 S1      
317m6242            VIA   -    MD0100PA01X+067706Y+120860X0190Y         S0      
327m6242            J27   -274        A01X+067706Y+120860X0205Y0590R090 S1      
317m6243            VIA   -    MD0080PA01X+053006Y+113329X0160Y         S0      
327m6243            U26   -CW14       A01X+052822Y+113225X0177Y    R180 S1      
317m6243            VIA   -    MD0100PA01X+069320Y+121195X0190Y         S0      
327m6243            J27   -131        A01X+069320Y+121195X0205Y0590R090 S1      
317m6244            VIA   -    MD0080PA01X+053561Y+113010X0160Y         S0      
327m6244            U26   -CV13       A01X+053377Y+112906X0177Y    R180 S1      
317m6244            VIA   -    MD0100PA01X+069320Y+120526X0190Y         S0      
327m6244            J27   -129        A01X+069320Y+120526X0205Y0590R090 S1      
317m6245            VIA   -    MD0080PA01X+053006Y+108227X0160Y         S0      
327m6245            U26   -CC14       A01X+052822Y+108122X0177Y    R180 S1      
317m6245            VIA   -    MD0100PA01X+069320Y+111490X0190Y         S0      
327m6245            J27   -102        A01X+069320Y+111490X0205Y0590R090 S1      
317m6246            VIA   -    MD0080PA01X+053191Y+112373X0160Y         S0      
327m6246            U26   -CT14       A01X+053007Y+112268X0177Y    R180 S1      
317m6246            VIA   -    MD0100PA01X+067706Y+119187X0190Y         S0      
327m6246            J27   -269        A01X+067706Y+119187X0205Y0590R090 S1      
317m6247            VIA   -    MD0080PA01X+053746Y+112054X0160Y         S0      
327m6247            U26   -CR12       A01X+053562Y+111949X0177Y    R180 S1      
317m6247            VIA   -    MD0100PA01X+067706Y+118518X0190Y         S0      
327m6247            J27   -267        A01X+067706Y+118518X0205Y0590R090 S1      
317m6248            VIA   -    MD0080PA01X+053006Y+112054X0160Y         S0      
327m6248            U26   -CR14       A01X+052822Y+111949X0177Y    R180 S1      
317m6248            VIA   -    MD0100PA01X+069320Y+118852X0190Y         S0      
327m6248            J27   -124        A01X+069320Y+118852X0205Y0590R090 S1      
317m6249            VIA   -    MD0080PA01X+053561Y+111735X0160Y         S0      
327m6249            U26   -CP13       A01X+053377Y+111630X0177Y    R180 S1      
317m6249            VIA   -    MD0100PA01X+069320Y+118183X0190Y         S0      
327m6249            J27   -122        A01X+069320Y+118183X0205Y0590R090 S1      
317m6250            VIA   -    MD0080PA01X+053191Y+111735X0160Y         S0      
327m6250            U26   -CP14       A01X+053007Y+111630X0177Y    R180 S1      
317m6250            VIA   -    MD0100PA01X+067706Y+117849X0190Y         S0      
327m6250            J27   -265        A01X+067706Y+117849X0205Y0590R090 S1      
317m6251            VIA   -    MD0080PA01X+053746Y+111416X0160Y         S0      
327m6251            U26   -CN12       A01X+053562Y+111311X0177Y    R180 S1      
317m6251            VIA   -    MD0100PA01X+067706Y+117179X0190Y         S0      
327m6251            J27   -263        A01X+067706Y+117179X0205Y0590R090 S1      
317m6252            VIA   -    MD0080PA01X+053006Y+111416X0160Y         S0      
327m6252            U26   -CN14       A01X+052822Y+111311X0177Y    R180 S1      
317m6252            VIA   -    MD0100PA01X+069320Y+117514X0190Y         S0      
327m6252            J27   -120        A01X+069320Y+117514X0205Y0590R090 S1      
317m6253            VIA   -    MD0080PA01X+053561Y+111097X0160Y         S0      
327m6253            U26   -CM13       A01X+053377Y+110992X0177Y    R180 S1      
317m6253            VIA   -    MD0100PA01X+069320Y+116845X0190Y         S0      
327m6253            J27   -118        A01X+069320Y+116845X0205Y0590R090 S1      
317m6254            VIA   -    MD0080PA01X+053191Y+110459X0160Y         S0      
327m6254            U26   -CK14       A01X+053007Y+110354X0177Y    R180 S1      
317m6254            VIA   -    MD0100PA01X+067706Y+115506X0190Y         S0      
327m6254            J27   -258        A01X+067706Y+115506X0205Y0590R090 S1      
317m6255            VIA   -    MD0080PA01X+053746Y+110140X0160Y         S0      
327m6255            U26   -CJ12       A01X+053562Y+110036X0177Y    R180 S1      
317m6255            VIA   -    MD0100PA01X+067706Y+114837X0190Y         S0      
327m6255            J27   -256        A01X+067706Y+114837X0205Y0590R090 S1      
317m6256            VIA   -    MD0080PA01X+053561Y+107908X0160Y         S0      
327m6256            U26   -CB13       A01X+053377Y+107803X0177Y    R180 S1      
317m6256            VIA   -    MD0100PA01X+069320Y+110821X0190Y         S0      
327m6256            J27   -100        A01X+069320Y+110821X0205Y0590R090 S1      
317m6257            VIA   -    MD0080PA01X+053746Y+105038X0160Y         S0      
327m6257            U26   -BN12       A01X+053562Y+104933X0177Y    R180 S1      
317m6257            VIA   -    MD0100PA01X+067706Y+105801X0190Y         S0      
327m6257            J27   -229        A01X+067706Y+105801X0205Y0590R090 S1      
317m6258            VIA   -    MD0080PA01X+053191Y+104719X0160Y         S0      
327m6258            U26   -BM14       A01X+053007Y+104614X0177Y    R180 S1      
317m6258            VIA   -    MD0100PA01X+069320Y+105467X0190Y         S0      
327m6258            J27   -84         A01X+069320Y+105467X0205Y0590R090 S1      
317m6259            VIA   -    MD0080PA01X+053191Y+106632X0160Y         S0      
327m6259            U26   -BV14       A01X+053007Y+106528X0177Y    R180 S1      
317m6259            VIA   -    MD0100PA01X+067706Y+108144X0190Y         S0      
327m6259            J27   -236        A01X+067706Y+108144X0205Y0590R090 S1      
317m6260            VIA   -    MD0080PA01X+053746Y+106314X0160Y         S0      
327m6260            U26   -BU12       A01X+053562Y+106209X0177Y    R180 S1      
317m6260            VIA   -    MD0100PA01X+067706Y+107474X0190Y         S0      
327m6260            J27   -234        A01X+067706Y+107474X0205Y0590R090 S1      
317m6261            VIA   -    MD0080PA01X+053006Y+106314X0160Y         S0      
327m6261            U26   -BU14       A01X+052822Y+106209X0177Y    R180 S1      
317m6261            VIA   -    MD0100PA01X+069320Y+107809X0190Y         S0      
327m6261            J27   -91         A01X+069320Y+107809X0205Y0590R090 S1      
317m6262            VIA   -    MD0080PA01X+053561Y+105995X0160Y         S0      
327m6262            U26   -BT13       A01X+053377Y+105890X0177Y    R180 S1      
317m6262            VIA   -    MD0100PA01X+069320Y+107140X0190Y         S0      
327m6262            J27   -89         A01X+069320Y+107140X0205Y0590R090 S1      
317m6263            VIA   -    MD0080PA01X+053191Y+107908X0160Y         S0      
327m6263            U26   -CB14       A01X+053007Y+107803X0177Y    R180 S1      
317m6263            VIA   -    MD0100PA01X+067706Y+110486X0190Y         S0      
327m6263            J27   -243        A01X+067706Y+110486X0205Y0590R090 S1      
317m6264            VIA   -    MD0080PA01X+053746Y+107589X0160Y         S0      
327m6264            U26   -CA12       A01X+053562Y+107484X0177Y    R180 S1      
317m6264            VIA   -    MD0100PA01X+067706Y+109817X0190Y         S0      
327m6264            J27   -241        A01X+067706Y+109817X0205Y0590R090 S1      
317m6265            VIA   -    MD0080PA01X+053006Y+107589X0160Y         S0      
327m6265            U26   -CA14       A01X+052822Y+107484X0177Y    R180 S1      
317m6265            VIA   -    MD0100PA01X+069320Y+110152X0190Y         S0      
327m6265            J27   -98         A01X+069320Y+110152X0205Y0590R090 S1      
317m6266            VIA   -    MD0080PA01X+053561Y+107270X0160Y         S0      
327m6266            U26   -BY13       A01X+053377Y+107166X0177Y    R180 S1      
317m6266            VIA   -    MD0100PA01X+069320Y+109482X0190Y         S0      
327m6266            J27   -96         A01X+069320Y+109482X0205Y0590R090 S1      
317m6267            VIA   -    MD0080PA01X+053561Y+104081X0160Y         S0      
327m6267            U26   -BK13       A01X+053377Y+103976X0177Y    R180 S1      
317m6267            VIA   -    MD0100PA01X+069320Y+104797X0190Y         S0      
327m6267            J27   -82         A01X+069320Y+104797X0205Y0590R090 S1      
317m6268            VIA   -    MD0080PA01X+053191Y+104081X0160Y         S0      
327m6268            U26   -BK14       A01X+053007Y+103976X0177Y    R180 S1      
317m6268            VIA   -    MD0100PA01X+067706Y+104463X0190Y         S0      
327m6268            J27   -225        A01X+067706Y+104463X0205Y0590R090 S1      
317m6269            VIA   -    MD0080PA01X+053006Y+103762X0160Y         S0      
327m6269            U26   -BJ14       A01X+052822Y+103658X0177Y    R180 S1      
317m6269            VIA   -    MD0100PA01X+069320Y+104128X0190Y         S0      
327m6269            J27   -80         A01X+069320Y+104128X0205Y0590R090 S1      
317m6270            VIA   -    MD0080PA01X+053746Y+103762X0160Y         S0      
327m6270            U26   -BJ12       A01X+053562Y+103658X0177Y    R180 S1      
317m6270            VIA   -    MD0100PA01X+067706Y+103793X0190Y         S0      
327m6270            J27   -223        A01X+067706Y+103793X0205Y0590R090 S1      
317m6271            VIA   -    MD0080PA01X+053561Y+103443X0160Y         S0      
327m6271            U26   -BH13       A01X+053377Y+103339X0177Y    R180 S1      
317m6271            VIA   -    MD0100PA01X+069320Y+103459X0190Y         S0      
327m6271            J27   -78         A01X+069320Y+103459X0205Y0590R090 S1      
317m6272            VIA   -    MD0080PA01X+053191Y+103443X0160Y         S0      
327m6272            U26   -BH14       A01X+053007Y+103339X0177Y    R180 S1      
317m6272            VIA   -    MD0100PA01X+067706Y+103124X0190Y         S0      
327m6272            J27   -221        A01X+067706Y+103124X0205Y0590R090 S1      
317m6273            VIA   -    MD0080PA01X+053006Y+103124X0160Y         S0      
327m6273            U26   -BG14       A01X+052822Y+103020X0177Y    R180 S1      
317m6273            VIA   -    MD0100PA01X+069320Y+102790X0190Y         S0      
327m6273            J27   -76         A01X+069320Y+102790X0205Y0590R090 S1      
317m6274            VIA   -    MD0080PA01X+053006Y+105038X0160Y         S0      
327m6274            U26   -BN14       A01X+052822Y+104933X0177Y    R180 S1      
317m6274            VIA   -    MD0100PA01X+069320Y+106136X0190Y         S0      
327m6274            J27   -86         A01X+069320Y+106136X0205Y0590R090 S1      
317m6275            VIA   -    MD0080PA01X+052888Y+100718X0160Y    R180 S0      
327m6275            U26   -BC14       A01X+052704Y+100823X0177Y    R180 S1      
317m6275            VIA   -    MD0100PA01X+069320Y+100112X0190Y         S0      
327m6275            J27   -74         A01X+069320Y+100112X0205Y0590R090 S1      
317m6276            VIA   -    MD0080PA01X+052888Y+097529X0160Y    R180 S0      
327m6276            U26   -AN14       A01X+052704Y+097634X0177Y    R180 S1      
317m6276            VIA   -    MD0100PA01X+067706Y+094423X0190Y         S0      
327m6276            J27   -201        A01X+067706Y+094423X0205Y0590R090 S1      
317m6277            VIA   -    MD0080PA01X+052888Y+095616X0160Y    R180 S0      
327m6277            U26   -AG14       A01X+052704Y+095721X0177Y    R180 S1      
317m6277            VIA   -    MD0100PA01X+067706Y+090742X0190Y         S0      
327m6277            J27   -190        A01X+067706Y+090742X0205Y0590R090 S1      
317m6278            VIA   -    MD0080PA01X+052888Y+093702X0160Y    R180 S0      
327m6278            U26   -AA14       A01X+052704Y+093807X0177Y    R180 S1      
317m6278            VIA   -    MD0100PA01X+067706Y+087061X0190Y         S0      
327m6278            J27   -179        A01X+067706Y+087061X0205Y0590R090 S1      
317m6279            VIA   -    MD0080PA01X+052888Y+091789X0160Y    R180 S0      
327m6279            U26   -R14        A01X+052704Y+091894X0177Y    R180 S1      
317m6279            VIA   -    MD0100PA01X+067706Y+083380X0190Y         S0      
327m6279            J27   -168        A01X+067706Y+083380X0205Y0590R090 S1      
317m6280            VIA   -    MD0080PA01X+052888Y+089876X0160Y    R180 S0      
327m6280            U26   -J14        A01X+052704Y+089980X0177Y    R180 S1      
317m6280            VIA   -    MD0100PA01X+067706Y+079699X0190Y         S0      
327m6280            J27   -157        A01X+067706Y+079699X0205Y0590R090 S1      
317m6281            VIA   -    MD0080PA01X+053628Y+096892X0160Y    R180 S0      
327m6281            U26   -AL12       A01X+053444Y+096996X0177Y    R180 S1      
317m6281            VIA   -    MD0100PA01X+069320Y+093754X0190Y         S0      
327m6281            J27   -55         A01X+069320Y+093754X0205Y0590R090 S1      
317m6282            VIA   -    MD0080PA01X+053628Y+094978X0160Y    R180 S0      
327m6282            U26   -AE12       A01X+053444Y+095083X0177Y    R180 S1      
317m6282            VIA   -    MD0100PA01X+069320Y+090073X0190Y         S0      
327m6282            J27   -44         A01X+069320Y+090073X0205Y0590R090 S1      
317m6283            VIA   -    MD0080PA01X+053628Y+093065X0160Y    R180 S0      
327m6283            U26   -W12        A01X+053444Y+093169X0177Y    R180 S1      
317m6283            VIA   -    MD0100PA01X+069320Y+086392X0190Y         S0      
327m6283            J27   -33         A01X+069320Y+086392X0205Y0590R090 S1      
317m6284            VIA   -    MD0080PA01X+053628Y+091151X0160Y    R180 S0      
327m6284            U26   -N12        A01X+053444Y+091256X0177Y    R180 S1      
317m6284            VIA   -    MD0100PA01X+069320Y+082711X0190Y         S0      
327m6284            J27   -22         A01X+069320Y+082711X0205Y0590R090 S1      
317m6285            VIA   -    MD0080PA01X+053628Y+089238X0160Y    R180 S0      
327m6285            U26   -G12        A01X+053444Y+089343X0177Y    R180 S1      
317m6285            VIA   -    MD0100PA01X+069320Y+079030X0190Y         S0      
327m6285            J27   -11         A01X+069320Y+079030X0205Y0590R090 S1      
317m6286            VIA   -    MD0080PA01X+053073Y+097210X0160Y    R180 S0      
327m6286            U26   -AM14       A01X+052889Y+097315X0177Y    R180 S1      
317m6286            VIA   -    MD0100PA01X+067706Y+094089X0190Y         S0      
327m6286            J27   -200        A01X+067706Y+094089X0205Y0590R090 S1      
317m6287            VIA   -    MD0080PA01X+053073Y+095297X0160Y    R180 S0      
327m6287            U26   -AF14       A01X+052889Y+095402X0177Y    R180 S1      
317m6287            VIA   -    MD0100PA01X+067706Y+090408X0190Y         S0      
327m6287            J27   -189        A01X+067706Y+090408X0205Y0590R090 S1      
317m6288            VIA   -    MD0080PA01X+053073Y+093384X0160Y    R180 S0      
327m6288            U26   -Y14        A01X+052889Y+093488X0177Y    R180 S1      
317m6288            VIA   -    MD0100PA01X+067706Y+086726X0190Y         S0      
327m6288            J27   -178        A01X+067706Y+086726X0205Y0590R090 S1      
317m6289            VIA   -    MD0080PA01X+053073Y+091470X0160Y    R180 S0      
327m6289            U26   -P14        A01X+052889Y+091575X0177Y    R180 S1      
317m6289            VIA   -    MD0100PA01X+067706Y+083045X0190Y         S0      
327m6289            J27   -167        A01X+067706Y+083045X0205Y0590R090 S1      
317m6290            VIA   -    MD0080PA01X+053073Y+089557X0160Y    R180 S0      
327m6290            U26   -H14        A01X+052889Y+089662X0177Y    R180 S1      
317m6290            VIA   -    MD0100PA01X+067706Y+079364X0190Y         S0      
327m6290            J27   -156        A01X+067706Y+079364X0205Y0590R090 S1      
317m6291            VIA   -    MD0080PA01X+053443Y+097210X0160Y    R180 S0      
327m6291            U26   -AM13       A01X+053259Y+097315X0177Y    R180 S1      
317m6291            VIA   -    MD0100PA01X+069320Y+094089X0190Y         S0      
327m6291            J27   -56         A01X+069320Y+094089X0205Y0590R090 S1      
317m6292            VIA   -    MD0080PA01X+053443Y+095297X0160Y    R180 S0      
327m6292            U26   -AF13       A01X+053259Y+095402X0177Y    R180 S1      
317m6292            VIA   -    MD0100PA01X+069320Y+090408X0190Y         S0      
327m6292            J27   -45         A01X+069320Y+090408X0205Y0590R090 S1      
317m6293            VIA   -    MD0080PA01X+053443Y+093384X0160Y    R180 S0      
327m6293            U26   -Y13        A01X+053259Y+093488X0177Y    R180 S1      
317m6293            VIA   -    MD0100PA01X+069320Y+086726X0190Y         S0      
327m6293            J27   -34         A01X+069320Y+086726X0205Y0590R090 S1      
317m6294            VIA   -    MD0080PA01X+053443Y+091470X0160Y    R180 S0      
327m6294            U26   -P13        A01X+053259Y+091575X0177Y    R180 S1      
317m6294            VIA   -    MD0100PA01X+069320Y+083045X0190Y         S0      
327m6294            J27   -23         A01X+069320Y+083045X0205Y0590R090 S1      
317m6295            VIA   -    MD0080PA01X+053443Y+089557X0160Y    R180 S0      
327m6295            U26   -H13        A01X+053259Y+089662X0177Y    R180 S1      
317m6295            VIA   -    MD0100PA01X+069320Y+079364X0190Y         S0      
327m6295            J27   -12         A01X+069320Y+079364X0205Y0590R090 S1      
317m6296            VIA   -    MD0080PA01X+053073Y+090832X0160Y    R180 S0      
327m6296            U26   -M14        A01X+052889Y+090937X0177Y    R180 S1      
317m6296            VIA   -    MD0100PA01X+069320Y+082042X0190Y         S0      
327m6296            J27   -20         A01X+069320Y+082042X0205Y0590R090 S1      
317m6297            VIA   -    MD0080PA01X+053628Y+090514X0160Y    R180 S0      
327m6297            U26   -L12        A01X+053444Y+090618X0177Y    R180 S1      
317m6297            VIA   -    MD0100PA01X+069320Y+081372X0190Y         S0      
327m6297            J27   -18         A01X+069320Y+081372X0205Y0590R090 S1      
317m6298            VIA   -    MD0080PA01X+052888Y+090514X0160Y    R180 S0      
327m6298            U26   -L14        A01X+052704Y+090618X0177Y    R180 S1      
317m6298            VIA   -    MD0100PA01X+067706Y+081038X0190Y         S0      
327m6298            J27   -161        A01X+067706Y+081038X0205Y0590R090 S1      
317m6299            VIA   -    MD0080PA01X+053443Y+090195X0160Y    R180 S0      
327m6299            U26   -K13        A01X+053259Y+090299X0177Y    R180 S1      
317m6299            VIA   -    MD0100PA01X+067706Y+080368X0190Y         S0      
327m6299            J27   -159        A01X+067706Y+080368X0205Y0590R090 S1      
317m6300            VIA   -    MD0080PA01X+053073Y+090195X0160Y    R180 S0      
327m6300            U26   -K14        A01X+052889Y+090299X0177Y    R180 S1      
317m6300            VIA   -    MD0100PA01X+069320Y+080703X0190Y         S0      
327m6300            J27   -16         A01X+069320Y+080703X0205Y0590R090 S1      
317m6301            VIA   -    MD0080PA01X+053628Y+089876X0160Y    R180 S0      
327m6301            U26   -J12        A01X+053444Y+089980X0177Y    R180 S1      
317m6301            VIA   -    MD0100PA01X+069320Y+080034X0190Y         S0      
327m6301            J27   -14         A01X+069320Y+080034X0205Y0590R090 S1      
317m6302            VIA   -    MD0080PA01X+052888Y+089238X0160Y    R180 S0      
327m6302            U26   -G14        A01X+052704Y+089343X0177Y    R180 S1      
317m6302            VIA   -    MD0100PA01X+067706Y+078695X0190Y         S0      
327m6302            J27   -154        A01X+067706Y+078695X0205Y0590R090 S1      
317m6303            VIA   -    MD0080PA01X+052888Y+096254X0160Y    R180 S0      
327m6303            U26   -AJ14       A01X+052704Y+096358X0177Y    R180 S1      
317m6303            VIA   -    MD0100PA01X+067706Y+092081X0190Y         S0      
327m6303            J27   -194        A01X+067706Y+092081X0205Y0590R090 S1      
317m6304            VIA   -    MD0080PA01X+053443Y+095935X0160Y    R180 S0      
327m6304            U26   -AH13       A01X+053259Y+096040X0177Y    R180 S1      
317m6304            VIA   -    MD0100PA01X+067706Y+091412X0190Y         S0      
327m6304            J27   -192        A01X+067706Y+091412X0205Y0590R090 S1      
317m6305            VIA   -    MD0080PA01X+053443Y+088919X0160Y    R180 S0      
327m6305            U26   -F13        A01X+053259Y+089024X0177Y    R180 S1      
317m6305            VIA   -    MD0100PA01X+067706Y+078026X0190Y         S0      
327m6305            J27   -152        A01X+067706Y+078026X0205Y0590R090 S1      
317m6306            VIA   -    MD0080PA01X+053073Y+095935X0160Y    R180 S0      
327m6306            U26   -AH14       A01X+052889Y+096040X0177Y    R180 S1      
317m6306            VIA   -    MD0100PA01X+069320Y+091746X0190Y         S0      
327m6306            J27   -49         A01X+069320Y+091746X0205Y0590R090 S1      
317m6307            VIA   -    MD0080PA01X+053628Y+095616X0160Y    R180 S0      
327m6307            U26   -AG12       A01X+053444Y+095721X0177Y    R180 S1      
317m6307            VIA   -    MD0100PA01X+069320Y+091077X0190Y         S0      
327m6307            J27   -47         A01X+069320Y+091077X0205Y0590R090 S1      
317m6308            VIA   -    MD0080PA01X+052888Y+094978X0160Y    R180 S0      
327m6308            U26   -AE14       A01X+052704Y+095083X0177Y    R180 S1      
317m6308            VIA   -    MD0100PA01X+067706Y+089738X0190Y         S0      
327m6308            J27   -187        A01X+067706Y+089738X0205Y0590R090 S1      
317m6309            VIA   -    MD0080PA01X+053443Y+094659X0160Y    R180 S0      
327m6309            U26   -AD13       A01X+053259Y+094764X0177Y    R180 S1      
317m6309            VIA   -    MD0100PA01X+067706Y+089069X0190Y         S0      
327m6309            J27   -185        A01X+067706Y+089069X0205Y0590R090 S1      
317m6310            VIA   -    MD0080PA01X+053073Y+094659X0160Y    R180 S0      
327m6310            U26   -AD14       A01X+052889Y+094764X0177Y    R180 S1      
317m6310            VIA   -    MD0100PA01X+069320Y+089404X0190Y         S0      
327m6310            J27   -42         A01X+069320Y+089404X0205Y0590R090 S1      
317m6311            VIA   -    MD0080PA01X+053628Y+094340X0160Y    R180 S0      
327m6311            U26   -AC12       A01X+053444Y+094445X0177Y    R180 S1      
317m6311            VIA   -    MD0100PA01X+069320Y+088734X0190Y         S0      
327m6311            J27   -40         A01X+069320Y+088734X0205Y0590R090 S1      
317m6312            VIA   -    MD0080PA01X+052888Y+094340X0160Y    R180 S0      
327m6312            U26   -AC14       A01X+052704Y+094445X0177Y    R180 S1      
317m6312            VIA   -    MD0100PA01X+067706Y+088400X0190Y         S0      
327m6312            J27   -183        A01X+067706Y+088400X0205Y0590R090 S1      
317m6313            VIA   -    MD0080PA01X+053443Y+094021X0160Y    R180 S0      
327m6313            U26   -AB13       A01X+053259Y+094126X0177Y    R180 S1      
317m6313            VIA   -    MD0100PA01X+067706Y+087730X0190Y         S0      
327m6313            J27   -181        A01X+067706Y+087730X0205Y0590R090 S1      
317m6314            VIA   -    MD0080PA01X+053073Y+094021X0160Y    R180 S0      
327m6314            U26   -AB14       A01X+052889Y+094126X0177Y    R180 S1      
317m6314            VIA   -    MD0100PA01X+069320Y+088065X0190Y         S0      
327m6314            J27   -38         A01X+069320Y+088065X0205Y0590R090 S1      
317m6315            VIA   -    MD0080PA01X+053628Y+093702X0160Y    R180 S0      
327m6315            U26   -AA12       A01X+053444Y+093807X0177Y    R180 S1      
317m6315            VIA   -    MD0100PA01X+069320Y+087396X0190Y         S0      
327m6315            J27   -36         A01X+069320Y+087396X0205Y0590R090 S1      
317m6316            VIA   -    MD0080PA01X+053073Y+088919X0160Y    R180 S0      
327m6316            U26   -F14        A01X+052889Y+089024X0177Y    R180 S1      
317m6316            VIA   -    MD0100PA01X+069320Y+078360X0190Y         S0      
327m6316            J27   -9          A01X+069320Y+078360X0205Y0590R090 S1      
317m6317            VIA   -    MD0080PA01X+052888Y+093065X0160Y    R180 S0      
327m6317            U26   -W14        A01X+052704Y+093169X0177Y    R180 S1      
317m6317            VIA   -    MD0100PA01X+067706Y+086057X0190Y         S0      
327m6317            J27   -176        A01X+067706Y+086057X0205Y0590R090 S1      
317m6318            VIA   -    MD0080PA01X+053443Y+092746X0160Y    R180 S0      
327m6318            U26   -V13        A01X+053259Y+092850X0177Y    R180 S1      
317m6318            VIA   -    MD0100PA01X+067706Y+085388X0190Y         S0      
327m6318            J27   -174        A01X+067706Y+085388X0205Y0590R090 S1      
317m6319            VIA   -    MD0080PA01X+053073Y+092746X0160Y    R180 S0      
327m6319            U26   -V14        A01X+052889Y+092850X0177Y    R180 S1      
317m6319            VIA   -    MD0100PA01X+069320Y+085723X0190Y         S0      
327m6319            J27   -31         A01X+069320Y+085723X0205Y0590R090 S1      
317m6320            VIA   -    MD0080PA01X+053628Y+092427X0160Y    R180 S0      
327m6320            U26   -U12        A01X+053444Y+092532X0177Y    R180 S1      
317m6320            VIA   -    MD0100PA01X+069320Y+085053X0190Y         S0      
327m6320            J27   -29         A01X+069320Y+085053X0205Y0590R090 S1      
317m6321            VIA   -    MD0080PA01X+052888Y+092427X0160Y    R180 S0      
327m6321            U26   -U14        A01X+052704Y+092532X0177Y    R180 S1      
317m6321            VIA   -    MD0100PA01X+067706Y+084719X0190Y         S0      
327m6321            J27   -172        A01X+067706Y+084719X0205Y0590R090 S1      
317m6322            VIA   -    MD0080PA01X+053443Y+092108X0160Y    R180 S0      
327m6322            U26   -T13        A01X+053259Y+092213X0177Y    R180 S1      
317m6322            VIA   -    MD0100PA01X+067706Y+084049X0190Y         S0      
327m6322            J27   -170        A01X+067706Y+084049X0205Y0590R090 S1      
317m6323            VIA   -    MD0080PA01X+053073Y+092108X0160Y    R180 S0      
327m6323            U26   -T14        A01X+052889Y+092213X0177Y    R180 S1      
317m6323            VIA   -    MD0100PA01X+069320Y+084384X0190Y         S0      
327m6323            J27   -27         A01X+069320Y+084384X0205Y0590R090 S1      
317m6324            VIA   -    MD0080PA01X+053628Y+091789X0160Y    R180 S0      
327m6324            U26   -R12        A01X+053444Y+091894X0177Y    R180 S1      
317m6324            VIA   -    MD0100PA01X+069320Y+083715X0190Y         S0      
327m6324            J27   -25         A01X+069320Y+083715X0205Y0590R090 S1      
317m6325            VIA   -    MD0080PA01X+052888Y+091151X0160Y    R180 S0      
327m6325            U26   -N14        A01X+052704Y+091256X0177Y    R180 S1      
317m6325            VIA   -    MD0100PA01X+067706Y+082376X0190Y         S0      
327m6325            J27   -165        A01X+067706Y+082376X0205Y0590R090 S1      
317m6326            VIA   -    MD0080PA01X+053443Y+090832X0160Y    R180 S0      
327m6326            U26   -M13        A01X+053259Y+090937X0177Y    R180 S1      
317m6326            VIA   -    MD0100PA01X+067706Y+081707X0190Y         S0      
327m6326            J27   -163        A01X+067706Y+081707X0205Y0590R090 S1      
317m6327            VIA   -    MD0080PA01X+053628Y+088600X0160Y    R180 S0      
327m6327            U26   -E12        A01X+053444Y+088705X0177Y    R180 S1      
317m6327            VIA   -    MD0100PA01X+069320Y+077691X0190Y         S0      
327m6327            J27   -7          A01X+069320Y+077691X0205Y0590R090 S1      
317m6328            VIA   -    MD0080PA01X+053073Y+099124X0160Y    R180 S0      
327m6328            U26   -AV14       A01X+052889Y+099228X0177Y    R180 S1      
317m6328            VIA   -    MD0100PA01X+067706Y+097100X0190Y         S0      
327m6328            J27   -209        A01X+067706Y+097100X0205Y0590R090 S1      
317m6329            VIA   -    MD0080PA01X+053628Y+098805X0160Y    R180 S0      
327m6329            U26   -AU12       A01X+053444Y+098910X0177Y    R180 S1      
317m6329            VIA   -    MD0100PA01X+069320Y+096766X0190Y         S0      
327m6329            J27   -64         A01X+069320Y+096766X0205Y0590R090 S1      
317m6330            VIA   -    MD0080PA01X+052888Y+098167X0160Y    R180 S0      
327m6330            U26   -AR14       A01X+052704Y+098272X0177Y    R180 S1      
317m6330            VIA   -    MD0100PA01X+067706Y+095762X0190Y         S0      
327m6330            J27   -205        A01X+067706Y+095762X0205Y0590R090 S1      
317m6331            VIA   -    MD0080PA01X+053443Y+097848X0160Y    R180 S0      
327m6331            U26   -AP13       A01X+053259Y+097953X0177Y    R180 S1      
317m6331            VIA   -    MD0100PA01X+067706Y+095093X0190Y         S0      
327m6331            J27   -203        A01X+067706Y+095093X0205Y0590R090 S1      
317m6332            VIA   -    MD0080PA01X+053073Y+097848X0160Y    R180 S0      
327m6332            U26   -AP14       A01X+052889Y+097953X0177Y    R180 S1      
317m6332            VIA   -    MD0100PA01X+069320Y+095427X0190Y         S0      
327m6332            J27   -60         A01X+069320Y+095427X0205Y0590R090 S1      
317m6333            VIA   -    MD0080PA01X+053628Y+097529X0160Y    R180 S0      
327m6333            U26   -AN12       A01X+053444Y+097634X0177Y    R180 S1      
317m6333            VIA   -    MD0100PA01X+069320Y+094758X0190Y         S0      
327m6333            J27   -58         A01X+069320Y+094758X0205Y0590R090 S1      
317m6334            VIA   -    MD0080PA01X+052888Y+096892X0160Y    R180 S0      
327m6334            U26   -AL14       A01X+052704Y+096996X0177Y    R180 S1      
317m6334            VIA   -    MD0100PA01X+067706Y+093419X0190Y         S0      
327m6334            J27   -198        A01X+067706Y+093419X0205Y0590R090 S1      
317m6335            VIA   -    MD0080PA01X+053443Y+096573X0160Y    R180 S0      
327m6335            U26   -AK13       A01X+053259Y+096677X0177Y    R180 S1      
317m6335            VIA   -    MD0100PA01X+067706Y+092750X0190Y         S0      
327m6335            J27   -196        A01X+067706Y+092750X0205Y0590R090 S1      
317m6336            VIA   -    MD0080PA01X+053073Y+096573X0160Y    R180 S0      
327m6336            U26   -AK14       A01X+052889Y+096677X0177Y    R180 S1      
317m6336            VIA   -    MD0100PA01X+069320Y+093085X0190Y         S0      
327m6336            J27   -53         A01X+069320Y+093085X0205Y0590R090 S1      
317m6337            VIA   -    MD0080PA01X+053628Y+096254X0160Y    R180 S0      
327m6337            U26   -AJ12       A01X+053444Y+096358X0177Y    R180 S1      
317m6337            VIA   -    MD0100PA01X+069320Y+092416X0190Y         S0      
327m6337            J27   -51         A01X+069320Y+092416X0205Y0590R090 S1      
317m6338            VIA   -    MD0080PA01X+053073Y+100399X0160Y    R180 S0      
327m6338            U26   -BB14       A01X+052889Y+100504X0177Y    R180 S1      
317m6338            VIA   -    MD0100PA01X+069320Y+099443X0190Y         S0      
327m6338            J27   -72         A01X+069320Y+099443X0205Y0590R090 S1      
317m6339            VIA   -    MD0080PA01X+053443Y+100399X0160Y    R180 S0      
327m6339            U26   -BB13       A01X+053259Y+100504X0177Y    R180 S1      
317m6339            VIA   -    MD0100PA01X+067706Y+099108X0190Y         S0      
327m6339            J27   -215        A01X+067706Y+099108X0205Y0590R090 S1      
317m6340            VIA   -    MD0080PA01X+053628Y+100080X0160Y    R180 S0      
327m6340            U26   -BA12       A01X+053444Y+100185X0177Y    R180 S1      
317m6340            VIA   -    MD0100PA01X+069320Y+098774X0190Y         S0      
327m6340            J27   -70         A01X+069320Y+098774X0205Y0590R090 S1      
317m6341            VIA   -    MD0080PA01X+052888Y+100080X0160Y    R180 S0      
327m6341            U26   -BA14       A01X+052704Y+100185X0177Y    R180 S1      
317m6341            VIA   -    MD0100PA01X+067706Y+098439X0190Y         S0      
327m6341            J27   -213        A01X+067706Y+098439X0205Y0590R090 S1      
317m6342            VIA   -    MD0080PA01X+053073Y+099762X0160Y    R180 S0      
327m6342            U26   -AY14       A01X+052889Y+099866X0177Y    R180 S1      
317m6342            VIA   -    MD0100PA01X+069320Y+098104X0190Y         S0      
327m6342            J27   -68         A01X+069320Y+098104X0205Y0590R090 S1      
317m6343            VIA   -    MD0080PA01X+053443Y+099762X0160Y    R180 S0      
327m6343            U26   -AY13       A01X+053259Y+099866X0177Y    R180 S1      
317m6343            VIA   -    MD0100PA01X+067706Y+097770X0190Y         S0      
327m6343            J27   -211        A01X+067706Y+097770X0205Y0590R090 S1      
317m6344            VIA   -    MD0080PA01X+053628Y+099443X0160Y    R180 S0      
327m6344            U26   -AW12       A01X+053444Y+099547X0177Y    R180 S1      
317m6344            VIA   -    MD0100PA01X+069320Y+097435X0190Y         S0      
327m6344            J27   -66         A01X+069320Y+097435X0205Y0590R090 S1      
317m6345            VIA   -    MD0080PA01X+052888Y+098805X0160Y    R180 S0      
327m6345            U26   -AU14       A01X+052704Y+098910X0177Y    R180 S1      
317m6345            VIA   -    MD0100PA01X+067706Y+096431X0190Y         S0      
327m6345            J27   -207        A01X+067706Y+096431X0205Y0590R090 S1      
317m6346            VIA   -    MD0080PA01X+053628Y+100718X0160Y    R180 S0      
327m6346            U26   -BC12       A01X+053444Y+100823X0177Y    R180 S1      
317m6346            VIA   -    MD0100PA01X+067706Y+099778X0190Y         S0      
327m6346            J27   -217        A01X+067706Y+099778X0205Y0590R090 S1      
317m6347            VIA   -    MD0080PA01X+053443Y+101037X0160Y    R180 S0      
327m6347            U26   -BD13       A01X+053259Y+101142X0177Y    R180 S1      
317m6347            VIA   -    MD0100PA01X+067706Y+100112X0190Y         S0      
327m6347            J27   -218        A01X+067706Y+100112X0205Y0590R090 S1      
317m6348            VIA   -    MD0080PA01X+053073Y+098486X0160Y    R180 S0      
327m6348            U26   -AT14       A01X+052889Y+098591X0177Y    R180 S1      
317m6348            VIA   -    MD0100PA18X+068770Y+096097X0190Y         S0      
327m6348            R507  -2          A18X+068770Y+096097X0198Y0197     S2      
327m6349            J27   -62         A01X+069320Y+096097X0205Y0590R090 S1      
317m6349            VIA   -    MD0100PA00X+069320Y+096097X0190Y         S0      
327m6349            R507  -1          A18X+069085Y+096097X0198Y0197     S2      
317m6350            VIA   -    MD0080PA01X+151175Y+105357X0160Y         S0      
327m6350            U25   -BP13       A01X+150991Y+105252X0177Y    R180 S1      
317m6350            VIA   -    MD0100PA01X+166934Y+106470X0190Y         S0      
327m6350            J69   -87         A01X+166934Y+106470X0205Y0590R090 S1      
317m6351            VIA   -    MD0080PA01X+150620Y+104400X0160Y         S0      
327m6351            U25   -BL14       A01X+150436Y+104295X0177Y    R180 S1      
317m6351            VIA   -    MD0100PA01X+165320Y+105132X0190Y         S0      
327m6351            J69   -227        A01X+165320Y+105132X0205Y0590R090 S1      
317m6352            VIA   -    MD0080PA01X+151175Y+106632X0160Y         S0      
327m6352            U25   -BV13       A01X+150991Y+106528X0177Y    R180 S1      
317m6352            VIA   -    MD0100PA01X+166934Y+108478X0190Y         S0      
327m6352            J69   -93         A01X+166934Y+108478X0205Y0590R090 S1      
317m6353            VIA   -    MD0080PA01X+150805Y+114924X0160Y         S0      
327m6353            U25   -DD14       A01X+150621Y+114819X0177Y    R180 S1      
317m6353            VIA   -    MD0100PA01X+165320Y+123872X0190Y         S0      
327m6353            J69   -283        A01X+165320Y+123872X0205Y0590R090 S1      
317m6354            VIA   -    MD0080PA01X+150805Y+113010X0160Y         S0      
327m6354            U25   -CV14       A01X+150621Y+112906X0177Y    R180 S1      
317m6354            VIA   -    MD0100PA01X+165320Y+120191X0190Y         S0      
327m6354            J69   -272        A01X+165320Y+120191X0205Y0590R090 S1      
317m6355            VIA   -    MD0080PA01X+150805Y+111097X0160Y         S0      
327m6355            U25   -CM14       A01X+150621Y+110992X0177Y    R180 S1      
317m6355            VIA   -    MD0100PA01X+165320Y+116510X0190Y         S0      
327m6355            J69   -261        A01X+165320Y+116510X0205Y0590R090 S1      
317m6356            VIA   -    MD0080PA01X+150805Y+109184X0160Y         S0      
327m6356            U25   -CF14       A01X+150621Y+109079X0177Y    R180 S1      
317m6356            VIA   -    MD0100PA01X+165320Y+112829X0190Y         S0      
327m6356            J69   -250        A01X+165320Y+112829X0205Y0590R090 S1      
317m6357            VIA   -    MD0080PA01X+150805Y+107270X0160Y         S0      
327m6357            U25   -BY14       A01X+150621Y+107165X0177Y    R180 S1      
317m6357            VIA   -    MD0100PA01X+165320Y+109148X0190Y         S0      
327m6357            J69   -239        A01X+165320Y+109148X0205Y0590R090 S1      
317m6358            VIA   -    MD0080PA01X+151175Y+114286X0160Y         S0      
327m6358            U25   -DB13       A01X+150991Y+114181X0177Y    R180 S1      
317m6358            VIA   -    MD0100PA01X+166934Y+123203X0190Y         S0      
327m6358            J69   -137        A01X+166934Y+123203X0205Y0590R090 S1      
317m6359            VIA   -    MD0080PA01X+151175Y+112372X0160Y         S0      
327m6359            U25   -CT13       A01X+150991Y+112268X0177Y    R180 S1      
317m6359            VIA   -    MD0100PA01X+166934Y+119522X0190Y         S0      
327m6359            J69   -126        A01X+166934Y+119522X0205Y0590R090 S1      
317m6360            VIA   -    MD0080PA01X+151175Y+110459X0160Y         S0      
327m6360            U25   -CK13       A01X+150991Y+110354X0177Y    R180 S1      
317m6360            VIA   -    MD0100PA01X+166934Y+115841X0190Y         S0      
327m6360            J69   -115        A01X+166934Y+115841X0205Y0590R090 S1      
317m6361            VIA   -    MD0080PA01X+151175Y+108546X0160Y         S0      
327m6361            U25   -CD13       A01X+150991Y+108441X0177Y    R180 S1      
317m6361            VIA   -    MD0100PA01X+166934Y+112160X0190Y         S0      
327m6361            J69   -104        A01X+166934Y+112160X0205Y0590R090 S1      
317m6362            VIA   -    MD0080PA01X+151360Y+106951X0160Y         S0      
327m6362            U25   -BW12       A01X+151176Y+106846X0177Y    R180 S1      
317m6362            VIA   -    MD0100PA01X+166934Y+108813X0190Y         S0      
327m6362            J69   -94         A01X+166934Y+108813X0205Y0590R090 S1      
317m6363            VIA   -    MD0080PA01X+150620Y+114605X0160Y         S0      
327m6363            U25   -DC14       A01X+150436Y+114500X0177Y    R180 S1      
317m6363            VIA   -    MD0100PA01X+165320Y+123537X0190Y         S0      
327m6363            J69   -282        A01X+165320Y+123537X0205Y0590R090 S1      
317m6364            VIA   -    MD0080PA01X+150620Y+112691X0160Y         S0      
327m6364            U25   -CU14       A01X+150436Y+112587X0177Y    R180 S1      
317m6364            VIA   -    MD0100PA01X+165320Y+119856X0190Y         S0      
327m6364            J69   -271        A01X+165320Y+119856X0205Y0590R090 S1      
317m6365            VIA   -    MD0080PA01X+150620Y+110778X0160Y         S0      
327m6365            U25   -CL14       A01X+150436Y+110673X0177Y    R180 S1      
317m6365            VIA   -    MD0100PA01X+165320Y+116175X0190Y         S0      
327m6365            J69   -260        A01X+165320Y+116175X0205Y0590R090 S1      
317m6366            VIA   -    MD0080PA01X+150620Y+108865X0160Y         S0      
327m6366            U25   -CE14       A01X+150436Y+108760X0177Y    R180 S1      
317m6366            VIA   -    MD0100PA01X+165320Y+112494X0190Y         S0      
327m6366            J69   -249        A01X+165320Y+112494X0205Y0590R090 S1      
317m6367            VIA   -    MD0080PA01X+150620Y+106951X0160Y         S0      
327m6367            U25   -BW14       A01X+150436Y+106846X0177Y    R180 S1      
317m6367            VIA   -    MD0100PA01X+165320Y+108813X0190Y         S0      
327m6367            J69   -238        A01X+165320Y+108813X0205Y0590R090 S1      
317m6368            VIA   -    MD0080PA01X+151360Y+114605X0160Y         S0      
327m6368            U25   -DC12       A01X+151176Y+114500X0177Y    R180 S1      
317m6368            VIA   -    MD0100PA01X+166934Y+123537X0190Y         S0      
327m6368            J69   -138        A01X+166934Y+123537X0205Y0590R090 S1      
317m6369            VIA   -    MD0080PA01X+151360Y+112691X0160Y         S0      
327m6369            U25   -CU12       A01X+151176Y+112587X0177Y    R180 S1      
317m6369            VIA   -    MD0100PA01X+166934Y+119856X0190Y         S0      
327m6369            J69   -127        A01X+166934Y+119856X0205Y0590R090 S1      
317m6370            VIA   -    MD0080PA01X+151360Y+110778X0160Y         S0      
327m6370            U25   -CL12       A01X+151176Y+110673X0177Y    R180 S1      
317m6370            VIA   -    MD0100PA01X+166934Y+116175X0190Y         S0      
327m6370            J69   -116        A01X+166934Y+116175X0205Y0590R090 S1      
317m6371            VIA   -    MD0080PA01X+151360Y+108865X0160Y         S0      
327m6371            U25   -CE12       A01X+151176Y+108760X0177Y    R180 S1      
317m6371            VIA   -    MD0100PA01X+166934Y+112494X0190Y         S0      
327m6371            J69   -105        A01X+166934Y+112494X0205Y0590R090 S1      
317m6372            VIA   -    MD0080PA01X+150620Y+110140X0160Y         S0      
327m6372            U25   -CJ14       A01X+150436Y+110036X0177Y    R180 S1      
317m6372            VIA   -    MD0100PA01X+166934Y+115171X0190Y         S0      
327m6372            J69   -113        A01X+166934Y+115171X0205Y0590R090 S1      
317m6373            VIA   -    MD0080PA01X+151175Y+109821X0160Y         S0      
327m6373            U25   -CH13       A01X+150991Y+109717X0177Y    R180 S1      
317m6373            VIA   -    MD0100PA01X+166934Y+114502X0190Y         S0      
327m6373            J69   -111        A01X+166934Y+114502X0205Y0590R090 S1      
317m6374            VIA   -    MD0080PA01X+150805Y+109821X0160Y         S0      
327m6374            U25   -CH14       A01X+150621Y+109717X0177Y    R180 S1      
317m6374            VIA   -    MD0100PA01X+165320Y+114167X0190Y         S0      
327m6374            J69   -254        A01X+165320Y+114167X0205Y0590R090 S1      
317m6375            VIA   -    MD0080PA01X+151360Y+109502X0160Y         S0      
327m6375            U25   -CG12       A01X+151176Y+109398X0177Y    R180 S1      
317m6375            VIA   -    MD0100PA01X+165320Y+113498X0190Y         S0      
327m6375            J69   -252        A01X+165320Y+113498X0205Y0590R090 S1      
317m6376            VIA   -    MD0080PA01X+150620Y+109502X0160Y         S0      
327m6376            U25   -CG14       A01X+150436Y+109398X0177Y    R180 S1      
317m6376            VIA   -    MD0100PA01X+166934Y+113833X0190Y         S0      
327m6376            J69   -109        A01X+166934Y+113833X0205Y0590R090 S1      
317m6377            VIA   -    MD0080PA01X+151175Y+109184X0160Y         S0      
327m6377            U25   -CF13       A01X+150991Y+109079X0177Y    R180 S1      
317m6377            VIA   -    MD0100PA01X+166934Y+113163X0190Y         S0      
327m6377            J69   -107        A01X+166934Y+113163X0205Y0590R090 S1      
317m6378            VIA   -    MD0080PA01X+150805Y+108546X0160Y         S0      
327m6378            U25   -CD14       A01X+150621Y+108441X0177Y    R180 S1      
317m6378            VIA   -    MD0100PA01X+165320Y+111825X0190Y         S0      
327m6378            J69   -247        A01X+165320Y+111825X0205Y0590R090 S1      
317m6379            VIA   -    MD0080PA01X+150805Y+115561X0160Y         S0      
327m6379            U25   -DF14       A01X+150621Y+115457X0177Y    R180 S1      
317m6379            VIA   -    MD0100PA01X+165320Y+125211X0190Y         S0      
327m6379            J69   -287        A01X+165320Y+125211X0205Y0590R090 S1      
317m6380            VIA   -    MD0080PA01X+151360Y+115242X0160Y         S0      
327m6380            U25   -DE12       A01X+151176Y+115138X0177Y    R180 S1      
317m6380            VIA   -    MD0100PA01X+165320Y+124541X0190Y         S0      
327m6380            J69   -285        A01X+165320Y+124541X0205Y0590R090 S1      
317m6381            VIA   -    MD0080PA01X+151360Y+108227X0160Y         S0      
327m6381            U25   -CC12       A01X+151176Y+108122X0177Y    R180 S1      
317m6381            VIA   -    MD0100PA01X+165320Y+111156X0190Y         S0      
327m6381            J69   -245        A01X+165320Y+111156X0205Y0590R090 S1      
317m6382            VIA   -    MD0080PA01X+150620Y+115242X0160Y         S0      
327m6382            U25   -DE14       A01X+150436Y+115138X0177Y    R180 S1      
317m6382            VIA   -    MD0100PA01X+166934Y+124876X0190Y         S0      
327m6382            J69   -142        A01X+166934Y+124876X0205Y0590R090 S1      
317m6383            VIA   -    MD0080PA01X+151175Y+114924X0160Y         S0      
327m6383            U25   -DD13       A01X+150991Y+114819X0177Y    R180 S1      
317m6383            VIA   -    MD0100PA01X+166934Y+124207X0190Y         S0      
327m6383            J69   -140        A01X+166934Y+124207X0205Y0590R090 S1      
317m6384            VIA   -    MD0080PA01X+150805Y+114286X0160Y         S0      
327m6384            U25   -DB14       A01X+150621Y+114181X0177Y    R180 S1      
317m6384            VIA   -    MD0100PA01X+165320Y+122868X0190Y         S0      
327m6384            J69   -280        A01X+165320Y+122868X0205Y0590R090 S1      
317m6385            VIA   -    MD0080PA01X+151360Y+113967X0160Y         S0      
327m6385            U25   -DA12       A01X+151176Y+113862X0177Y    R180 S1      
317m6385            VIA   -    MD0100PA01X+165320Y+122199X0190Y         S0      
327m6385            J69   -278        A01X+165320Y+122199X0205Y0590R090 S1      
317m6386            VIA   -    MD0080PA01X+150620Y+113967X0160Y         S0      
327m6386            U25   -DA14       A01X+150436Y+113862X0177Y    R180 S1      
317m6386            VIA   -    MD0100PA01X+166934Y+122534X0190Y         S0      
327m6386            J69   -135        A01X+166934Y+122534X0205Y0590R090 S1      
317m6387            VIA   -    MD0080PA01X+151175Y+113648X0160Y         S0      
327m6387            U25   -CY13       A01X+150991Y+113543X0177Y    R180 S1      
317m6387            VIA   -    MD0100PA01X+166934Y+121864X0190Y         S0      
327m6387            J69   -133        A01X+166934Y+121864X0205Y0590R090 S1      
317m6388            VIA   -    MD0080PA01X+150805Y+113648X0160Y         S0      
327m6388            U25   -CY14       A01X+150621Y+113543X0177Y    R180 S1      
317m6388            VIA   -    MD0100PA01X+165320Y+121530X0190Y         S0      
327m6388            J69   -276        A01X+165320Y+121530X0205Y0590R090 S1      
317m6389            VIA   -    MD0080PA01X+151360Y+113329X0160Y         S0      
327m6389            U25   -CW12       A01X+151176Y+113224X0177Y    R180 S1      
317m6389            VIA   -    MD0100PA01X+165320Y+120860X0190Y         S0      
327m6389            J69   -274        A01X+165320Y+120860X0205Y0590R090 S1      
317m6390            VIA   -    MD0080PA01X+150620Y+113329X0160Y         S0      
327m6390            U25   -CW14       A01X+150436Y+113224X0177Y    R180 S1      
317m6390            VIA   -    MD0100PA01X+166934Y+121195X0190Y         S0      
327m6390            J69   -131        A01X+166934Y+121195X0205Y0590R090 S1      
317m6391            VIA   -    MD0080PA01X+151175Y+113010X0160Y         S0      
327m6391            U25   -CV13       A01X+150991Y+112906X0177Y    R180 S1      
317m6391            VIA   -    MD0100PA01X+166934Y+120526X0190Y         S0      
327m6391            J69   -129        A01X+166934Y+120526X0205Y0590R090 S1      
317m6392            VIA   -    MD0080PA01X+150620Y+108227X0160Y         S0      
327m6392            U25   -CC14       A01X+150436Y+108122X0177Y    R180 S1      
317m6392            VIA   -    MD0100PA01X+166934Y+111490X0190Y         S0      
327m6392            J69   -102        A01X+166934Y+111490X0205Y0590R090 S1      
317m6393            VIA   -    MD0080PA01X+150805Y+112372X0160Y         S0      
327m6393            U25   -CT14       A01X+150621Y+112268X0177Y    R180 S1      
317m6393            VIA   -    MD0100PA01X+165320Y+119187X0190Y         S0      
327m6393            J69   -269        A01X+165320Y+119187X0205Y0590R090 S1      
317m6394            VIA   -    MD0080PA01X+151360Y+112054X0160Y         S0      
327m6394            U25   -CR12       A01X+151176Y+111949X0177Y    R180 S1      
317m6394            VIA   -    MD0100PA01X+165320Y+118518X0190Y         S0      
327m6394            J69   -267        A01X+165320Y+118518X0205Y0590R090 S1      
317m6395            VIA   -    MD0080PA01X+150620Y+112054X0160Y         S0      
327m6395            U25   -CR14       A01X+150436Y+111949X0177Y    R180 S1      
317m6395            VIA   -    MD0100PA01X+166934Y+118852X0190Y         S0      
327m6395            J69   -124        A01X+166934Y+118852X0205Y0590R090 S1      
317m6396            VIA   -    MD0080PA01X+151175Y+111735X0160Y         S0      
327m6396            U25   -CP13       A01X+150991Y+111630X0177Y    R180 S1      
317m6396            VIA   -    MD0100PA01X+166934Y+118183X0190Y         S0      
327m6396            J69   -122        A01X+166934Y+118183X0205Y0590R090 S1      
317m6397            VIA   -    MD0080PA01X+150805Y+111735X0160Y         S0      
327m6397            U25   -CP14       A01X+150621Y+111630X0177Y    R180 S1      
317m6397            VIA   -    MD0100PA01X+165320Y+117848X0190Y         S0      
327m6397            J69   -265        A01X+165320Y+117848X0205Y0590R090 S1      
317m6398            VIA   -    MD0080PA01X+151360Y+111416X0160Y         S0      
327m6398            U25   -CN12       A01X+151176Y+111311X0177Y    R180 S1      
317m6398            VIA   -    MD0100PA01X+165320Y+117179X0190Y         S0      
327m6398            J69   -263        A01X+165320Y+117179X0205Y0590R090 S1      
317m6399            VIA   -    MD0080PA01X+150620Y+111416X0160Y         S0      
327m6399            U25   -CN14       A01X+150436Y+111311X0177Y    R180 S1      
317m6399            VIA   -    MD0100PA01X+166934Y+117514X0190Y         S0      
327m6399            J69   -120        A01X+166934Y+117514X0205Y0590R090 S1      
317m6400            VIA   -    MD0080PA01X+151175Y+111097X0160Y         S0      
327m6400            U25   -CM13       A01X+150991Y+110992X0177Y    R180 S1      
317m6400            VIA   -    MD0100PA01X+166934Y+116844X0190Y         S0      
327m6400            J69   -118        A01X+166934Y+116844X0205Y0590R090 S1      
317m6401            VIA   -    MD0080PA01X+150805Y+110459X0160Y         S0      
327m6401            U25   -CK14       A01X+150621Y+110354X0177Y    R180 S1      
317m6401            VIA   -    MD0100PA01X+165320Y+115506X0190Y         S0      
327m6401            J69   -258        A01X+165320Y+115506X0205Y0590R090 S1      
317m6402            VIA   -    MD0080PA01X+151360Y+110140X0160Y         S0      
327m6402            U25   -CJ12       A01X+151176Y+110036X0177Y    R180 S1      
317m6402            VIA   -    MD0100PA01X+165320Y+114837X0190Y         S0      
327m6402            J69   -256        A01X+165320Y+114837X0205Y0590R090 S1      
317m6403            VIA   -    MD0080PA01X+151175Y+107908X0160Y         S0      
327m6403            U25   -CB13       A01X+150991Y+107803X0177Y    R180 S1      
317m6403            VIA   -    MD0100PA01X+166934Y+110821X0190Y         S0      
327m6403            J69   -100        A01X+166934Y+110821X0205Y0590R090 S1      
317m6404            VIA   -    MD0080PA01X+151360Y+105038X0160Y         S0      
327m6404            U25   -BN12       A01X+151176Y+104933X0177Y    R180 S1      
317m6404            VIA   -    MD0100PA01X+165320Y+105801X0190Y         S0      
327m6404            J69   -229        A01X+165320Y+105801X0205Y0590R090 S1      
317m6405            VIA   -    MD0080PA01X+150805Y+104719X0160Y         S0      
327m6405            U25   -BM14       A01X+150621Y+104614X0177Y    R180 S1      
317m6405            VIA   -    MD0100PA01X+166934Y+105467X0190Y         S0      
327m6405            J69   -84         A01X+166934Y+105467X0205Y0590R090 S1      
317m6406            VIA   -    MD0080PA01X+150805Y+106632X0160Y         S0      
327m6406            U25   -BV14       A01X+150621Y+106528X0177Y    R180 S1      
317m6406            VIA   -    MD0100PA01X+165320Y+108144X0190Y         S0      
327m6406            J69   -236        A01X+165320Y+108144X0205Y0590R090 S1      
317m6407            VIA   -    MD0080PA01X+151360Y+106313X0160Y         S0      
327m6407            U25   -BU12       A01X+151176Y+106209X0177Y    R180 S1      
317m6407            VIA   -    MD0100PA01X+165320Y+107474X0190Y         S0      
327m6407            J69   -234        A01X+165320Y+107474X0205Y0590R090 S1      
317m6408            VIA   -    MD0080PA01X+150620Y+106313X0160Y         S0      
327m6408            U25   -BU14       A01X+150436Y+106209X0177Y    R180 S1      
317m6408            VIA   -    MD0100PA01X+166934Y+107809X0190Y         S0      
327m6408            J69   -91         A01X+166934Y+107809X0205Y0590R090 S1      
317m6409            VIA   -    MD0080PA01X+151175Y+105994X0160Y         S0      
327m6409            U25   -BT13       A01X+150991Y+105890X0177Y    R180 S1      
317m6409            VIA   -    MD0100PA01X+166934Y+107140X0190Y         S0      
327m6409            J69   -89         A01X+166934Y+107140X0205Y0590R090 S1      
317m6410            VIA   -    MD0080PA01X+150805Y+107908X0160Y         S0      
327m6410            U25   -CB14       A01X+150621Y+107803X0177Y    R180 S1      
317m6410            VIA   -    MD0100PA01X+165320Y+110486X0190Y         S0      
327m6410            J69   -243        A01X+165320Y+110486X0205Y0590R090 S1      
317m6411            VIA   -    MD0080PA01X+151360Y+107589X0160Y         S0      
327m6411            U25   -CA12       A01X+151176Y+107484X0177Y    R180 S1      
317m6411            VIA   -    MD0100PA01X+165320Y+109817X0190Y         S0      
327m6411            J69   -241        A01X+165320Y+109817X0205Y0590R090 S1      
317m6412            VIA   -    MD0080PA01X+150620Y+107589X0160Y         S0      
327m6412            U25   -CA14       A01X+150436Y+107484X0177Y    R180 S1      
317m6412            VIA   -    MD0100PA01X+166934Y+110152X0190Y         S0      
327m6412            J69   -98         A01X+166934Y+110152X0205Y0590R090 S1      
317m6413            VIA   -    MD0080PA01X+151175Y+107270X0160Y         S0      
327m6413            U25   -BY13       A01X+150991Y+107165X0177Y    R180 S1      
317m6413            VIA   -    MD0100PA01X+166934Y+109482X0190Y         S0      
327m6413            J69   -96         A01X+166934Y+109482X0205Y0590R090 S1      
317m6414            VIA   -    MD0080PA01X+151175Y+104081X0160Y         S0      
327m6414            U25   -BK13       A01X+150991Y+103976X0177Y    R180 S1      
317m6414            VIA   -    MD0100PA01X+166934Y+104797X0190Y         S0      
327m6414            J69   -82         A01X+166934Y+104797X0205Y0590R090 S1      
317m6415            VIA   -    MD0080PA01X+150805Y+104081X0160Y         S0      
327m6415            U25   -BK14       A01X+150621Y+103976X0177Y    R180 S1      
317m6415            VIA   -    MD0100PA01X+165320Y+104463X0190Y         S0      
327m6415            J69   -225        A01X+165320Y+104463X0205Y0590R090 S1      
317m6416            VIA   -    MD0080PA01X+150620Y+103762X0160Y         S0      
327m6416            U25   -BJ14       A01X+150436Y+103658X0177Y    R180 S1      
317m6416            VIA   -    MD0100PA01X+166934Y+104128X0190Y         S0      
327m6416            J69   -80         A01X+166934Y+104128X0205Y0590R090 S1      
317m6417            VIA   -    MD0080PA01X+151360Y+103762X0160Y         S0      
327m6417            U25   -BJ12       A01X+151176Y+103658X0177Y    R180 S1      
317m6417            VIA   -    MD0100PA01X+165320Y+103793X0190Y         S0      
327m6417            J69   -223        A01X+165320Y+103793X0205Y0590R090 S1      
317m6418            VIA   -    MD0080PA01X+151175Y+103443X0160Y         S0      
327m6418            U25   -BH13       A01X+150991Y+103339X0177Y    R180 S1      
317m6418            VIA   -    MD0100PA01X+166934Y+103459X0190Y         S0      
327m6418            J69   -78         A01X+166934Y+103459X0205Y0590R090 S1      
317m6419            VIA   -    MD0080PA01X+150805Y+103443X0160Y         S0      
327m6419            U25   -BH14       A01X+150621Y+103339X0177Y    R180 S1      
317m6419            VIA   -    MD0100PA01X+165320Y+103124X0190Y         S0      
327m6419            J69   -221        A01X+165320Y+103124X0205Y0590R090 S1      
317m6420            VIA   -    MD0080PA01X+150620Y+103124X0160Y         S0      
327m6420            U25   -BG14       A01X+150436Y+103020X0177Y    R180 S1      
317m6420            VIA   -    MD0100PA01X+166934Y+102789X0190Y         S0      
327m6420            J69   -76         A01X+166934Y+102789X0205Y0590R090 S1      
317m6421            VIA   -    MD0080PA01X+150620Y+105038X0160Y         S0      
327m6421            U25   -BN14       A01X+150436Y+104933X0177Y    R180 S1      
317m6421            VIA   -    MD0100PA01X+166934Y+106136X0190Y         S0      
327m6421            J69   -86         A01X+166934Y+106136X0205Y0590R090 S1      
317m6422            VIA   -    MD0080PA01X+150502Y+100718X0160Y    R180 S0      
327m6422            U25   -BC14       A01X+150318Y+100823X0177Y    R180 S1      
317m6422            VIA   -    MD0100PA01X+166934Y+100112X0190Y         S0      
327m6422            J69   -74         A01X+166934Y+100112X0205Y0590R090 S1      
317m6423            VIA   -    MD0080PA01X+150502Y+097529X0160Y    R180 S0      
327m6423            U25   -AN14       A01X+150318Y+097634X0177Y    R180 S1      
317m6423            VIA   -    MD0100PA01X+165320Y+094423X0190Y         S0      
327m6423            J69   -201        A01X+165320Y+094423X0205Y0590R090 S1      
317m6424            VIA   -    MD0080PA01X+150502Y+095616X0160Y    R180 S0      
327m6424            U25   -AG14       A01X+150318Y+095720X0177Y    R180 S1      
317m6424            VIA   -    MD0100PA01X+165320Y+090742X0190Y         S0      
327m6424            J69   -190        A01X+165320Y+090742X0205Y0590R090 S1      
317m6425            VIA   -    MD0080PA01X+150502Y+093702X0160Y    R180 S0      
327m6425            U25   -AA14       A01X+150318Y+093807X0177Y    R180 S1      
317m6425            VIA   -    MD0100PA01X+165320Y+087061X0190Y         S0      
327m6425            J69   -179        A01X+165320Y+087061X0205Y0590R090 S1      
317m6426            VIA   -    MD0080PA01X+150502Y+091789X0160Y    R180 S0      
327m6426            U25   -R14        A01X+150318Y+091894X0177Y    R180 S1      
317m6426            VIA   -    MD0100PA01X+165320Y+083380X0190Y         S0      
327m6426            J69   -168        A01X+165320Y+083380X0205Y0590R090 S1      
317m6427            VIA   -    MD0080PA01X+150502Y+089876X0160Y    R180 S0      
327m6427            U25   -J14        A01X+150318Y+089980X0177Y    R180 S1      
317m6427            VIA   -    MD0100PA01X+165320Y+079699X0190Y         S0      
327m6427            J69   -157        A01X+165320Y+079699X0205Y0590R090 S1      
317m6428            VIA   -    MD0080PA01X+151242Y+096891X0160Y    R180 S0      
327m6428            U25   -AL12       A01X+151058Y+096996X0177Y    R180 S1      
317m6428            VIA   -    MD0100PA01X+166934Y+093754X0190Y         S0      
327m6428            J69   -55         A01X+166934Y+093754X0205Y0590R090 S1      
317m6429            VIA   -    MD0080PA01X+151242Y+094978X0160Y    R180 S0      
327m6429            U25   -AE12       A01X+151058Y+095083X0177Y    R180 S1      
317m6429            VIA   -    MD0100PA01X+166934Y+090073X0190Y         S0      
327m6429            J69   -44         A01X+166934Y+090073X0205Y0590R090 S1      
317m6430            VIA   -    MD0080PA01X+151242Y+093065X0160Y    R180 S0      
327m6430            U25   -W12        A01X+151058Y+093169X0177Y    R180 S1      
317m6430            VIA   -    MD0100PA01X+166934Y+086392X0190Y         S0      
327m6430            J69   -33         A01X+166934Y+086392X0205Y0590R090 S1      
317m6431            VIA   -    MD0080PA01X+151242Y+091151X0160Y    R180 S0      
327m6431            U25   -N12        A01X+151058Y+091256X0177Y    R180 S1      
317m6431            VIA   -    MD0100PA01X+166934Y+082711X0190Y         S0      
327m6431            J69   -22         A01X+166934Y+082711X0205Y0590R090 S1      
317m6432            VIA   -    MD0080PA01X+151242Y+089238X0160Y    R180 S0      
327m6432            U25   -G12        A01X+151058Y+089343X0177Y    R180 S1      
317m6432            VIA   -    MD0100PA01X+166934Y+079030X0190Y         S0      
327m6432            J69   -11         A01X+166934Y+079030X0205Y0590R090 S1      
317m6433            VIA   -    MD0080PA01X+150687Y+097210X0160Y    R180 S0      
327m6433            U25   -AM14       A01X+150503Y+097315X0177Y    R180 S1      
317m6433            VIA   -    MD0100PA01X+165320Y+094089X0190Y         S0      
327m6433            J69   -200        A01X+165320Y+094089X0205Y0590R090 S1      
317m6434            VIA   -    MD0080PA01X+150687Y+095297X0160Y    R180 S0      
327m6434            U25   -AF14       A01X+150503Y+095402X0177Y    R180 S1      
317m6434            VIA   -    MD0100PA01X+165320Y+090408X0190Y         S0      
327m6434            J69   -189        A01X+165320Y+090408X0205Y0590R090 S1      
317m6435            VIA   -    MD0080PA01X+150687Y+093384X0160Y    R180 S0      
327m6435            U25   -Y14        A01X+150503Y+093488X0177Y    R180 S1      
317m6435            VIA   -    MD0100PA01X+165320Y+086726X0190Y         S0      
327m6435            J69   -178        A01X+165320Y+086726X0205Y0590R090 S1      
317m6436            VIA   -    MD0080PA01X+150687Y+091470X0160Y    R180 S0      
327m6436            U25   -P14        A01X+150503Y+091575X0177Y    R180 S1      
317m6436            VIA   -    MD0100PA01X+165320Y+083045X0190Y         S0      
327m6436            J69   -167        A01X+165320Y+083045X0205Y0590R090 S1      
317m6437            VIA   -    MD0080PA01X+150687Y+089557X0160Y    R180 S0      
327m6437            U25   -H14        A01X+150503Y+089662X0177Y    R180 S1      
317m6437            VIA   -    MD0100PA01X+165320Y+079364X0190Y         S0      
327m6437            J69   -156        A01X+165320Y+079364X0205Y0590R090 S1      
317m6438            VIA   -    MD0080PA01X+151057Y+097210X0160Y    R180 S0      
327m6438            U25   -AM13       A01X+150873Y+097315X0177Y    R180 S1      
317m6438            VIA   -    MD0100PA01X+166934Y+094089X0190Y         S0      
327m6438            J69   -56         A01X+166934Y+094089X0205Y0590R090 S1      
317m6439            VIA   -    MD0080PA01X+151057Y+095297X0160Y    R180 S0      
327m6439            U25   -AF13       A01X+150873Y+095402X0177Y    R180 S1      
317m6439            VIA   -    MD0100PA01X+166934Y+090408X0190Y         S0      
327m6439            J69   -45         A01X+166934Y+090408X0205Y0590R090 S1      
317m6440            VIA   -    MD0080PA01X+151057Y+093384X0160Y    R180 S0      
327m6440            U25   -Y13        A01X+150873Y+093488X0177Y    R180 S1      
317m6440            VIA   -    MD0100PA01X+166934Y+086726X0190Y         S0      
327m6440            J69   -34         A01X+166934Y+086726X0205Y0590R090 S1      
317m6441            VIA   -    MD0080PA01X+151057Y+091470X0160Y    R180 S0      
327m6441            U25   -P13        A01X+150873Y+091575X0177Y    R180 S1      
317m6441            VIA   -    MD0100PA01X+166934Y+083045X0190Y         S0      
327m6441            J69   -23         A01X+166934Y+083045X0205Y0590R090 S1      
317m6442            VIA   -    MD0080PA01X+151057Y+089557X0160Y    R180 S0      
327m6442            U25   -H13        A01X+150873Y+089662X0177Y    R180 S1      
317m6442            VIA   -    MD0100PA01X+166934Y+079364X0190Y         S0      
327m6442            J69   -12         A01X+166934Y+079364X0205Y0590R090 S1      
317m6443            VIA   -    MD0080PA01X+150687Y+090832X0160Y    R180 S0      
327m6443            U25   -M14        A01X+150503Y+090937X0177Y    R180 S1      
317m6443            VIA   -    MD0100PA01X+166934Y+082041X0190Y         S0      
327m6443            J69   -20         A01X+166934Y+082041X0205Y0590R090 S1      
317m6444            VIA   -    MD0080PA01X+151242Y+090513X0160Y    R180 S0      
327m6444            U25   -L12        A01X+151058Y+090618X0177Y    R180 S1      
317m6444            VIA   -    MD0100PA01X+166934Y+081372X0190Y         S0      
327m6444            J69   -18         A01X+166934Y+081372X0205Y0590R090 S1      
317m6445            VIA   -    MD0080PA01X+150502Y+090513X0160Y    R180 S0      
327m6445            U25   -L14        A01X+150318Y+090618X0177Y    R180 S1      
317m6445            VIA   -    MD0100PA01X+165320Y+081037X0190Y         S0      
327m6445            J69   -161        A01X+165320Y+081037X0205Y0590R090 S1      
317m6446            VIA   -    MD0080PA01X+151057Y+090195X0160Y    R180 S0      
327m6446            U25   -K13        A01X+150873Y+090299X0177Y    R180 S1      
317m6446            VIA   -    MD0100PA01X+165320Y+080368X0190Y         S0      
327m6446            J69   -159        A01X+165320Y+080368X0205Y0590R090 S1      
317m6447            VIA   -    MD0080PA01X+150687Y+090195X0160Y    R180 S0      
327m6447            U25   -K14        A01X+150503Y+090299X0177Y    R180 S1      
317m6447            VIA   -    MD0100PA01X+166934Y+080703X0190Y         S0      
327m6447            J69   -16         A01X+166934Y+080703X0205Y0590R090 S1      
317m6448            VIA   -    MD0080PA01X+151242Y+089876X0160Y    R180 S0      
327m6448            U25   -J12        A01X+151058Y+089980X0177Y    R180 S1      
317m6448            VIA   -    MD0100PA01X+166934Y+080034X0190Y         S0      
327m6448            J69   -14         A01X+166934Y+080034X0205Y0590R090 S1      
317m6449            VIA   -    MD0080PA01X+150502Y+089238X0160Y    R180 S0      
327m6449            U25   -G14        A01X+150318Y+089343X0177Y    R180 S1      
317m6449            VIA   -    MD0100PA01X+165320Y+078695X0190Y         S0      
327m6449            J69   -154        A01X+165320Y+078695X0205Y0590R090 S1      
317m6450            VIA   -    MD0080PA01X+150502Y+096254X0160Y    R180 S0      
327m6450            U25   -AJ14       A01X+150318Y+096358X0177Y    R180 S1      
317m6450            VIA   -    MD0100PA01X+165320Y+092081X0190Y         S0      
327m6450            J69   -194        A01X+165320Y+092081X0205Y0590R090 S1      
317m6451            VIA   -    MD0080PA01X+151057Y+095935X0160Y    R180 S0      
327m6451            U25   -AH13       A01X+150873Y+096039X0177Y    R180 S1      
317m6451            VIA   -    MD0100PA01X+165320Y+091411X0190Y         S0      
327m6451            J69   -192        A01X+165320Y+091411X0205Y0590R090 S1      
317m6452            VIA   -    MD0080PA01X+151057Y+088919X0160Y    R180 S0      
327m6452            U25   -F13        A01X+150873Y+089024X0177Y    R180 S1      
317m6452            VIA   -    MD0100PA01X+165320Y+078026X0190Y         S0      
327m6452            J69   -152        A01X+165320Y+078026X0205Y0590R090 S1      
317m6453            VIA   -    MD0080PA01X+150687Y+095935X0160Y    R180 S0      
327m6453            U25   -AH14       A01X+150503Y+096039X0177Y    R180 S1      
317m6453            VIA   -    MD0100PA01X+166934Y+091746X0190Y         S0      
327m6453            J69   -49         A01X+166934Y+091746X0205Y0590R090 S1      
317m6454            VIA   -    MD0080PA01X+151242Y+095616X0160Y    R180 S0      
327m6454            U25   -AG12       A01X+151058Y+095720X0177Y    R180 S1      
317m6454            VIA   -    MD0100PA01X+166934Y+091077X0190Y         S0      
327m6454            J69   -47         A01X+166934Y+091077X0205Y0590R090 S1      
317m6455            VIA   -    MD0080PA01X+150502Y+094978X0160Y    R180 S0      
327m6455            U25   -AE14       A01X+150318Y+095083X0177Y    R180 S1      
317m6455            VIA   -    MD0100PA01X+165320Y+089738X0190Y         S0      
327m6455            J69   -187        A01X+165320Y+089738X0205Y0590R090 S1      
317m6456            VIA   -    MD0080PA01X+151057Y+094659X0160Y    R180 S0      
327m6456            U25   -AD13       A01X+150873Y+094764X0177Y    R180 S1      
317m6456            VIA   -    MD0100PA01X+165320Y+089069X0190Y         S0      
327m6456            J69   -185        A01X+165320Y+089069X0205Y0590R090 S1      
317m6457            VIA   -    MD0080PA01X+150687Y+094659X0160Y    R180 S0      
327m6457            U25   -AD14       A01X+150503Y+094764X0177Y    R180 S1      
317m6457            VIA   -    MD0100PA01X+166934Y+089404X0190Y         S0      
327m6457            J69   -42         A01X+166934Y+089404X0205Y0590R090 S1      
317m6458            VIA   -    MD0080PA01X+151242Y+094340X0160Y    R180 S0      
327m6458            U25   -AC12       A01X+151058Y+094445X0177Y    R180 S1      
317m6458            VIA   -    MD0100PA01X+166934Y+088734X0190Y         S0      
327m6458            J69   -40         A01X+166934Y+088734X0205Y0590R090 S1      
317m6459            VIA   -    MD0080PA01X+150502Y+094340X0160Y    R180 S0      
327m6459            U25   -AC14       A01X+150318Y+094445X0177Y    R180 S1      
317m6459            VIA   -    MD0100PA01X+165320Y+088400X0190Y         S0      
327m6459            J69   -183        A01X+165320Y+088400X0205Y0590R090 S1      
317m6460            VIA   -    MD0080PA01X+151057Y+094021X0160Y    R180 S0      
327m6460            U25   -AB13       A01X+150873Y+094126X0177Y    R180 S1      
317m6460            VIA   -    MD0100PA01X+165320Y+087730X0190Y         S0      
327m6460            J69   -181        A01X+165320Y+087730X0205Y0590R090 S1      
317m6461            VIA   -    MD0080PA01X+150687Y+094021X0160Y    R180 S0      
327m6461            U25   -AB14       A01X+150503Y+094126X0177Y    R180 S1      
317m6461            VIA   -    MD0100PA01X+166934Y+088065X0190Y         S0      
327m6461            J69   -38         A01X+166934Y+088065X0205Y0590R090 S1      
317m6462            VIA   -    MD0080PA01X+151242Y+093702X0160Y    R180 S0      
327m6462            U25   -AA12       A01X+151058Y+093807X0177Y    R180 S1      
317m6462            VIA   -    MD0100PA01X+166934Y+087396X0190Y         S0      
327m6462            J69   -36         A01X+166934Y+087396X0205Y0590R090 S1      
317m6463            VIA   -    MD0080PA01X+150687Y+088919X0160Y    R180 S0      
327m6463            U25   -F14        A01X+150503Y+089024X0177Y    R180 S1      
317m6463            VIA   -    MD0100PA01X+166934Y+078360X0190Y         S0      
327m6463            J69   -9          A01X+166934Y+078360X0205Y0590R090 S1      
317m6464            VIA   -    MD0080PA01X+150502Y+093065X0160Y    R180 S0      
327m6464            U25   -W14        A01X+150318Y+093169X0177Y    R180 S1      
317m6464            VIA   -    MD0100PA01X+165320Y+086057X0190Y         S0      
327m6464            J69   -176        A01X+165320Y+086057X0205Y0590R090 S1      
317m6465            VIA   -    MD0080PA01X+151057Y+092746X0160Y    R180 S0      
327m6465            U25   -V13        A01X+150873Y+092850X0177Y    R180 S1      
317m6465            VIA   -    MD0100PA01X+165320Y+085388X0190Y         S0      
327m6465            J69   -174        A01X+165320Y+085388X0205Y0590R090 S1      
317m6466            VIA   -    MD0080PA01X+150687Y+092746X0160Y    R180 S0      
327m6466            U25   -V14        A01X+150503Y+092850X0177Y    R180 S1      
317m6466            VIA   -    MD0100PA01X+166934Y+085722X0190Y         S0      
327m6466            J69   -31         A01X+166934Y+085722X0205Y0590R090 S1      
317m6467            VIA   -    MD0080PA01X+151242Y+092427X0160Y    R180 S0      
327m6467            U25   -U12        A01X+151058Y+092532X0177Y    R180 S1      
317m6467            VIA   -    MD0100PA01X+166934Y+085053X0190Y         S0      
327m6467            J69   -29         A01X+166934Y+085053X0205Y0590R090 S1      
317m6468            VIA   -    MD0080PA01X+150502Y+092427X0160Y    R180 S0      
327m6468            U25   -U14        A01X+150318Y+092532X0177Y    R180 S1      
317m6468            VIA   -    MD0100PA01X+165320Y+084718X0190Y         S0      
327m6468            J69   -172        A01X+165320Y+084718X0205Y0590R090 S1      
317m6469            VIA   -    MD0080PA01X+151057Y+092108X0160Y    R180 S0      
327m6469            U25   -T13        A01X+150873Y+092213X0177Y    R180 S1      
317m6469            VIA   -    MD0100PA01X+165320Y+084049X0190Y         S0      
327m6469            J69   -170        A01X+165320Y+084049X0205Y0590R090 S1      
317m6470            VIA   -    MD0080PA01X+150687Y+092108X0160Y    R180 S0      
327m6470            U25   -T14        A01X+150503Y+092213X0177Y    R180 S1      
317m6470            VIA   -    MD0100PA01X+166934Y+084384X0190Y         S0      
327m6470            J69   -27         A01X+166934Y+084384X0205Y0590R090 S1      
317m6471            VIA   -    MD0080PA01X+151242Y+091789X0160Y    R180 S0      
327m6471            U25   -R12        A01X+151058Y+091894X0177Y    R180 S1      
317m6471            VIA   -    MD0100PA01X+166934Y+083715X0190Y         S0      
327m6471            J69   -25         A01X+166934Y+083715X0205Y0590R090 S1      
317m6472            VIA   -    MD0080PA01X+150502Y+091151X0160Y    R180 S0      
327m6472            U25   -N14        A01X+150318Y+091256X0177Y    R180 S1      
317m6472            VIA   -    MD0100PA01X+165320Y+082376X0190Y         S0      
327m6472            J69   -165        A01X+165320Y+082376X0205Y0590R090 S1      
317m6473            VIA   -    MD0080PA01X+151057Y+090832X0160Y    R180 S0      
327m6473            U25   -M13        A01X+150873Y+090937X0177Y    R180 S1      
317m6473            VIA   -    MD0100PA01X+165320Y+081707X0190Y         S0      
327m6473            J69   -163        A01X+165320Y+081707X0205Y0590R090 S1      
317m6474            VIA   -    MD0080PA01X+151242Y+088600X0160Y    R180 S0      
327m6474            U25   -E12        A01X+151058Y+088705X0177Y    R180 S1      
317m6474            VIA   -    MD0100PA01X+166934Y+077691X0190Y         S0      
327m6474            J69   -7          A01X+166934Y+077691X0205Y0590R090 S1      
317m6475            VIA   -    MD0080PA01X+150687Y+099124X0160Y    R180 S0      
327m6475            U25   -AV14       A01X+150503Y+099228X0177Y    R180 S1      
317m6475            VIA   -    MD0100PA01X+165320Y+097100X0190Y         S0      
327m6475            J69   -209        A01X+165320Y+097100X0205Y0590R090 S1      
317m6476            VIA   -    MD0080PA01X+151242Y+098805X0160Y    R180 S0      
327m6476            U25   -AU12       A01X+151058Y+098910X0177Y    R180 S1      
317m6476            VIA   -    MD0100PA01X+166934Y+096766X0190Y         S0      
327m6476            J69   -64         A01X+166934Y+096766X0205Y0590R090 S1      
317m6477            VIA   -    MD0080PA01X+150502Y+098167X0160Y    R180 S0      
327m6477            U25   -AR14       A01X+150318Y+098272X0177Y    R180 S1      
317m6477            VIA   -    MD0100PA01X+165320Y+095762X0190Y         S0      
327m6477            J69   -205        A01X+165320Y+095762X0205Y0590R090 S1      
317m6478            VIA   -    MD0080PA01X+151057Y+097848X0160Y    R180 S0      
327m6478            U25   -AP13       A01X+150873Y+097953X0177Y    R180 S1      
317m6478            VIA   -    MD0100PA01X+165320Y+095092X0190Y         S0      
327m6478            J69   -203        A01X+165320Y+095092X0205Y0590R090 S1      
317m6479            VIA   -    MD0080PA01X+150687Y+097848X0160Y    R180 S0      
327m6479            U25   -AP14       A01X+150503Y+097953X0177Y    R180 S1      
317m6479            VIA   -    MD0100PA01X+166934Y+095427X0190Y         S0      
327m6479            J69   -60         A01X+166934Y+095427X0205Y0590R090 S1      
317m6480            VIA   -    MD0080PA01X+151242Y+097529X0160Y    R180 S0      
327m6480            U25   -AN12       A01X+151058Y+097634X0177Y    R180 S1      
317m6480            VIA   -    MD0100PA01X+166934Y+094758X0190Y         S0      
327m6480            J69   -58         A01X+166934Y+094758X0205Y0590R090 S1      
317m6481            VIA   -    MD0080PA01X+150502Y+096891X0160Y    R180 S0      
327m6481            U25   -AL14       A01X+150318Y+096996X0177Y    R180 S1      
317m6481            VIA   -    MD0100PA01X+165320Y+093419X0190Y         S0      
327m6481            J69   -198        A01X+165320Y+093419X0205Y0590R090 S1      
317m6482            VIA   -    MD0080PA01X+151057Y+096572X0160Y    R180 S0      
327m6482            U25   -AK13       A01X+150873Y+096677X0177Y    R180 S1      
317m6482            VIA   -    MD0100PA01X+165320Y+092750X0190Y         S0      
327m6482            J69   -196        A01X+165320Y+092750X0205Y0590R090 S1      
317m6483            VIA   -    MD0080PA01X+150687Y+096572X0160Y    R180 S0      
327m6483            U25   -AK14       A01X+150503Y+096677X0177Y    R180 S1      
317m6483            VIA   -    MD0100PA01X+166934Y+093085X0190Y         S0      
327m6483            J69   -53         A01X+166934Y+093085X0205Y0590R090 S1      
317m6484            VIA   -    MD0080PA01X+151242Y+096254X0160Y    R180 S0      
327m6484            U25   -AJ12       A01X+151058Y+096358X0177Y    R180 S1      
317m6484            VIA   -    MD0100PA01X+166934Y+092415X0190Y         S0      
327m6484            J69   -51         A01X+166934Y+092415X0205Y0590R090 S1      
317m6485            VIA   -    MD0080PA01X+150687Y+100399X0160Y    R180 S0      
327m6485            U25   -BB14       A01X+150503Y+100504X0177Y    R180 S1      
317m6485            VIA   -    MD0100PA01X+166934Y+099443X0190Y         S0      
327m6485            J69   -72         A01X+166934Y+099443X0205Y0590R090 S1      
317m6486            VIA   -    MD0080PA01X+151057Y+100399X0160Y    R180 S0      
327m6486            U25   -BB13       A01X+150873Y+100504X0177Y    R180 S1      
317m6486            VIA   -    MD0100PA01X+165320Y+099108X0190Y         S0      
327m6486            J69   -215        A01X+165320Y+099108X0205Y0590R090 S1      
317m6487            VIA   -    MD0080PA01X+151242Y+100080X0160Y    R180 S0      
327m6487            U25   -BA12       A01X+151058Y+100185X0177Y    R180 S1      
317m6487            VIA   -    MD0100PA01X+166934Y+098774X0190Y         S0      
327m6487            J69   -70         A01X+166934Y+098774X0205Y0590R090 S1      
317m6488            VIA   -    MD0080PA01X+150502Y+100080X0160Y    R180 S0      
327m6488            U25   -BA14       A01X+150318Y+100185X0177Y    R180 S1      
317m6488            VIA   -    MD0100PA01X+165320Y+098439X0190Y         S0      
327m6488            J69   -213        A01X+165320Y+098439X0205Y0590R090 S1      
317m6489            VIA   -    MD0080PA01X+150687Y+099762X0160Y    R180 S0      
327m6489            U25   -AY14       A01X+150503Y+099866X0177Y    R180 S1      
317m6489            VIA   -    MD0100PA01X+166934Y+098104X0190Y         S0      
327m6489            J69   -68         A01X+166934Y+098104X0205Y0590R090 S1      
317m6490            VIA   -    MD0080PA01X+151057Y+099762X0160Y    R180 S0      
327m6490            U25   -AY13       A01X+150873Y+099866X0177Y    R180 S1      
317m6490            VIA   -    MD0100PA01X+165320Y+097770X0190Y         S0      
327m6490            J69   -211        A01X+165320Y+097770X0205Y0590R090 S1      
317m6491            VIA   -    MD0080PA01X+151242Y+099443X0160Y    R180 S0      
327m6491            U25   -AW12       A01X+151058Y+099547X0177Y    R180 S1      
317m6491            VIA   -    MD0100PA01X+166934Y+097435X0190Y         S0      
327m6491            J69   -66         A01X+166934Y+097435X0205Y0590R090 S1      
317m6492            VIA   -    MD0080PA01X+150502Y+098805X0160Y    R180 S0      
327m6492            U25   -AU14       A01X+150318Y+098910X0177Y    R180 S1      
317m6492            VIA   -    MD0100PA01X+165320Y+096431X0190Y         S0      
327m6492            J69   -207        A01X+165320Y+096431X0205Y0590R090 S1      
317m6493            VIA   -    MD0080PA01X+151242Y+100718X0160Y    R180 S0      
327m6493            U25   -BC12       A01X+151058Y+100823X0177Y    R180 S1      
317m6493            VIA   -    MD0100PA01X+165320Y+099778X0190Y         S0      
327m6493            J69   -217        A01X+165320Y+099778X0205Y0590R090 S1      
317m6494            VIA   -    MD0080PA01X+151057Y+101037X0160Y    R180 S0      
327m6494            U25   -BD13       A01X+150873Y+101142X0177Y    R180 S1      
317m6494            VIA   -    MD0100PA01X+165320Y+100112X0190Y         S0      
327m6494            J69   -218        A01X+165320Y+100112X0205Y0590R090 S1      
317m6495            VIA   -    MD0080PA01X+150687Y+098486X0160Y    R180 S0      
327m6495            U25   -AT14       A01X+150503Y+098591X0177Y    R180 S1      
317m6495            VIA   -    MD0100PA18X+166384Y+096096X0190Y         S0      
327m6495            R382  -2          A18X+166384Y+096096X0198Y0197     S2      
327m6496            J69   -62         A01X+166934Y+096096X0205Y0590R090 S1      
317m6496            VIA   -    MD0100PA00X+166934Y+096096X0190Y         S0      
327m6496            R382  -1          A18X+166699Y+096096X0198Y0197     S2      
327m6497            U26   -BP2        A01X+057448Y+105252X0177Y    R180 S1      
327m6497            J102  -87         A01X+066350Y+106471X0205Y0590R090 S1      
327m6498            U26   -BL3        A01X+056893Y+104295X0177Y    R180 S1      
327m6498            J102  -227        A01X+064735Y+105132X0205Y0590R090 S1      
327m6499            U26   -BV2        A01X+057448Y+106528X0177Y    R180 S1      
327m6499            J102  -93         A01X+066350Y+108478X0205Y0590R090 S1      
327m6500            U26   -DD4        A01X+056708Y+114819X0177Y    R180 S1      
327m6500            J102  -283        A01X+064735Y+123872X0205Y0590R090 S1      
327m6501            U26   -CV4        A01X+056708Y+112906X0177Y    R180 S1      
327m6501            J102  -272        A01X+064735Y+120191X0205Y0590R090 S1      
327m6502            U26   -CM4        A01X+056708Y+110992X0177Y    R180 S1      
327m6502            J102  -261        A01X+064735Y+116510X0205Y0590R090 S1      
327m6503            U26   -CF4        A01X+056708Y+109079X0177Y    R180 S1      
327m6503            J102  -250        A01X+064735Y+112829X0205Y0590R090 S1      
327m6504            U26   -BY4        A01X+056708Y+107166X0177Y    R180 S1      
327m6504            J102  -239        A01X+064735Y+109148X0205Y0590R090 S1      
327m6505            U26   -DB2        A01X+057448Y+114181X0177Y    R180 S1      
327m6505            J102  -137        A01X+066350Y+123203X0205Y0590R090 S1      
327m6506            U26   -CT2        A01X+057448Y+112268X0177Y    R180 S1      
327m6506            J102  -126        A01X+066350Y+119522X0205Y0590R090 S1      
327m6507            U26   -CK2        A01X+057448Y+110354X0177Y    R180 S1      
327m6507            J102  -115        A01X+066350Y+115841X0205Y0590R090 S1      
327m6508            U26   -CD2        A01X+057448Y+108441X0177Y    R180 S1      
327m6508            J102  -104        A01X+066350Y+112160X0205Y0590R090 S1      
327m6509            U26   -BW2        A01X+057263Y+106847X0177Y    R180 S1      
327m6509            J102  -94         A01X+066350Y+108813X0205Y0590R090 S1      
327m6510            U26   -DC3        A01X+056893Y+114500X0177Y    R180 S1      
327m6510            J102  -282        A01X+064735Y+123538X0205Y0590R090 S1      
327m6511            U26   -CU3        A01X+056893Y+112587X0177Y    R180 S1      
327m6511            J102  -271        A01X+064735Y+119856X0205Y0590R090 S1      
327m6512            U26   -CL3        A01X+056893Y+110673X0177Y    R180 S1      
327m6512            J102  -260        A01X+064735Y+116175X0205Y0590R090 S1      
327m6513            U26   -CE3        A01X+056893Y+108760X0177Y    R180 S1      
327m6513            J102  -249        A01X+064735Y+112494X0205Y0590R090 S1      
327m6514            U26   -BW3        A01X+056893Y+106847X0177Y    R180 S1      
327m6514            J102  -238        A01X+064735Y+108813X0205Y0590R090 S1      
327m6515            U26   -DC2        A01X+057263Y+114500X0177Y    R180 S1      
327m6515            J102  -138        A01X+066350Y+123538X0205Y0590R090 S1      
327m6516            U26   -CU2        A01X+057263Y+112587X0177Y    R180 S1      
327m6516            J102  -127        A01X+066350Y+119856X0205Y0590R090 S1      
327m6517            U26   -CL2        A01X+057263Y+110673X0177Y    R180 S1      
327m6517            J102  -116        A01X+066350Y+116175X0205Y0590R090 S1      
327m6518            U26   -CE2        A01X+057263Y+108760X0177Y    R180 S1      
327m6518            J102  -105        A01X+066350Y+112494X0205Y0590R090 S1      
327m6519            U26   -CJ3        A01X+056893Y+110036X0177Y    R180 S1      
327m6519            J102  -113        A01X+066350Y+115171X0205Y0590R090 S1      
327m6520            U26   -CH2        A01X+057448Y+109717X0177Y    R180 S1      
327m6520            J102  -111        A01X+066350Y+114502X0205Y0590R090 S1      
327m6521            U26   -CH4        A01X+056708Y+109717X0177Y    R180 S1      
327m6521            J102  -254        A01X+064735Y+114168X0205Y0590R090 S1      
327m6522            U26   -CG2        A01X+057263Y+109398X0177Y    R180 S1      
327m6522            J102  -252        A01X+064735Y+113498X0205Y0590R090 S1      
327m6523            U26   -CG3        A01X+056893Y+109398X0177Y    R180 S1      
327m6523            J102  -109        A01X+066350Y+113833X0205Y0590R090 S1      
327m6524            U26   -CF2        A01X+057448Y+109079X0177Y    R180 S1      
327m6524            J102  -107        A01X+066350Y+113164X0205Y0590R090 S1      
327m6525            U26   -CD4        A01X+056708Y+108441X0177Y    R180 S1      
327m6525            J102  -247        A01X+064735Y+111825X0205Y0590R090 S1      
327m6526            U26   -DF2        A01X+057448Y+115457X0177Y    R180 S1      
327m6526            J102  -287        A01X+064735Y+125211X0205Y0590R090 S1      
327m6527            U26   -DE2        A01X+057263Y+115138X0177Y    R180 S1      
327m6527            J102  -285        A01X+064735Y+124542X0205Y0590R090 S1      
327m6528            U26   -CC2        A01X+057263Y+108122X0177Y    R180 S1      
327m6528            J102  -245        A01X+064735Y+111156X0205Y0590R090 S1      
327m6529            U26   -DE3        A01X+056893Y+115138X0177Y    R180 S1      
327m6529            J102  -142        A01X+066350Y+124876X0205Y0590R090 S1      
327m6530            U26   -DD2        A01X+057448Y+114819X0177Y    R180 S1      
327m6530            J102  -140        A01X+066350Y+124207X0205Y0590R090 S1      
327m6531            U26   -DB4        A01X+056708Y+114181X0177Y    R180 S1      
327m6531            J102  -280        A01X+064735Y+122868X0205Y0590R090 S1      
327m6532            U26   -DA2        A01X+057263Y+113862X0177Y    R180 S1      
327m6532            J102  -278        A01X+064735Y+122199X0205Y0590R090 S1      
327m6533            U26   -DA3        A01X+056893Y+113862X0177Y    R180 S1      
327m6533            J102  -135        A01X+066350Y+122534X0205Y0590R090 S1      
327m6534            U26   -CY2        A01X+057448Y+113543X0177Y    R180 S1      
327m6534            J102  -133        A01X+066350Y+121864X0205Y0590R090 S1      
327m6535            U26   -CY4        A01X+056708Y+113543X0177Y    R180 S1      
327m6535            J102  -276        A01X+064735Y+121530X0205Y0590R090 S1      
327m6536            U26   -CW2        A01X+057263Y+113225X0177Y    R180 S1      
327m6536            J102  -274        A01X+064735Y+120860X0205Y0590R090 S1      
327m6537            U26   -CW3        A01X+056893Y+113225X0177Y    R180 S1      
327m6537            J102  -131        A01X+066350Y+121195X0205Y0590R090 S1      
327m6538            U26   -CV2        A01X+057448Y+112906X0177Y    R180 S1      
327m6538            J102  -129        A01X+066350Y+120526X0205Y0590R090 S1      
327m6539            U26   -CC3        A01X+056893Y+108122X0177Y    R180 S1      
327m6539            J102  -102        A01X+066350Y+111490X0205Y0590R090 S1      
327m6540            U26   -CT4        A01X+056708Y+112268X0177Y    R180 S1      
327m6540            J102  -269        A01X+064735Y+119187X0205Y0590R090 S1      
327m6541            U26   -CR2        A01X+057263Y+111949X0177Y    R180 S1      
327m6541            J102  -267        A01X+064735Y+118518X0205Y0590R090 S1      
327m6542            U26   -CR3        A01X+056893Y+111949X0177Y    R180 S1      
327m6542            J102  -124        A01X+066350Y+118852X0205Y0590R090 S1      
327m6543            U26   -CP2        A01X+057448Y+111630X0177Y    R180 S1      
327m6543            J102  -122        A01X+066350Y+118183X0205Y0590R090 S1      
327m6544            U26   -CP4        A01X+056708Y+111630X0177Y    R180 S1      
327m6544            J102  -265        A01X+064735Y+117849X0205Y0590R090 S1      
327m6545            U26   -CN2        A01X+057263Y+111311X0177Y    R180 S1      
327m6545            J102  -263        A01X+064735Y+117179X0205Y0590R090 S1      
327m6546            U26   -CN3        A01X+056893Y+111311X0177Y    R180 S1      
327m6546            J102  -120        A01X+066350Y+117514X0205Y0590R090 S1      
327m6547            U26   -CM2        A01X+057448Y+110992X0177Y    R180 S1      
327m6547            J102  -118        A01X+066350Y+116845X0205Y0590R090 S1      
327m6548            U26   -CK4        A01X+056708Y+110354X0177Y    R180 S1      
327m6548            J102  -258        A01X+064735Y+115506X0205Y0590R090 S1      
327m6549            U26   -CJ2        A01X+057263Y+110036X0177Y    R180 S1      
327m6549            J102  -256        A01X+064735Y+114837X0205Y0590R090 S1      
327m6550            U26   -CB2        A01X+057448Y+107803X0177Y    R180 S1      
327m6550            J102  -100        A01X+066350Y+110821X0205Y0590R090 S1      
327m6551            U26   -BN2        A01X+057263Y+104933X0177Y    R180 S1      
327m6551            J102  -229        A01X+064735Y+105801X0205Y0590R090 S1      
327m6552            U26   -BM4        A01X+056708Y+104614X0177Y    R180 S1      
327m6552            J102  -84         A01X+066350Y+105467X0205Y0590R090 S1      
327m6553            U26   -BV4        A01X+056708Y+106528X0177Y    R180 S1      
327m6553            J102  -236        A01X+064735Y+108144X0205Y0590R090 S1      
327m6554            U26   -BU2        A01X+057263Y+106209X0177Y    R180 S1      
327m6554            J102  -234        A01X+064735Y+107474X0205Y0590R090 S1      
327m6555            U26   -BU3        A01X+056893Y+106209X0177Y    R180 S1      
327m6555            J102  -91         A01X+066350Y+107809X0205Y0590R090 S1      
327m6556            U26   -BT2        A01X+057448Y+105890X0177Y    R180 S1      
327m6556            J102  -89         A01X+066350Y+107140X0205Y0590R090 S1      
327m6557            U26   -CB4        A01X+056708Y+107803X0177Y    R180 S1      
327m6557            J102  -243        A01X+064735Y+110486X0205Y0590R090 S1      
327m6558            U26   -CA2        A01X+057263Y+107484X0177Y    R180 S1      
327m6558            J102  -241        A01X+064735Y+109817X0205Y0590R090 S1      
327m6559            U26   -CA3        A01X+056893Y+107484X0177Y    R180 S1      
327m6559            J102  -98         A01X+066350Y+110152X0205Y0590R090 S1      
327m6560            U26   -BY2        A01X+057448Y+107166X0177Y    R180 S1      
327m6560            J102  -96         A01X+066350Y+109482X0205Y0590R090 S1      
327m6561            U26   -BK2        A01X+057448Y+103976X0177Y    R180 S1      
327m6561            J102  -82         A01X+066350Y+104797X0205Y0590R090 S1      
327m6562            U26   -BK4        A01X+056708Y+103976X0177Y    R180 S1      
327m6562            J102  -225        A01X+064735Y+104463X0205Y0590R090 S1      
327m6563            U26   -BJ3        A01X+056893Y+103658X0177Y    R180 S1      
327m6563            J102  -80         A01X+066350Y+104128X0205Y0590R090 S1      
327m6564            U26   -BJ2        A01X+057263Y+103658X0177Y    R180 S1      
327m6564            J102  -223        A01X+064735Y+103793X0205Y0590R090 S1      
327m6565            U26   -BH2        A01X+057448Y+103339X0177Y    R180 S1      
327m6565            J102  -78         A01X+066350Y+103459X0205Y0590R090 S1      
327m6566            U26   -BH4        A01X+056708Y+103339X0177Y    R180 S1      
327m6566            J102  -221        A01X+064735Y+103124X0205Y0590R090 S1      
327m6567            U26   -BG3        A01X+056893Y+103020X0177Y    R180 S1      
327m6567            J102  -76         A01X+066350Y+102790X0205Y0590R090 S1      
327m6568            U26   -BN3        A01X+056893Y+104933X0177Y    R180 S1      
327m6568            J102  -86         A01X+066350Y+106136X0205Y0590R090 S1      
327m6569            U26   -BC3        A01X+056775Y+100823X0177Y    R180 S1      
327m6569            J102  -74         A01X+066350Y+100112X0205Y0590R090 S1      
327m6570            U26   -AN3        A01X+056775Y+097634X0177Y    R180 S1      
327m6570            J102  -201        A01X+064735Y+094423X0205Y0590R090 S1      
327m6571            U26   -AG3        A01X+056775Y+095721X0177Y    R180 S1      
327m6571            J102  -190        A01X+064735Y+090742X0205Y0590R090 S1      
327m6572            U26   -AA3        A01X+056775Y+093807X0177Y    R180 S1      
327m6572            J102  -179        A01X+064735Y+087061X0205Y0590R090 S1      
327m6573            U26   -R3         A01X+056775Y+091894X0177Y    R180 S1      
327m6573            J102  -168        A01X+064735Y+083380X0205Y0590R090 S1      
327m6574            U26   -J3         A01X+056775Y+089980X0177Y    R180 S1      
327m6574            J102  -157        A01X+064735Y+079699X0205Y0590R090 S1      
327m6575            U26   -AL2        A01X+057145Y+096996X0177Y    R180 S1      
327m6575            J102  -55         A01X+066350Y+093754X0205Y0590R090 S1      
327m6576            U26   -AE2        A01X+057145Y+095083X0177Y    R180 S1      
327m6576            J102  -44         A01X+066350Y+090073X0205Y0590R090 S1      
327m6577            U26   -W2         A01X+057145Y+093169X0177Y    R180 S1      
327m6577            J102  -33         A01X+066350Y+086392X0205Y0590R090 S1      
327m6578            U26   -N2         A01X+057145Y+091256X0177Y    R180 S1      
327m6578            J102  -22         A01X+066350Y+082711X0205Y0590R090 S1      
327m6579            U26   -G2         A01X+057145Y+089343X0177Y    R180 S1      
327m6579            J102  -11         A01X+066350Y+079030X0205Y0590R090 S1      
327m6580            U26   -AM4        A01X+056590Y+097315X0177Y    R180 S1      
327m6580            J102  -200        A01X+064735Y+094089X0205Y0590R090 S1      
327m6581            U26   -AF4        A01X+056590Y+095402X0177Y    R180 S1      
327m6581            J102  -189        A01X+064735Y+090408X0205Y0590R090 S1      
327m6582            U26   -Y4         A01X+056590Y+093488X0177Y    R180 S1      
327m6582            J102  -178        A01X+064735Y+086726X0205Y0590R090 S1      
327m6583            U26   -P4         A01X+056590Y+091575X0177Y    R180 S1      
327m6583            J102  -167        A01X+064735Y+083045X0205Y0590R090 S1      
327m6584            U26   -H4         A01X+056590Y+089662X0177Y    R180 S1      
327m6584            J102  -156        A01X+064735Y+079364X0205Y0590R090 S1      
327m6585            U26   -AM2        A01X+057330Y+097315X0177Y    R180 S1      
327m6585            J102  -56         A01X+066350Y+094089X0205Y0590R090 S1      
327m6586            U26   -AF2        A01X+057330Y+095402X0177Y    R180 S1      
327m6586            J102  -45         A01X+066350Y+090408X0205Y0590R090 S1      
327m6587            U26   -Y2         A01X+057330Y+093488X0177Y    R180 S1      
327m6587            J102  -34         A01X+066350Y+086726X0205Y0590R090 S1      
327m6588            U26   -P2         A01X+057330Y+091575X0177Y    R180 S1      
327m6588            J102  -23         A01X+066350Y+083045X0205Y0590R090 S1      
327m6589            U26   -H2         A01X+057330Y+089662X0177Y    R180 S1      
327m6589            J102  -12         A01X+066350Y+079364X0205Y0590R090 S1      
327m6590            U26   -M4         A01X+056590Y+090937X0177Y    R180 S1      
327m6590            J102  -20         A01X+066350Y+082042X0205Y0590R090 S1      
327m6591            U26   -L2         A01X+057145Y+090618X0177Y    R180 S1      
327m6591            J102  -18         A01X+066350Y+081372X0205Y0590R090 S1      
327m6592            U26   -L3         A01X+056775Y+090618X0177Y    R180 S1      
327m6592            J102  -161        A01X+064735Y+081038X0205Y0590R090 S1      
327m6593            U26   -K2         A01X+057330Y+090299X0177Y    R180 S1      
327m6593            J102  -159        A01X+064735Y+080368X0205Y0590R090 S1      
327m6594            U26   -K4         A01X+056590Y+090299X0177Y    R180 S1      
327m6594            J102  -16         A01X+066350Y+080703X0205Y0590R090 S1      
327m6595            U26   -J2         A01X+057145Y+089980X0177Y    R180 S1      
327m6595            J102  -14         A01X+066350Y+080034X0205Y0590R090 S1      
327m6596            U26   -G3         A01X+056775Y+089343X0177Y    R180 S1      
327m6596            J102  -154        A01X+064735Y+078695X0205Y0590R090 S1      
327m6597            U26   -AJ3        A01X+056775Y+096358X0177Y    R180 S1      
327m6597            J102  -194        A01X+064735Y+092081X0205Y0590R090 S1      
327m6598            U26   -AH2        A01X+057330Y+096040X0177Y    R180 S1      
327m6598            J102  -192        A01X+064735Y+091412X0205Y0590R090 S1      
327m6599            U26   -F2         A01X+057330Y+089024X0177Y    R180 S1      
327m6599            J102  -152        A01X+064735Y+078026X0205Y0590R090 S1      
327m6600            U26   -AH4        A01X+056590Y+096040X0177Y    R180 S1      
327m6600            J102  -49         A01X+066350Y+091746X0205Y0590R090 S1      
327m6601            U26   -AG2        A01X+057145Y+095721X0177Y    R180 S1      
327m6601            J102  -47         A01X+066350Y+091077X0205Y0590R090 S1      
327m6602            U26   -AE3        A01X+056775Y+095083X0177Y    R180 S1      
327m6602            J102  -187        A01X+064735Y+089738X0205Y0590R090 S1      
327m6603            U26   -AD2        A01X+057330Y+094764X0177Y    R180 S1      
327m6603            J102  -185        A01X+064735Y+089069X0205Y0590R090 S1      
327m6604            U26   -AD4        A01X+056590Y+094764X0177Y    R180 S1      
327m6604            J102  -42         A01X+066350Y+089404X0205Y0590R090 S1      
327m6605            U26   -AC2        A01X+057145Y+094445X0177Y    R180 S1      
327m6605            J102  -40         A01X+066350Y+088734X0205Y0590R090 S1      
327m6606            U26   -AC3        A01X+056775Y+094445X0177Y    R180 S1      
327m6606            J102  -183        A01X+064735Y+088400X0205Y0590R090 S1      
327m6607            U26   -AB2        A01X+057330Y+094126X0177Y    R180 S1      
327m6607            J102  -181        A01X+064735Y+087730X0205Y0590R090 S1      
327m6608            U26   -AB4        A01X+056590Y+094126X0177Y    R180 S1      
327m6608            J102  -38         A01X+066350Y+088065X0205Y0590R090 S1      
327m6609            U26   -AA2        A01X+057145Y+093807X0177Y    R180 S1      
327m6609            J102  -36         A01X+066350Y+087396X0205Y0590R090 S1      
327m6610            U26   -F4         A01X+056590Y+089024X0177Y    R180 S1      
327m6610            J102  -9          A01X+066350Y+078360X0205Y0590R090 S1      
327m6611            U26   -W3         A01X+056775Y+093169X0177Y    R180 S1      
327m6611            J102  -176        A01X+064735Y+086057X0205Y0590R090 S1      
327m6612            U26   -V2         A01X+057330Y+092850X0177Y    R180 S1      
327m6612            J102  -174        A01X+064735Y+085388X0205Y0590R090 S1      
327m6613            U26   -V4         A01X+056590Y+092850X0177Y    R180 S1      
327m6613            J102  -31         A01X+066350Y+085723X0205Y0590R090 S1      
327m6614            U26   -U2         A01X+057145Y+092532X0177Y    R180 S1      
327m6614            J102  -29         A01X+066350Y+085053X0205Y0590R090 S1      
327m6615            U26   -U3         A01X+056775Y+092532X0177Y    R180 S1      
327m6615            J102  -172        A01X+064735Y+084719X0205Y0590R090 S1      
327m6616            U26   -T2         A01X+057330Y+092213X0177Y    R180 S1      
327m6616            J102  -170        A01X+064735Y+084049X0205Y0590R090 S1      
327m6617            U26   -T4         A01X+056590Y+092213X0177Y    R180 S1      
327m6617            J102  -27         A01X+066350Y+084384X0205Y0590R090 S1      
327m6618            U26   -R2         A01X+057145Y+091894X0177Y    R180 S1      
327m6618            J102  -25         A01X+066350Y+083715X0205Y0590R090 S1      
327m6619            U26   -N3         A01X+056775Y+091256X0177Y    R180 S1      
327m6619            J102  -165        A01X+064735Y+082376X0205Y0590R090 S1      
327m6620            U26   -M2         A01X+057330Y+090937X0177Y    R180 S1      
327m6620            J102  -163        A01X+064735Y+081707X0205Y0590R090 S1      
327m6621            U26   -E2         A01X+057145Y+088705X0177Y    R180 S1      
327m6621            J102  -7          A01X+066350Y+077691X0205Y0590R090 S1      
327m6622            U26   -AV4        A01X+056590Y+099228X0177Y    R180 S1      
327m6622            J102  -209        A01X+064735Y+097100X0205Y0590R090 S1      
327m6623            U26   -AU2        A01X+057145Y+098910X0177Y    R180 S1      
327m6623            J102  -64         A01X+066350Y+096766X0205Y0590R090 S1      
327m6624            U26   -AR3        A01X+056775Y+098272X0177Y    R180 S1      
327m6624            J102  -205        A01X+064735Y+095762X0205Y0590R090 S1      
327m6625            U26   -AP2        A01X+057330Y+097953X0177Y    R180 S1      
327m6625            J102  -203        A01X+064735Y+095093X0205Y0590R090 S1      
327m6626            U26   -AP4        A01X+056590Y+097953X0177Y    R180 S1      
327m6626            J102  -60         A01X+066350Y+095427X0205Y0590R090 S1      
327m6627            U26   -AN2        A01X+057145Y+097634X0177Y    R180 S1      
327m6627            J102  -58         A01X+066350Y+094758X0205Y0590R090 S1      
327m6628            U26   -AL3        A01X+056775Y+096996X0177Y    R180 S1      
327m6628            J102  -198        A01X+064735Y+093419X0205Y0590R090 S1      
327m6629            U26   -AK2        A01X+057330Y+096677X0177Y    R180 S1      
327m6629            J102  -196        A01X+064735Y+092750X0205Y0590R090 S1      
327m6630            U26   -AK4        A01X+056590Y+096677X0177Y    R180 S1      
327m6630            J102  -53         A01X+066350Y+093085X0205Y0590R090 S1      
327m6631            U26   -AJ2        A01X+057145Y+096358X0177Y    R180 S1      
327m6631            J102  -51         A01X+066350Y+092416X0205Y0590R090 S1      
327m6632            U26   -BB4        A01X+056590Y+100504X0177Y    R180 S1      
327m6632            J102  -72         A01X+066350Y+099443X0205Y0590R090 S1      
327m6633            U26   -BB2        A01X+057330Y+100504X0177Y    R180 S1      
327m6633            J102  -215        A01X+064735Y+099108X0205Y0590R090 S1      
327m6634            U26   -BA2        A01X+057145Y+100185X0177Y    R180 S1      
327m6634            J102  -70         A01X+066350Y+098774X0205Y0590R090 S1      
327m6635            U26   -BA3        A01X+056775Y+100185X0177Y    R180 S1      
327m6635            J102  -213        A01X+064735Y+098439X0205Y0590R090 S1      
327m6636            U26   -AY4        A01X+056590Y+099866X0177Y    R180 S1      
327m6636            J102  -68         A01X+066350Y+098104X0205Y0590R090 S1      
327m6637            U26   -AY2        A01X+057330Y+099866X0177Y    R180 S1      
327m6637            J102  -211        A01X+064735Y+097770X0205Y0590R090 S1      
327m6638            U26   -AW2        A01X+057145Y+099547X0177Y    R180 S1      
327m6638            J102  -66         A01X+066350Y+097435X0205Y0590R090 S1      
327m6639            U26   -AT2        A01X+057330Y+098591X0177Y    R180 S1      
327m6639            J102  -207        A01X+064735Y+096431X0205Y0590R090 S1      
327m6640            U26   -BC2        A01X+057145Y+100823X0177Y    R180 S1      
327m6640            J102  -217        A01X+064735Y+099778X0205Y0590R090 S1      
327m6641            U26   -BD2        A01X+057330Y+101142X0177Y    R180 S1      
327m6641            J102  -218        A01X+064735Y+100112X0205Y0590R090 S1      
327m6642            U26   -AR2        A01X+057145Y+098272X0177Y    R180 S1      
327m6642            R506  -2          A18X+065800Y+096097X0198Y0197     S2      
317m6642            VIA   -    MD0100PA00X+065800Y+096097X0190Y         S0      
327m6643            J102  -62         A01X+066350Y+096097X0205Y0590R090 S1      
317m6643            VIA   -    MD0100PA00X+066350Y+096097X0190Y         S0      
327m6643            R506  -1          A18X+066115Y+096097X0198Y0197     S2      
327m6644            U25   -BP2        A01X+155062Y+105252X0177Y    R180 S1      
327m6644            J16   -87         A01X+163964Y+106470X0205Y0590R090 S1      
327m6645            U25   -BL3        A01X+154507Y+104295X0177Y    R180 S1      
327m6645            J16   -227        A01X+162350Y+105132X0205Y0590R090 S1      
327m6646            U25   -BV2        A01X+155062Y+106528X0177Y    R180 S1      
327m6646            J16   -93         A01X+163964Y+108478X0205Y0590R090 S1      
327m6647            U25   -DD4        A01X+154322Y+114819X0177Y    R180 S1      
327m6647            J16   -283        A01X+162350Y+123872X0205Y0590R090 S1      
327m6648            U25   -CV4        A01X+154322Y+112906X0177Y    R180 S1      
327m6648            J16   -272        A01X+162350Y+120191X0205Y0590R090 S1      
327m6649            U25   -CM4        A01X+154322Y+110992X0177Y    R180 S1      
327m6649            J16   -261        A01X+162350Y+116510X0205Y0590R090 S1      
327m6650            U25   -CF4        A01X+154322Y+109079X0177Y    R180 S1      
327m6650            J16   -250        A01X+162350Y+112829X0205Y0590R090 S1      
327m6651            U25   -BY4        A01X+154322Y+107165X0177Y    R180 S1      
327m6651            J16   -239        A01X+162350Y+109148X0205Y0590R090 S1      
327m6652            U25   -DB2        A01X+155062Y+114181X0177Y    R180 S1      
327m6652            J16   -137        A01X+163964Y+123203X0205Y0590R090 S1      
327m6653            U25   -CT2        A01X+155062Y+112268X0177Y    R180 S1      
327m6653            J16   -126        A01X+163964Y+119522X0205Y0590R090 S1      
327m6654            U25   -CK2        A01X+155062Y+110354X0177Y    R180 S1      
327m6654            J16   -115        A01X+163964Y+115841X0205Y0590R090 S1      
327m6655            U25   -CD2        A01X+155062Y+108441X0177Y    R180 S1      
327m6655            J16   -104        A01X+163964Y+112160X0205Y0590R090 S1      
327m6656            U25   -BW2        A01X+154877Y+106846X0177Y    R180 S1      
327m6656            J16   -94         A01X+163964Y+108813X0205Y0590R090 S1      
327m6657            U25   -DC3        A01X+154507Y+114500X0177Y    R180 S1      
327m6657            J16   -282        A01X+162350Y+123537X0205Y0590R090 S1      
327m6658            U25   -CU3        A01X+154507Y+112587X0177Y    R180 S1      
327m6658            J16   -271        A01X+162350Y+119856X0205Y0590R090 S1      
327m6659            U25   -CL3        A01X+154507Y+110673X0177Y    R180 S1      
327m6659            J16   -260        A01X+162350Y+116175X0205Y0590R090 S1      
327m6660            U25   -CE3        A01X+154507Y+108760X0177Y    R180 S1      
327m6660            J16   -249        A01X+162350Y+112494X0205Y0590R090 S1      
327m6661            U25   -BW3        A01X+154507Y+106846X0177Y    R180 S1      
327m6661            J16   -238        A01X+162350Y+108813X0205Y0590R090 S1      
327m6662            U25   -DC2        A01X+154877Y+114500X0177Y    R180 S1      
327m6662            J16   -138        A01X+163964Y+123537X0205Y0590R090 S1      
327m6663            U25   -CU2        A01X+154877Y+112587X0177Y    R180 S1      
327m6663            J16   -127        A01X+163964Y+119856X0205Y0590R090 S1      
327m6664            U25   -CL2        A01X+154877Y+110673X0177Y    R180 S1      
327m6664            J16   -116        A01X+163964Y+116175X0205Y0590R090 S1      
327m6665            U25   -CE2        A01X+154877Y+108760X0177Y    R180 S1      
327m6665            J16   -105        A01X+163964Y+112494X0205Y0590R090 S1      
327m6666            U25   -CJ3        A01X+154507Y+110036X0177Y    R180 S1      
327m6666            J16   -113        A01X+163964Y+115171X0205Y0590R090 S1      
327m6667            U25   -CH2        A01X+155062Y+109717X0177Y    R180 S1      
327m6667            J16   -111        A01X+163964Y+114502X0205Y0590R090 S1      
327m6668            U25   -CH4        A01X+154322Y+109717X0177Y    R180 S1      
327m6668            J16   -254        A01X+162350Y+114167X0205Y0590R090 S1      
327m6669            U25   -CG2        A01X+154877Y+109398X0177Y    R180 S1      
327m6669            J16   -252        A01X+162350Y+113498X0205Y0590R090 S1      
327m6670            U25   -CG3        A01X+154507Y+109398X0177Y    R180 S1      
327m6670            J16   -109        A01X+163964Y+113833X0205Y0590R090 S1      
327m6671            U25   -CF2        A01X+155062Y+109079X0177Y    R180 S1      
327m6671            J16   -107        A01X+163964Y+113163X0205Y0590R090 S1      
327m6672            U25   -CD4        A01X+154322Y+108441X0177Y    R180 S1      
327m6672            J16   -247        A01X+162350Y+111825X0205Y0590R090 S1      
327m6673            U25   -DF2        A01X+155062Y+115457X0177Y    R180 S1      
327m6673            J16   -287        A01X+162350Y+125211X0205Y0590R090 S1      
327m6674            U25   -DE2        A01X+154877Y+115138X0177Y    R180 S1      
327m6674            J16   -285        A01X+162350Y+124541X0205Y0590R090 S1      
327m6675            U25   -CC2        A01X+154877Y+108122X0177Y    R180 S1      
327m6675            J16   -245        A01X+162350Y+111156X0205Y0590R090 S1      
327m6676            U25   -DE3        A01X+154507Y+115138X0177Y    R180 S1      
327m6676            J16   -142        A01X+163964Y+124876X0205Y0590R090 S1      
327m6677            U25   -DD2        A01X+155062Y+114819X0177Y    R180 S1      
327m6677            J16   -140        A01X+163964Y+124207X0205Y0590R090 S1      
327m6678            U25   -DB4        A01X+154322Y+114181X0177Y    R180 S1      
327m6678            J16   -280        A01X+162350Y+122868X0205Y0590R090 S1      
327m6679            U25   -DA2        A01X+154877Y+113862X0177Y    R180 S1      
327m6679            J16   -278        A01X+162350Y+122199X0205Y0590R090 S1      
327m6680            U25   -DA3        A01X+154507Y+113862X0177Y    R180 S1      
327m6680            J16   -135        A01X+163964Y+122534X0205Y0590R090 S1      
327m6681            U25   -CY2        A01X+155062Y+113543X0177Y    R180 S1      
327m6681            J16   -133        A01X+163964Y+121864X0205Y0590R090 S1      
327m6682            U25   -CY4        A01X+154322Y+113543X0177Y    R180 S1      
327m6682            J16   -276        A01X+162350Y+121530X0205Y0590R090 S1      
327m6683            U25   -CW2        A01X+154877Y+113224X0177Y    R180 S1      
327m6683            J16   -274        A01X+162350Y+120860X0205Y0590R090 S1      
327m6684            U25   -CW3        A01X+154507Y+113224X0177Y    R180 S1      
327m6684            J16   -131        A01X+163964Y+121195X0205Y0590R090 S1      
327m6685            U25   -CV2        A01X+155062Y+112906X0177Y    R180 S1      
327m6685            J16   -129        A01X+163964Y+120526X0205Y0590R090 S1      
327m6686            U25   -CC3        A01X+154507Y+108122X0177Y    R180 S1      
327m6686            J16   -102        A01X+163964Y+111490X0205Y0590R090 S1      
327m6687            U25   -CT4        A01X+154322Y+112268X0177Y    R180 S1      
327m6687            J16   -269        A01X+162350Y+119187X0205Y0590R090 S1      
327m6688            U25   -CR2        A01X+154877Y+111949X0177Y    R180 S1      
327m6688            J16   -267        A01X+162350Y+118518X0205Y0590R090 S1      
327m6689            U25   -CR3        A01X+154507Y+111949X0177Y    R180 S1      
327m6689            J16   -124        A01X+163964Y+118852X0205Y0590R090 S1      
327m6690            U25   -CP2        A01X+155062Y+111630X0177Y    R180 S1      
327m6690            J16   -122        A01X+163964Y+118183X0205Y0590R090 S1      
327m6691            U25   -CP4        A01X+154322Y+111630X0177Y    R180 S1      
327m6691            J16   -265        A01X+162350Y+117848X0205Y0590R090 S1      
327m6692            U25   -CN2        A01X+154877Y+111311X0177Y    R180 S1      
327m6692            J16   -263        A01X+162350Y+117179X0205Y0590R090 S1      
327m6693            U25   -CN3        A01X+154507Y+111311X0177Y    R180 S1      
327m6693            J16   -120        A01X+163964Y+117514X0205Y0590R090 S1      
327m6694            U25   -CM2        A01X+155062Y+110992X0177Y    R180 S1      
327m6694            J16   -118        A01X+163964Y+116844X0205Y0590R090 S1      
327m6695            U25   -CK4        A01X+154322Y+110354X0177Y    R180 S1      
327m6695            J16   -258        A01X+162350Y+115506X0205Y0590R090 S1      
327m6696            U25   -CJ2        A01X+154877Y+110036X0177Y    R180 S1      
327m6696            J16   -256        A01X+162350Y+114837X0205Y0590R090 S1      
327m6697            U25   -CB2        A01X+155062Y+107803X0177Y    R180 S1      
327m6697            J16   -100        A01X+163964Y+110821X0205Y0590R090 S1      
327m6698            U25   -BN2        A01X+154877Y+104933X0177Y    R180 S1      
327m6698            J16   -229        A01X+162350Y+105801X0205Y0590R090 S1      
327m6699            U25   -BM4        A01X+154322Y+104614X0177Y    R180 S1      
327m6699            J16   -84         A01X+163964Y+105467X0205Y0590R090 S1      
327m6700            U25   -BV4        A01X+154322Y+106528X0177Y    R180 S1      
327m6700            J16   -236        A01X+162350Y+108144X0205Y0590R090 S1      
327m6701            U25   -BU2        A01X+154877Y+106209X0177Y    R180 S1      
327m6701            J16   -234        A01X+162350Y+107474X0205Y0590R090 S1      
327m6702            U25   -BU3        A01X+154507Y+106209X0177Y    R180 S1      
327m6702            J16   -91         A01X+163964Y+107809X0205Y0590R090 S1      
327m6703            U25   -BT2        A01X+155062Y+105890X0177Y    R180 S1      
327m6703            J16   -89         A01X+163964Y+107140X0205Y0590R090 S1      
327m6704            U25   -CB4        A01X+154322Y+107803X0177Y    R180 S1      
327m6704            J16   -243        A01X+162350Y+110486X0205Y0590R090 S1      
327m6705            U25   -CA2        A01X+154877Y+107484X0177Y    R180 S1      
327m6705            J16   -241        A01X+162350Y+109817X0205Y0590R090 S1      
327m6706            U25   -CA3        A01X+154507Y+107484X0177Y    R180 S1      
327m6706            J16   -98         A01X+163964Y+110152X0205Y0590R090 S1      
327m6707            U25   -BY2        A01X+155062Y+107165X0177Y    R180 S1      
327m6707            J16   -96         A01X+163964Y+109482X0205Y0590R090 S1      
327m6708            U25   -BK2        A01X+155062Y+103976X0177Y    R180 S1      
327m6708            J16   -82         A01X+163964Y+104797X0205Y0590R090 S1      
327m6709            U25   -BK4        A01X+154322Y+103976X0177Y    R180 S1      
327m6709            J16   -225        A01X+162350Y+104463X0205Y0590R090 S1      
327m6710            U25   -BJ3        A01X+154507Y+103658X0177Y    R180 S1      
327m6710            J16   -80         A01X+163964Y+104128X0205Y0590R090 S1      
327m6711            U25   -BJ2        A01X+154877Y+103658X0177Y    R180 S1      
327m6711            J16   -223        A01X+162350Y+103793X0205Y0590R090 S1      
327m6712            U25   -BH2        A01X+155062Y+103339X0177Y    R180 S1      
327m6712            J16   -78         A01X+163964Y+103459X0205Y0590R090 S1      
327m6713            U25   -BH4        A01X+154322Y+103339X0177Y    R180 S1      
327m6713            J16   -221        A01X+162350Y+103124X0205Y0590R090 S1      
327m6714            U25   -BG3        A01X+154507Y+103020X0177Y    R180 S1      
327m6714            J16   -76         A01X+163964Y+102789X0205Y0590R090 S1      
327m6715            U25   -BN3        A01X+154507Y+104933X0177Y    R180 S1      
327m6715            J16   -86         A01X+163964Y+106136X0205Y0590R090 S1      
327m6716            U25   -BC3        A01X+154389Y+100823X0177Y    R180 S1      
327m6716            J16   -74         A01X+163964Y+100112X0205Y0590R090 S1      
327m6717            U25   -AN3        A01X+154389Y+097634X0177Y    R180 S1      
327m6717            J16   -201        A01X+162350Y+094423X0205Y0590R090 S1      
327m6718            U25   -AG3        A01X+154389Y+095720X0177Y    R180 S1      
327m6718            J16   -190        A01X+162350Y+090742X0205Y0590R090 S1      
327m6719            U25   -AA3        A01X+154389Y+093807X0177Y    R180 S1      
327m6719            J16   -179        A01X+162350Y+087061X0205Y0590R090 S1      
327m6720            U25   -R3         A01X+154389Y+091894X0177Y    R180 S1      
327m6720            J16   -168        A01X+162350Y+083380X0205Y0590R090 S1      
327m6721            U25   -J3         A01X+154389Y+089980X0177Y    R180 S1      
327m6721            J16   -157        A01X+162350Y+079699X0205Y0590R090 S1      
327m6722            U25   -AL2        A01X+154759Y+096996X0177Y    R180 S1      
327m6722            J16   -55         A01X+163964Y+093754X0205Y0590R090 S1      
327m6723            U25   -AE2        A01X+154759Y+095083X0177Y    R180 S1      
327m6723            J16   -44         A01X+163964Y+090073X0205Y0590R090 S1      
327m6724            U25   -W2         A01X+154759Y+093169X0177Y    R180 S1      
327m6724            J16   -33         A01X+163964Y+086392X0205Y0590R090 S1      
327m6725            U25   -N2         A01X+154759Y+091256X0177Y    R180 S1      
327m6725            J16   -22         A01X+163964Y+082711X0205Y0590R090 S1      
327m6726            U25   -G2         A01X+154759Y+089343X0177Y    R180 S1      
327m6726            J16   -11         A01X+163964Y+079030X0205Y0590R090 S1      
327m6727            U25   -AM4        A01X+154204Y+097315X0177Y    R180 S1      
327m6727            J16   -200        A01X+162350Y+094089X0205Y0590R090 S1      
327m6728            U25   -AF4        A01X+154204Y+095402X0177Y    R180 S1      
327m6728            J16   -189        A01X+162350Y+090408X0205Y0590R090 S1      
327m6729            U25   -Y4         A01X+154204Y+093488X0177Y    R180 S1      
327m6729            J16   -178        A01X+162350Y+086726X0205Y0590R090 S1      
327m6730            U25   -P4         A01X+154204Y+091575X0177Y    R180 S1      
327m6730            J16   -167        A01X+162350Y+083045X0205Y0590R090 S1      
327m6731            U25   -H4         A01X+154204Y+089662X0177Y    R180 S1      
327m6731            J16   -156        A01X+162350Y+079364X0205Y0590R090 S1      
327m6732            U25   -AM2        A01X+154944Y+097315X0177Y    R180 S1      
327m6732            J16   -56         A01X+163964Y+094089X0205Y0590R090 S1      
327m6733            U25   -AF2        A01X+154944Y+095402X0177Y    R180 S1      
327m6733            J16   -45         A01X+163964Y+090408X0205Y0590R090 S1      
327m6734            U25   -Y2         A01X+154944Y+093488X0177Y    R180 S1      
327m6734            J16   -34         A01X+163964Y+086726X0205Y0590R090 S1      
327m6735            U25   -P2         A01X+154944Y+091575X0177Y    R180 S1      
327m6735            J16   -23         A01X+163964Y+083045X0205Y0590R090 S1      
327m6736            U25   -H2         A01X+154944Y+089662X0177Y    R180 S1      
327m6736            J16   -12         A01X+163964Y+079364X0205Y0590R090 S1      
327m6737            U25   -M4         A01X+154204Y+090937X0177Y    R180 S1      
327m6737            J16   -20         A01X+163964Y+082041X0205Y0590R090 S1      
327m6738            U25   -L2         A01X+154759Y+090618X0177Y    R180 S1      
327m6738            J16   -18         A01X+163964Y+081372X0205Y0590R090 S1      
327m6739            U25   -L3         A01X+154389Y+090618X0177Y    R180 S1      
327m6739            J16   -161        A01X+162350Y+081037X0205Y0590R090 S1      
327m6740            U25   -K2         A01X+154944Y+090299X0177Y    R180 S1      
327m6740            J16   -159        A01X+162350Y+080368X0205Y0590R090 S1      
327m6741            U25   -K4         A01X+154204Y+090299X0177Y    R180 S1      
327m6741            J16   -16         A01X+163964Y+080703X0205Y0590R090 S1      
327m6742            U25   -J2         A01X+154759Y+089980X0177Y    R180 S1      
327m6742            J16   -14         A01X+163964Y+080034X0205Y0590R090 S1      
327m6743            U25   -G3         A01X+154389Y+089343X0177Y    R180 S1      
327m6743            J16   -154        A01X+162350Y+078695X0205Y0590R090 S1      
327m6744            U25   -AJ3        A01X+154389Y+096358X0177Y    R180 S1      
327m6744            J16   -194        A01X+162350Y+092081X0205Y0590R090 S1      
327m6745            U25   -AH2        A01X+154944Y+096039X0177Y    R180 S1      
327m6745            J16   -192        A01X+162350Y+091411X0205Y0590R090 S1      
327m6746            U25   -F2         A01X+154944Y+089024X0177Y    R180 S1      
327m6746            J16   -152        A01X+162350Y+078026X0205Y0590R090 S1      
327m6747            U25   -AH4        A01X+154204Y+096039X0177Y    R180 S1      
327m6747            J16   -49         A01X+163964Y+091746X0205Y0590R090 S1      
327m6748            U25   -AG2        A01X+154759Y+095720X0177Y    R180 S1      
327m6748            J16   -47         A01X+163964Y+091077X0205Y0590R090 S1      
327m6749            U25   -AE3        A01X+154389Y+095083X0177Y    R180 S1      
327m6749            J16   -187        A01X+162350Y+089738X0205Y0590R090 S1      
327m6750            U25   -AD2        A01X+154944Y+094764X0177Y    R180 S1      
327m6750            J16   -185        A01X+162350Y+089069X0205Y0590R090 S1      
327m6751            U25   -AD4        A01X+154204Y+094764X0177Y    R180 S1      
327m6751            J16   -42         A01X+163964Y+089404X0205Y0590R090 S1      
327m6752            U25   -AC2        A01X+154759Y+094445X0177Y    R180 S1      
327m6752            J16   -40         A01X+163964Y+088734X0205Y0590R090 S1      
327m6753            U25   -AC3        A01X+154389Y+094445X0177Y    R180 S1      
327m6753            J16   -183        A01X+162350Y+088400X0205Y0590R090 S1      
327m6754            U25   -AB2        A01X+154944Y+094126X0177Y    R180 S1      
327m6754            J16   -181        A01X+162350Y+087730X0205Y0590R090 S1      
327m6755            U25   -AB4        A01X+154204Y+094126X0177Y    R180 S1      
327m6755            J16   -38         A01X+163964Y+088065X0205Y0590R090 S1      
327m6756            U25   -AA2        A01X+154759Y+093807X0177Y    R180 S1      
327m6756            J16   -36         A01X+163964Y+087396X0205Y0590R090 S1      
327m6757            U25   -F4         A01X+154204Y+089024X0177Y    R180 S1      
327m6757            J16   -9          A01X+163964Y+078360X0205Y0590R090 S1      
327m6758            U25   -W3         A01X+154389Y+093169X0177Y    R180 S1      
327m6758            J16   -176        A01X+162350Y+086057X0205Y0590R090 S1      
327m6759            U25   -V2         A01X+154944Y+092850X0177Y    R180 S1      
327m6759            J16   -174        A01X+162350Y+085388X0205Y0590R090 S1      
327m6760            U25   -V4         A01X+154204Y+092850X0177Y    R180 S1      
327m6760            J16   -31         A01X+163964Y+085722X0205Y0590R090 S1      
327m6761            U25   -U2         A01X+154759Y+092532X0177Y    R180 S1      
327m6761            J16   -29         A01X+163964Y+085053X0205Y0590R090 S1      
327m6762            U25   -U3         A01X+154389Y+092532X0177Y    R180 S1      
327m6762            J16   -172        A01X+162350Y+084718X0205Y0590R090 S1      
327m6763            U25   -T2         A01X+154944Y+092213X0177Y    R180 S1      
327m6763            J16   -170        A01X+162350Y+084049X0205Y0590R090 S1      
327m6764            U25   -T4         A01X+154204Y+092213X0177Y    R180 S1      
327m6764            J16   -27         A01X+163964Y+084384X0205Y0590R090 S1      
327m6765            U25   -R2         A01X+154759Y+091894X0177Y    R180 S1      
327m6765            J16   -25         A01X+163964Y+083715X0205Y0590R090 S1      
327m6766            U25   -N3         A01X+154389Y+091256X0177Y    R180 S1      
327m6766            J16   -165        A01X+162350Y+082376X0205Y0590R090 S1      
327m6767            U25   -M2         A01X+154944Y+090937X0177Y    R180 S1      
327m6767            J16   -163        A01X+162350Y+081707X0205Y0590R090 S1      
327m6768            U25   -E2         A01X+154759Y+088705X0177Y    R180 S1      
327m6768            J16   -7          A01X+163964Y+077691X0205Y0590R090 S1      
327m6769            U25   -AV4        A01X+154204Y+099228X0177Y    R180 S1      
327m6769            J16   -209        A01X+162350Y+097100X0205Y0590R090 S1      
327m6770            U25   -AU2        A01X+154759Y+098910X0177Y    R180 S1      
327m6770            J16   -64         A01X+163964Y+096766X0205Y0590R090 S1      
327m6771            U25   -AR3        A01X+154389Y+098272X0177Y    R180 S1      
327m6771            J16   -205        A01X+162350Y+095762X0205Y0590R090 S1      
327m6772            U25   -AP2        A01X+154944Y+097953X0177Y    R180 S1      
327m6772            J16   -203        A01X+162350Y+095092X0205Y0590R090 S1      
327m6773            U25   -AP4        A01X+154204Y+097953X0177Y    R180 S1      
327m6773            J16   -60         A01X+163964Y+095427X0205Y0590R090 S1      
327m6774            U25   -AN2        A01X+154759Y+097634X0177Y    R180 S1      
327m6774            J16   -58         A01X+163964Y+094758X0205Y0590R090 S1      
327m6775            U25   -AL3        A01X+154389Y+096996X0177Y    R180 S1      
327m6775            J16   -198        A01X+162350Y+093419X0205Y0590R090 S1      
327m6776            U25   -AK2        A01X+154944Y+096677X0177Y    R180 S1      
327m6776            J16   -196        A01X+162350Y+092750X0205Y0590R090 S1      
327m6777            U25   -AK4        A01X+154204Y+096677X0177Y    R180 S1      
327m6777            J16   -53         A01X+163964Y+093085X0205Y0590R090 S1      
327m6778            U25   -AJ2        A01X+154759Y+096358X0177Y    R180 S1      
327m6778            J16   -51         A01X+163964Y+092415X0205Y0590R090 S1      
327m6779            U25   -BB4        A01X+154204Y+100504X0177Y    R180 S1      
327m6779            J16   -72         A01X+163964Y+099443X0205Y0590R090 S1      
327m6780            U25   -BB2        A01X+154944Y+100504X0177Y    R180 S1      
327m6780            J16   -215        A01X+162350Y+099108X0205Y0590R090 S1      
327m6781            U25   -BA2        A01X+154759Y+100185X0177Y    R180 S1      
327m6781            J16   -70         A01X+163964Y+098774X0205Y0590R090 S1      
327m6782            U25   -BA3        A01X+154389Y+100185X0177Y    R180 S1      
327m6782            J16   -213        A01X+162350Y+098439X0205Y0590R090 S1      
327m6783            U25   -AY4        A01X+154204Y+099866X0177Y    R180 S1      
327m6783            J16   -68         A01X+163964Y+098104X0205Y0590R090 S1      
327m6784            U25   -AY2        A01X+154944Y+099866X0177Y    R180 S1      
327m6784            J16   -211        A01X+162350Y+097770X0205Y0590R090 S1      
327m6785            U25   -AW2        A01X+154759Y+099547X0177Y    R180 S1      
327m6785            J16   -66         A01X+163964Y+097435X0205Y0590R090 S1      
327m6786            U25   -AT2        A01X+154944Y+098591X0177Y    R180 S1      
327m6786            J16   -207        A01X+162350Y+096431X0205Y0590R090 S1      
327m6787            U25   -BC2        A01X+154759Y+100823X0177Y    R180 S1      
327m6787            J16   -217        A01X+162350Y+099778X0205Y0590R090 S1      
327m6788            U25   -BD2        A01X+154944Y+101142X0177Y    R180 S1      
327m6788            J16   -218        A01X+162350Y+100112X0205Y0590R090 S1      
327m6789            U25   -AR2        A01X+154759Y+098272X0177Y    R180 S1      
327m6789            R381  -2          A18X+163414Y+096096X0198Y0197     S2      
317m6789            VIA   -    MD0100PA00X+163414Y+096096X0190Y         S0      
327m6790            J16   -62         A01X+163964Y+096096X0205Y0590R090 S1      
317m6790            VIA   -    MD0100PA00X+163964Y+096096X0190Y         S0      
327m6790            R381  -1          A18X+163729Y+096096X0198Y0197     S2      
317m6791            VIA   -    MD0080PA01X+033209Y+105357X0160Y         S0      
327m6791            U26   -BP67       A01X+033393Y+105252X0177Y    R180 S1      
327m6791            J33   -87         A01X+008546Y+106471X0205Y0590R090 S1      
317m6791            VIA   -    MD0100PA01X+008546Y+106471X0190Y         S0      
317m6792            VIA   -    MD0080PA01X+033394Y+104400X0160Y         S0      
327m6792            U26   -BL67       A01X+033578Y+104295X0177Y    R180 S1      
327m6792            J33   -227        A01X+006932Y+105132X0205Y0590R090 S1      
317m6792            VIA   -    MD0100PA01X+006932Y+105132X0190Y         S0      
317m6793            VIA   -    MD0080PA01X+033209Y+106632X0160Y         S0      
327m6793            U26   -BV67       A01X+033393Y+106528X0177Y    R180 S1      
327m6793            J33   -93         A01X+008546Y+108478X0205Y0590R090 S1      
317m6793            VIA   -    MD0100PA01X+008546Y+108478X0190Y         S0      
317m6794            VIA   -    MD0080PA01X+033949Y+114924X0160Y         S0      
327m6794            U26   -DD65       A01X+034133Y+114819X0177Y    R180 S1      
317m6794            VIA   -    MD0100PA01X+006932Y+123872X0190Y         S0      
327m6794            J33   -283        A01X+006932Y+123872X0205Y0590R090 S1      
317m6795            VIA   -    MD0080PA01X+033949Y+113010X0160Y         S0      
317m6795            VIA   -    MD0100PA01X+006932Y+120191X0190Y         S0      
327m6795            J33   -272        A01X+006932Y+120191X0205Y0590R090 S1      
327m6795            U26   -CV65       A01X+034133Y+112906X0177Y    R180 S1      
317m6796            VIA   -    MD0080PA01X+033949Y+111097X0160Y         S0      
327m6796            U26   -CM65       A01X+034133Y+110992X0177Y    R180 S1      
327m6796            J33   -261        A01X+006932Y+116510X0205Y0590R090 S1      
317m6796            VIA   -    MD0100PA01X+006932Y+116510X0190Y         S0      
317m6797            VIA   -    MD0080PA01X+033949Y+109184X0160Y         S0      
327m6797            U26   -CF65       A01X+034133Y+109079X0177Y    R180 S1      
327m6797            J33   -250        A01X+006932Y+112829X0205Y0590R090 S1      
317m6797            VIA   -    MD0100PA01X+006932Y+112829X0190Y         S0      
317m6798            VIA   -    MD0080PA01X+033949Y+107270X0160Y         S0      
327m6798            U26   -BY65       A01X+034133Y+107166X0177Y    R180 S1      
327m6798            J33   -239        A01X+006932Y+109148X0205Y0590R090 S1      
317m6798            VIA   -    MD0100PA01X+006932Y+109148X0190Y         S0      
317m6799            VIA   -    MD0080PA01X+033209Y+114286X0160Y         S0      
317m6799            VIA   -    MD0100PA01X+008546Y+123203X0190Y         S0      
327m6799            J33   -137        A01X+008546Y+123203X0205Y0590R090 S1      
327m6799            U26   -DB67       A01X+033393Y+114181X0177Y    R180 S1      
317m6800            VIA   -    MD0080PA01X+033209Y+112373X0160Y         S0      
327m6800            J33   -126        A01X+008546Y+119522X0205Y0590R090 S1      
317m6800            VIA   -    MD0100PA01X+008546Y+119522X0190Y         S0      
327m6800            U26   -CT67       A01X+033393Y+112268X0177Y    R180 S1      
317m6801            VIA   -    MD0080PA01X+033209Y+110459X0160Y         S0      
327m6801            U26   -CK67       A01X+033393Y+110354X0177Y    R180 S1      
327m6801            J33   -115        A01X+008546Y+115841X0205Y0590R090 S1      
317m6801            VIA   -    MD0100PA01X+008546Y+115841X0190Y         S0      
317m6802            VIA   -    MD0080PA01X+033209Y+108546X0160Y         S0      
327m6802            U26   -CD67       A01X+033393Y+108441X0177Y    R180 S1      
327m6802            J33   -104        A01X+008546Y+112160X0205Y0590R090 S1      
317m6802            VIA   -    MD0100PA01X+008546Y+112160X0190Y         S0      
317m6803            VIA   -    MD0080PA01X+033394Y+106951X0160Y         S0      
327m6803            U26   -BW67       A01X+033578Y+106847X0177Y    R180 S1      
327m6803            J33   -94         A01X+008546Y+108813X0205Y0590R090 S1      
317m6803            VIA   -    MD0100PA01X+008546Y+108813X0190Y         S0      
317m6804            VIA   -    MD0080PA01X+033764Y+114605X0160Y         S0      
327m6804            U26   -DC66       A01X+033948Y+114500X0177Y    R180 S1      
317m6804            VIA   -    MD0100PA01X+006932Y+123538X0190Y         S0      
327m6804            J33   -282        A01X+006932Y+123538X0205Y0590R090 S1      
317m6805            VIA   -    MD0080PA01X+033764Y+112692X0160Y         S0      
317m6805            VIA   -    MD0100PA01X+006932Y+119856X0190Y         S0      
327m6805            J33   -271        A01X+006932Y+119856X0205Y0590R090 S1      
327m6805            U26   -CU66       A01X+033948Y+112587X0177Y    R180 S1      
317m6806            VIA   -    MD0080PA01X+033764Y+110778X0160Y         S0      
327m6806            U26   -CL66       A01X+033948Y+110673X0177Y    R180 S1      
327m6806            J33   -260        A01X+006932Y+116175X0205Y0590R090 S1      
317m6806            VIA   -    MD0100PA01X+006932Y+116175X0190Y         S0      
317m6807            VIA   -    MD0080PA01X+033764Y+108865X0160Y         S0      
327m6807            U26   -CE66       A01X+033948Y+108760X0177Y    R180 S1      
327m6807            J33   -249        A01X+006932Y+112494X0205Y0590R090 S1      
317m6807            VIA   -    MD0100PA01X+006932Y+112494X0190Y         S0      
317m6808            VIA   -    MD0080PA01X+033764Y+106951X0160Y         S0      
327m6808            U26   -BW66       A01X+033948Y+106847X0177Y    R180 S1      
327m6808            J33   -238        A01X+006932Y+108813X0205Y0590R090 S1      
317m6808            VIA   -    MD0100PA01X+006932Y+108813X0190Y         S0      
317m6809            VIA   -    MD0080PA01X+033394Y+114605X0160Y         S0      
317m6809            VIA   -    MD0100PA01X+008546Y+123538X0190Y         S0      
327m6809            J33   -138        A01X+008546Y+123538X0205Y0590R090 S1      
327m6809            U26   -DC67       A01X+033578Y+114500X0177Y    R180 S1      
317m6810            VIA   -    MD0080PA01X+033394Y+112692X0160Y         S0      
327m6810            J33   -127        A01X+008546Y+119856X0205Y0590R090 S1      
317m6810            VIA   -    MD0100PA01X+008546Y+119856X0190Y         S0      
327m6810            U26   -CU67       A01X+033578Y+112587X0177Y    R180 S1      
317m6811            VIA   -    MD0080PA01X+033394Y+110778X0160Y         S0      
327m6811            U26   -CL67       A01X+033578Y+110673X0177Y    R180 S1      
327m6811            J33   -116        A01X+008546Y+116175X0205Y0590R090 S1      
317m6811            VIA   -    MD0100PA01X+008546Y+116175X0190Y         S0      
317m6812            VIA   -    MD0080PA01X+033394Y+108865X0160Y         S0      
327m6812            U26   -CE67       A01X+033578Y+108760X0177Y    R180 S1      
327m6812            J33   -105        A01X+008546Y+112494X0205Y0590R090 S1      
317m6812            VIA   -    MD0100PA01X+008546Y+112494X0190Y         S0      
317m6813            VIA   -    MD0080PA01X+033764Y+110140X0160Y         S0      
327m6813            U26   -CJ66       A01X+033948Y+110036X0177Y    R180 S1      
327m6813            J33   -113        A01X+008546Y+115171X0205Y0590R090 S1      
317m6813            VIA   -    MD0100PA01X+008546Y+115171X0190Y         S0      
317m6814            VIA   -    MD0080PA01X+033209Y+109821X0160Y         S0      
327m6814            U26   -CH67       A01X+033393Y+109717X0177Y    R180 S1      
327m6814            J33   -111        A01X+008546Y+114502X0205Y0590R090 S1      
317m6814            VIA   -    MD0100PA01X+008546Y+114502X0190Y         S0      
317m6815            VIA   -    MD0080PA01X+033949Y+109821X0160Y         S0      
327m6815            U26   -CH65       A01X+034133Y+109717X0177Y    R180 S1      
327m6815            J33   -254        A01X+006932Y+114168X0205Y0590R090 S1      
317m6815            VIA   -    MD0100PA01X+006932Y+114168X0190Y         S0      
317m6816            VIA   -    MD0080PA01X+033394Y+109502X0160Y         S0      
327m6816            U26   -CG67       A01X+033578Y+109398X0177Y    R180 S1      
327m6816            J33   -252        A01X+006932Y+113498X0205Y0590R090 S1      
317m6816            VIA   -    MD0100PA01X+006932Y+113498X0190Y         S0      
317m6817            VIA   -    MD0080PA01X+033764Y+109502X0160Y         S0      
327m6817            U26   -CG66       A01X+033948Y+109398X0177Y    R180 S1      
327m6817            J33   -109        A01X+008546Y+113833X0205Y0590R090 S1      
317m6817            VIA   -    MD0100PA01X+008546Y+113833X0190Y         S0      
317m6818            VIA   -    MD0080PA01X+033209Y+109184X0160Y         S0      
327m6818            U26   -CF67       A01X+033393Y+109079X0177Y    R180 S1      
327m6818            J33   -107        A01X+008546Y+113164X0205Y0590R090 S1      
317m6818            VIA   -    MD0100PA01X+008546Y+113164X0190Y         S0      
317m6819            VIA   -    MD0080PA01X+033949Y+108546X0160Y         S0      
327m6819            U26   -CD65       A01X+034133Y+108441X0177Y    R180 S1      
327m6819            J33   -247        A01X+006932Y+111825X0205Y0590R090 S1      
317m6819            VIA   -    MD0100PA01X+006932Y+111825X0190Y         S0      
317m6820            VIA   -    MD0080PA01X+033209Y+115562X0160Y         S0      
327m6820            U26   -DF67       A01X+033393Y+115457X0177Y    R180 S1      
327m6820            J33   -287        A01X+006932Y+125211X0205Y0590R090 S1      
317m6820            VIA   -    MD0100PA01X+006932Y+125211X0190Y         S0      
317m6821            VIA   -    MD0080PA01X+033394Y+115243X0160Y         S0      
317m6821            VIA   -    MD0100PA01X+006932Y+124542X0190Y         S0      
327m6821            J33   -285        A01X+006932Y+124542X0205Y0590R090 S1      
327m6821            U26   -DE67       A01X+033578Y+115138X0177Y    R180 S1      
317m6822            VIA   -    MD0080PA01X+033394Y+108227X0160Y         S0      
327m6822            U26   -CC67       A01X+033578Y+108122X0177Y    R180 S1      
327m6822            J33   -245        A01X+006932Y+111156X0205Y0590R090 S1      
317m6822            VIA   -    MD0100PA01X+006932Y+111156X0190Y         S0      
317m6823            VIA   -    MD0080PA01X+033764Y+115243X0160Y         S0      
317m6823            VIA   -    MD0100PA01X+008546Y+124876X0190Y         S0      
327m6823            J33   -142        A01X+008546Y+124876X0205Y0590R090 S1      
327m6823            U26   -DE66       A01X+033948Y+115138X0177Y    R180 S1      
317m6824            VIA   -    MD0080PA01X+033209Y+114924X0160Y         S0      
317m6824            VIA   -    MD0100PA01X+008546Y+124207X0190Y         S0      
327m6824            J33   -140        A01X+008546Y+124207X0205Y0590R090 S1      
327m6824            U26   -DD67       A01X+033393Y+114819X0177Y    R180 S1      
317m6825            VIA   -    MD0080PA01X+033949Y+114286X0160Y         S0      
327m6825            J33   -280        A01X+006932Y+122868X0205Y0590R090 S1      
317m6825            VIA   -    MD0100PA01X+006932Y+122868X0190Y         S0      
327m6825            U26   -DB65       A01X+034133Y+114181X0177Y    R180 S1      
317m6826            VIA   -    MD0080PA01X+033394Y+113967X0160Y         S0      
317m6826            VIA   -    MD0100PA01X+006932Y+122199X0190Y         S0      
327m6826            J33   -278        A01X+006932Y+122199X0205Y0590R090 S1      
327m6826            U26   -DA67       A01X+033578Y+113862X0177Y    R180 S1      
317m6827            VIA   -    MD0080PA01X+033764Y+113967X0160Y         S0      
327m6827            J33   -135        A01X+008546Y+122534X0205Y0590R090 S1      
317m6827            VIA   -    MD0100PA01X+008546Y+122534X0190Y         S0      
327m6827            U26   -DA66       A01X+033948Y+113862X0177Y    R180 S1      
317m6828            VIA   -    MD0080PA01X+033209Y+113648X0160Y         S0      
317m6828            VIA   -    MD0100PA01X+008546Y+121864X0190Y         S0      
327m6828            J33   -133        A01X+008546Y+121864X0205Y0590R090 S1      
327m6828            U26   -CY67       A01X+033393Y+113543X0177Y    R180 S1      
317m6829            VIA   -    MD0080PA01X+033949Y+113648X0160Y         S0      
327m6829            U26   -CY65       A01X+034133Y+113543X0177Y    R180 S1      
327m6829            J33   -276        A01X+006932Y+121530X0205Y0590R090 S1      
317m6829            VIA   -    MD0100PA01X+006932Y+121530X0190Y         S0      
317m6830            VIA   -    MD0080PA01X+033394Y+113329X0160Y         S0      
317m6830            VIA   -    MD0100PA01X+006932Y+120860X0190Y         S0      
327m6830            J33   -274        A01X+006932Y+120860X0205Y0590R090 S1      
327m6830            U26   -CW67       A01X+033578Y+113225X0177Y    R180 S1      
317m6831            VIA   -    MD0080PA01X+033764Y+113329X0160Y         S0      
317m6831            VIA   -    MD0100PA01X+008546Y+121195X0190Y         S0      
327m6831            J33   -131        A01X+008546Y+121195X0205Y0590R090 S1      
327m6831            U26   -CW66       A01X+033948Y+113225X0177Y    R180 S1      
317m6832            VIA   -    MD0080PA01X+033209Y+113010X0160Y         S0      
317m6832            VIA   -    MD0100PA01X+008546Y+120526X0190Y         S0      
327m6832            J33   -129        A01X+008546Y+120526X0205Y0590R090 S1      
327m6832            U26   -CV67       A01X+033393Y+112906X0177Y    R180 S1      
317m6833            VIA   -    MD0080PA01X+033764Y+108227X0160Y         S0      
327m6833            U26   -CC66       A01X+033948Y+108122X0177Y    R180 S1      
327m6833            J33   -102        A01X+008546Y+111490X0205Y0590R090 S1      
317m6833            VIA   -    MD0100PA01X+008546Y+111490X0190Y         S0      
317m6834            VIA   -    MD0080PA01X+033949Y+112373X0160Y         S0      
317m6834            VIA   -    MD0100PA01X+006932Y+119187X0190Y         S0      
327m6834            J33   -269        A01X+006932Y+119187X0205Y0590R090 S1      
327m6834            U26   -CT65       A01X+034133Y+112268X0177Y    R180 S1      
317m6835            VIA   -    MD0080PA01X+033394Y+112054X0160Y         S0      
317m6835            VIA   -    MD0100PA01X+006932Y+118518X0190Y         S0      
327m6835            J33   -267        A01X+006932Y+118518X0205Y0590R090 S1      
327m6835            U26   -CR67       A01X+033578Y+111949X0177Y    R180 S1      
317m6836            VIA   -    MD0080PA01X+033764Y+112054X0160Y         S0      
317m6836            VIA   -    MD0100PA01X+008546Y+118852X0190Y         S0      
327m6836            J33   -124        A01X+008546Y+118852X0205Y0590R090 S1      
327m6836            U26   -CR66       A01X+033948Y+111949X0177Y    R180 S1      
317m6837            VIA   -    MD0080PA01X+033209Y+111735X0160Y         S0      
317m6837            VIA   -    MD0100PA01X+008546Y+118183X0190Y         S0      
327m6837            J33   -122        A01X+008546Y+118183X0205Y0590R090 S1      
327m6837            U26   -CP67       A01X+033393Y+111630X0177Y    R180 S1      
317m6838            VIA   -    MD0080PA01X+033949Y+111735X0160Y         S0      
327m6838            U26   -CP65       A01X+034133Y+111630X0177Y    R180 S1      
327m6838            J33   -265        A01X+006932Y+117849X0205Y0590R090 S1      
317m6838            VIA   -    MD0100PA01X+006932Y+117849X0190Y         S0      
317m6839            VIA   -    MD0080PA01X+033394Y+111416X0160Y         S0      
327m6839            U26   -CN67       A01X+033578Y+111311X0177Y    R180 S1      
327m6839            J33   -263        A01X+006932Y+117179X0205Y0590R090 S1      
317m6839            VIA   -    MD0100PA01X+006932Y+117179X0190Y         S0      
317m6840            VIA   -    MD0080PA01X+033764Y+111416X0160Y         S0      
327m6840            U26   -CN66       A01X+033948Y+111311X0177Y    R180 S1      
327m6840            J33   -120        A01X+008546Y+117514X0205Y0590R090 S1      
317m6840            VIA   -    MD0100PA01X+008546Y+117514X0190Y         S0      
317m6841            VIA   -    MD0080PA01X+033209Y+111097X0160Y         S0      
327m6841            U26   -CM67       A01X+033393Y+110992X0177Y    R180 S1      
327m6841            J33   -118        A01X+008546Y+116845X0205Y0590R090 S1      
317m6841            VIA   -    MD0100PA01X+008546Y+116845X0190Y         S0      
317m6842            VIA   -    MD0080PA01X+033949Y+110459X0160Y         S0      
327m6842            U26   -CK65       A01X+034133Y+110354X0177Y    R180 S1      
327m6842            J33   -258        A01X+006932Y+115506X0205Y0590R090 S1      
317m6842            VIA   -    MD0100PA01X+006932Y+115506X0190Y         S0      
317m6843            VIA   -    MD0080PA01X+033394Y+110140X0160Y         S0      
327m6843            U26   -CJ67       A01X+033578Y+110036X0177Y    R180 S1      
327m6843            J33   -256        A01X+006932Y+114837X0205Y0590R090 S1      
317m6843            VIA   -    MD0100PA01X+006932Y+114837X0190Y         S0      
317m6844            VIA   -    MD0080PA01X+033209Y+107908X0160Y         S0      
327m6844            U26   -CB67       A01X+033393Y+107803X0177Y    R180 S1      
327m6844            J33   -100        A01X+008546Y+110821X0205Y0590R090 S1      
317m6844            VIA   -    MD0100PA01X+008546Y+110821X0190Y         S0      
317m6845            VIA   -    MD0080PA01X+033394Y+105038X0160Y         S0      
327m6845            U26   -BN67       A01X+033578Y+104933X0177Y    R180 S1      
327m6845            J33   -229        A01X+006932Y+105801X0205Y0590R090 S1      
317m6845            VIA   -    MD0100PA01X+006932Y+105801X0190Y         S0      
317m6846            VIA   -    MD0080PA01X+033949Y+104719X0160Y         S0      
327m6846            U26   -BM65       A01X+034133Y+104614X0177Y    R180 S1      
327m6846            J33   -84         A01X+008546Y+105467X0205Y0590R090 S1      
317m6846            VIA   -    MD0100PA01X+008546Y+105467X0190Y         S0      
317m6847            VIA   -    MD0080PA01X+033949Y+106632X0160Y         S0      
327m6847            U26   -BV65       A01X+034133Y+106528X0177Y    R180 S1      
327m6847            J33   -236        A01X+006932Y+108144X0205Y0590R090 S1      
317m6847            VIA   -    MD0100PA01X+006932Y+108144X0190Y         S0      
317m6848            VIA   -    MD0080PA01X+033394Y+106314X0160Y         S0      
327m6848            U26   -BU67       A01X+033578Y+106209X0177Y    R180 S1      
327m6848            J33   -234        A01X+006932Y+107474X0205Y0590R090 S1      
317m6848            VIA   -    MD0100PA01X+006932Y+107474X0190Y         S0      
317m6849            VIA   -    MD0080PA01X+033764Y+106314X0160Y         S0      
327m6849            U26   -BU66       A01X+033948Y+106209X0177Y    R180 S1      
327m6849            J33   -91         A01X+008546Y+107809X0205Y0590R090 S1      
317m6849            VIA   -    MD0100PA01X+008546Y+107809X0190Y         S0      
317m6850            VIA   -    MD0080PA01X+033209Y+105995X0160Y         S0      
327m6850            U26   -BT67       A01X+033393Y+105890X0177Y    R180 S1      
327m6850            J33   -89         A01X+008546Y+107140X0205Y0590R090 S1      
317m6850            VIA   -    MD0100PA01X+008546Y+107140X0190Y         S0      
317m6851            VIA   -    MD0080PA01X+033949Y+107908X0160Y         S0      
327m6851            U26   -CB65       A01X+034133Y+107803X0177Y    R180 S1      
327m6851            J33   -243        A01X+006932Y+110486X0205Y0590R090 S1      
317m6851            VIA   -    MD0100PA01X+006932Y+110486X0190Y         S0      
317m6852            VIA   -    MD0080PA01X+033394Y+107589X0160Y         S0      
327m6852            U26   -CA67       A01X+033578Y+107484X0177Y    R180 S1      
327m6852            J33   -241        A01X+006932Y+109817X0205Y0590R090 S1      
317m6852            VIA   -    MD0100PA01X+006932Y+109817X0190Y         S0      
317m6853            VIA   -    MD0080PA01X+033764Y+107589X0160Y         S0      
327m6853            U26   -CA66       A01X+033948Y+107484X0177Y    R180 S1      
327m6853            J33   -98         A01X+008546Y+110152X0205Y0590R090 S1      
317m6853            VIA   -    MD0100PA01X+008546Y+110152X0190Y         S0      
317m6854            VIA   -    MD0080PA01X+033209Y+107270X0160Y         S0      
327m6854            U26   -BY67       A01X+033393Y+107166X0177Y    R180 S1      
327m6854            J33   -96         A01X+008546Y+109482X0205Y0590R090 S1      
317m6854            VIA   -    MD0100PA01X+008546Y+109482X0190Y         S0      
317m6855            VIA   -    MD0080PA01X+033209Y+104081X0160Y         S0      
327m6855            U26   -BK67       A01X+033393Y+103976X0177Y    R180 S1      
327m6855            J33   -82         A01X+008546Y+104797X0205Y0590R090 S1      
317m6855            VIA   -    MD0100PA01X+008546Y+104797X0190Y         S0      
317m6856            VIA   -    MD0080PA01X+033949Y+104081X0160Y         S0      
327m6856            U26   -BK65       A01X+034133Y+103976X0177Y    R180 S1      
327m6856            J33   -225        A01X+006932Y+104463X0205Y0590R090 S1      
317m6856            VIA   -    MD0100PA01X+006932Y+104463X0190Y         S0      
317m6857            VIA   -    MD0080PA01X+033764Y+103762X0160Y         S0      
327m6857            U26   -BJ66       A01X+033948Y+103658X0177Y    R180 S1      
327m6857            J33   -80         A01X+008546Y+104128X0205Y0590R090 S1      
317m6857            VIA   -    MD0100PA01X+008546Y+104128X0190Y         S0      
317m6858            VIA   -    MD0080PA01X+033394Y+103762X0160Y         S0      
327m6858            U26   -BJ67       A01X+033578Y+103658X0177Y    R180 S1      
327m6858            J33   -223        A01X+006932Y+103793X0205Y0590R090 S1      
317m6858            VIA   -    MD0100PA01X+006932Y+103793X0190Y         S0      
317m6859            VIA   -    MD0080PA01X+033209Y+103443X0160Y         S0      
327m6859            U26   -BH67       A01X+033393Y+103339X0177Y    R180 S1      
327m6859            J33   -78         A01X+008546Y+103459X0205Y0590R090 S1      
317m6859            VIA   -    MD0100PA01X+008546Y+103459X0190Y         S0      
317m6860            VIA   -    MD0080PA01X+033949Y+103443X0160Y         S0      
327m6860            U26   -BH65       A01X+034133Y+103339X0177Y    R180 S1      
327m6860            J33   -221        A01X+006932Y+103124X0205Y0590R090 S1      
317m6860            VIA   -    MD0100PA01X+006932Y+103124X0190Y         S0      
317m6861            VIA   -    MD0080PA01X+033764Y+103124X0160Y         S0      
327m6861            U26   -BG66       A01X+033948Y+103020X0177Y    R180 S1      
327m6861            J33   -76         A01X+008546Y+102790X0205Y0590R090 S1      
317m6861            VIA   -    MD0100PA01X+008546Y+102790X0190Y         S0      
317m6862            VIA   -    MD0080PA01X+033764Y+105038X0160Y         S0      
327m6862            U26   -BN66       A01X+033948Y+104933X0177Y    R180 S1      
327m6862            J33   -86         A01X+008546Y+106136X0205Y0590R090 S1      
317m6862            VIA   -    MD0100PA01X+008546Y+106136X0190Y         S0      
317m6863            VIA   -    MD0080PA01X+033646Y+100718X0160Y    R180 S0      
327m6863            U26   -BC66       A01X+033830Y+100823X0177Y    R180 S1      
327m6863            J33   -74         A01X+008546Y+100112X0205Y0590R090 S1      
317m6863            VIA   -    MD0100PA01X+008546Y+100112X0190Y         S0      
317m6864            VIA   -    MD0080PA01X+033646Y+097529X0160Y    R180 S0      
327m6864            U26   -AN66       A01X+033830Y+097634X0177Y    R180 S1      
327m6864            J33   -201        A01X+006932Y+094423X0205Y0590R090 S1      
317m6864            VIA   -    MD0100PA01X+006932Y+094423X0190Y         S0      
317m6865            VIA   -    MD0080PA01X+033646Y+095616X0160Y    R180 S0      
327m6865            U26   -AG66       A01X+033830Y+095721X0177Y    R180 S1      
327m6865            J33   -190        A01X+006932Y+090742X0205Y0590R090 S1      
317m6865            VIA   -    MD0100PA01X+006932Y+090742X0190Y         S0      
317m6866            VIA   -    MD0080PA01X+033646Y+093702X0160Y    R180 S0      
327m6866            U26   -AA66       A01X+033830Y+093807X0177Y    R180 S1      
327m6866            J33   -179        A01X+006932Y+087061X0205Y0590R090 S1      
317m6866            VIA   -    MD0100PA01X+006932Y+087061X0190Y         S0      
317m6867            VIA   -    MD0080PA01X+033646Y+091789X0160Y    R180 S0      
327m6867            U26   -R66        A01X+033830Y+091894X0177Y    R180 S1      
327m6867            J33   -168        A01X+006932Y+083380X0205Y0590R090 S1      
317m6867            VIA   -    MD0100PA01X+006932Y+083380X0190Y         S0      
317m6868            VIA   -    MD0080PA01X+033646Y+089876X0160Y    R180 S0      
327m6868            U26   -J66        A01X+033830Y+089980X0177Y    R180 S1      
327m6868            J33   -157        A01X+006932Y+079699X0205Y0590R090 S1      
317m6868            VIA   -    MD0100PA01X+006932Y+079699X0190Y         S0      
317m6869            VIA   -    MD0080PA01X+033276Y+096892X0160Y    R180 S0      
327m6869            U26   -AL67       A01X+033460Y+096996X0177Y    R180 S1      
327m6869            J33   -55         A01X+008546Y+093754X0205Y0590R090 S1      
317m6869            VIA   -    MD0100PA01X+008546Y+093754X0190Y         S0      
317m6870            VIA   -    MD0080PA01X+033276Y+094978X0160Y    R180 S0      
327m6870            U26   -AE67       A01X+033460Y+095083X0177Y    R180 S1      
327m6870            J33   -44         A01X+008546Y+090073X0205Y0590R090 S1      
317m6870            VIA   -    MD0100PA01X+008546Y+090073X0190Y         S0      
317m6871            VIA   -    MD0080PA01X+033276Y+093065X0160Y    R180 S0      
327m6871            U26   -W67        A01X+033460Y+093169X0177Y    R180 S1      
327m6871            J33   -33         A01X+008546Y+086392X0205Y0590R090 S1      
317m6871            VIA   -    MD0100PA01X+008546Y+086392X0190Y         S0      
317m6872            VIA   -    MD0080PA01X+033276Y+091151X0160Y    R180 S0      
327m6872            U26   -N67        A01X+033460Y+091256X0177Y    R180 S1      
327m6872            J33   -22         A01X+008546Y+082711X0205Y0590R090 S1      
317m6872            VIA   -    MD0100PA01X+008546Y+082711X0190Y         S0      
317m6873            VIA   -    MD0080PA01X+033276Y+089238X0160Y    R180 S0      
327m6873            U26   -G67        A01X+033460Y+089343X0177Y    R180 S1      
327m6873            J33   -11         A01X+008546Y+079030X0205Y0590R090 S1      
317m6873            VIA   -    MD0100PA01X+008546Y+079030X0190Y         S0      
317m6874            VIA   -    MD0080PA01X+033831Y+097210X0160Y    R180 S0      
327m6874            U26   -AM65       A01X+034015Y+097315X0177Y    R180 S1      
327m6874            J33   -200        A01X+006932Y+094089X0205Y0590R090 S1      
317m6874            VIA   -    MD0100PA01X+006932Y+094089X0190Y         S0      
317m6875            VIA   -    MD0080PA01X+033831Y+095297X0160Y    R180 S0      
327m6875            U26   -AF65       A01X+034015Y+095402X0177Y    R180 S1      
327m6875            J33   -189        A01X+006932Y+090408X0205Y0590R090 S1      
317m6875            VIA   -    MD0100PA01X+006932Y+090408X0190Y         S0      
317m6876            VIA   -    MD0080PA01X+033831Y+093384X0160Y    R180 S0      
327m6876            U26   -Y65        A01X+034015Y+093488X0177Y    R180 S1      
327m6876            J33   -178        A01X+006932Y+086726X0205Y0590R090 S1      
317m6876            VIA   -    MD0100PA01X+006932Y+086726X0190Y         S0      
317m6877            VIA   -    MD0080PA01X+033831Y+091470X0160Y    R180 S0      
327m6877            U26   -P65        A01X+034015Y+091575X0177Y    R180 S1      
327m6877            J33   -167        A01X+006932Y+083045X0205Y0590R090 S1      
317m6877            VIA   -    MD0100PA01X+006932Y+083045X0190Y         S0      
317m6878            VIA   -    MD0080PA01X+033831Y+089557X0160Y    R180 S0      
327m6878            U26   -H65        A01X+034015Y+089662X0177Y    R180 S1      
327m6878            J33   -156        A01X+006932Y+079364X0205Y0590R090 S1      
317m6878            VIA   -    MD0100PA01X+006932Y+079364X0190Y         S0      
317m6879            VIA   -    MD0080PA01X+033091Y+097210X0160Y    R180 S0      
327m6879            U26   -AM67       A01X+033275Y+097315X0177Y    R180 S1      
327m6879            J33   -56         A01X+008546Y+094089X0205Y0590R090 S1      
317m6879            VIA   -    MD0100PA01X+008546Y+094089X0190Y         S0      
317m6880            VIA   -    MD0080PA01X+033091Y+095297X0160Y    R180 S0      
327m6880            U26   -AF67       A01X+033275Y+095402X0177Y    R180 S1      
327m6880            J33   -45         A01X+008546Y+090408X0205Y0590R090 S1      
317m6880            VIA   -    MD0100PA01X+008546Y+090408X0190Y         S0      
317m6881            VIA   -    MD0080PA01X+033091Y+093384X0160Y    R180 S0      
327m6881            U26   -Y67        A01X+033275Y+093488X0177Y    R180 S1      
327m6881            J33   -34         A01X+008546Y+086726X0205Y0590R090 S1      
317m6881            VIA   -    MD0100PA01X+008546Y+086726X0190Y         S0      
317m6882            VIA   -    MD0080PA01X+033091Y+091470X0160Y    R180 S0      
327m6882            U26   -P67        A01X+033275Y+091575X0177Y    R180 S1      
327m6882            J33   -23         A01X+008546Y+083045X0205Y0590R090 S1      
317m6882            VIA   -    MD0100PA01X+008546Y+083045X0190Y         S0      
317m6883            VIA   -    MD0080PA01X+033091Y+089557X0160Y    R180 S0      
327m6883            U26   -H67        A01X+033275Y+089662X0177Y    R180 S1      
327m6883            J33   -12         A01X+008546Y+079364X0205Y0590R090 S1      
317m6883            VIA   -    MD0100PA01X+008546Y+079364X0190Y         S0      
317m6884            VIA   -    MD0080PA01X+033831Y+090832X0160Y    R180 S0      
327m6884            U26   -M65        A01X+034015Y+090937X0177Y    R180 S1      
327m6884            J33   -20         A01X+008546Y+082042X0205Y0590R090 S1      
317m6884            VIA   -    MD0100PA01X+008546Y+082042X0190Y         S0      
317m6885            VIA   -    MD0080PA01X+033276Y+090514X0160Y    R180 S0      
327m6885            U26   -L67        A01X+033460Y+090618X0177Y    R180 S1      
327m6885            J33   -18         A01X+008546Y+081372X0205Y0590R090 S1      
317m6885            VIA   -    MD0100PA01X+008546Y+081372X0190Y         S0      
317m6886            VIA   -    MD0080PA01X+033646Y+090514X0160Y    R180 S0      
327m6886            U26   -L66        A01X+033830Y+090618X0177Y    R180 S1      
327m6886            J33   -161        A01X+006932Y+081038X0205Y0590R090 S1      
317m6886            VIA   -    MD0100PA01X+006932Y+081038X0190Y         S0      
317m6887            VIA   -    MD0080PA01X+033091Y+090195X0160Y    R180 S0      
327m6887            U26   -K67        A01X+033275Y+090299X0177Y    R180 S1      
327m6887            J33   -159        A01X+006932Y+080368X0205Y0590R090 S1      
317m6887            VIA   -    MD0100PA01X+006932Y+080368X0190Y         S0      
317m6888            VIA   -    MD0080PA01X+033831Y+090195X0160Y    R180 S0      
327m6888            U26   -K65        A01X+034015Y+090299X0177Y    R180 S1      
327m6888            J33   -16         A01X+008546Y+080703X0205Y0590R090 S1      
317m6888            VIA   -    MD0100PA01X+008546Y+080703X0190Y         S0      
317m6889            VIA   -    MD0080PA01X+033276Y+089876X0160Y    R180 S0      
327m6889            U26   -J67        A01X+033460Y+089980X0177Y    R180 S1      
327m6889            J33   -14         A01X+008546Y+080034X0205Y0590R090 S1      
317m6889            VIA   -    MD0100PA01X+008546Y+080034X0190Y         S0      
317m6890            VIA   -    MD0080PA01X+033646Y+089238X0160Y    R180 S0      
327m6890            U26   -G66        A01X+033830Y+089343X0177Y    R180 S1      
327m6890            J33   -154        A01X+006932Y+078695X0205Y0590R090 S1      
317m6890            VIA   -    MD0100PA01X+006932Y+078695X0190Y         S0      
317m6891            VIA   -    MD0080PA01X+033646Y+096254X0160Y    R180 S0      
327m6891            U26   -AJ66       A01X+033830Y+096358X0177Y    R180 S1      
327m6891            J33   -194        A01X+006932Y+092081X0205Y0590R090 S1      
317m6891            VIA   -    MD0100PA01X+006932Y+092081X0190Y         S0      
317m6892            VIA   -    MD0080PA01X+033091Y+095935X0160Y    R180 S0      
327m6892            U26   -AH67       A01X+033275Y+096040X0177Y    R180 S1      
327m6892            J33   -192        A01X+006932Y+091412X0205Y0590R090 S1      
317m6892            VIA   -    MD0100PA01X+006932Y+091412X0190Y         S0      
317m6893            VIA   -    MD0080PA01X+033091Y+088919X0160Y    R180 S0      
327m6893            U26   -F67        A01X+033275Y+089024X0177Y    R180 S1      
327m6893            J33   -152        A01X+006932Y+078026X0205Y0590R090 S1      
317m6893            VIA   -    MD0100PA01X+006932Y+078026X0190Y         S0      
317m6894            VIA   -    MD0080PA01X+033831Y+095935X0160Y    R180 S0      
327m6894            U26   -AH65       A01X+034015Y+096040X0177Y    R180 S1      
327m6894            J33   -49         A01X+008546Y+091746X0205Y0590R090 S1      
317m6894            VIA   -    MD0100PA01X+008546Y+091746X0190Y         S0      
317m6895            VIA   -    MD0080PA01X+033276Y+095616X0160Y    R180 S0      
327m6895            U26   -AG67       A01X+033460Y+095721X0177Y    R180 S1      
327m6895            J33   -47         A01X+008546Y+091077X0205Y0590R090 S1      
317m6895            VIA   -    MD0100PA01X+008546Y+091077X0190Y         S0      
317m6896            VIA   -    MD0080PA01X+033646Y+094978X0160Y    R180 S0      
327m6896            U26   -AE66       A01X+033830Y+095083X0177Y    R180 S1      
327m6896            J33   -187        A01X+006932Y+089738X0205Y0590R090 S1      
317m6896            VIA   -    MD0100PA01X+006932Y+089738X0190Y         S0      
317m6897            VIA   -    MD0080PA01X+033091Y+094659X0160Y    R180 S0      
327m6897            U26   -AD67       A01X+033275Y+094764X0177Y    R180 S1      
327m6897            J33   -185        A01X+006932Y+089069X0205Y0590R090 S1      
317m6897            VIA   -    MD0100PA01X+006932Y+089069X0190Y         S0      
317m6898            VIA   -    MD0080PA01X+033831Y+094659X0160Y    R180 S0      
327m6898            U26   -AD65       A01X+034015Y+094764X0177Y    R180 S1      
327m6898            J33   -42         A01X+008546Y+089404X0205Y0590R090 S1      
317m6898            VIA   -    MD0100PA01X+008546Y+089404X0190Y         S0      
317m6899            VIA   -    MD0080PA01X+033276Y+094340X0160Y    R180 S0      
327m6899            U26   -AC67       A01X+033460Y+094445X0177Y    R180 S1      
327m6899            J33   -40         A01X+008546Y+088734X0205Y0590R090 S1      
317m6899            VIA   -    MD0100PA01X+008546Y+088734X0190Y         S0      
317m6900            VIA   -    MD0080PA01X+033646Y+094340X0160Y    R180 S0      
327m6900            U26   -AC66       A01X+033830Y+094445X0177Y    R180 S1      
327m6900            J33   -183        A01X+006932Y+088400X0205Y0590R090 S1      
317m6900            VIA   -    MD0100PA01X+006932Y+088400X0190Y         S0      
317m6901            VIA   -    MD0080PA01X+033091Y+094021X0160Y    R180 S0      
327m6901            U26   -AB67       A01X+033275Y+094126X0177Y    R180 S1      
327m6901            J33   -181        A01X+006932Y+087730X0205Y0590R090 S1      
317m6901            VIA   -    MD0100PA01X+006932Y+087730X0190Y         S0      
317m6902            VIA   -    MD0080PA01X+033831Y+094021X0160Y    R180 S0      
327m6902            U26   -AB65       A01X+034015Y+094126X0177Y    R180 S1      
327m6902            J33   -38         A01X+008546Y+088065X0205Y0590R090 S1      
317m6902            VIA   -    MD0100PA01X+008546Y+088065X0190Y         S0      
317m6903            VIA   -    MD0080PA01X+033276Y+093702X0160Y    R180 S0      
327m6903            U26   -AA67       A01X+033460Y+093807X0177Y    R180 S1      
327m6903            J33   -36         A01X+008546Y+087396X0205Y0590R090 S1      
317m6903            VIA   -    MD0100PA01X+008546Y+087396X0190Y         S0      
317m6904            VIA   -    MD0080PA01X+033831Y+088919X0160Y    R180 S0      
327m6904            U26   -F65        A01X+034015Y+089024X0177Y    R180 S1      
327m6904            J33   -9          A01X+008546Y+078360X0205Y0590R090 S1      
317m6904            VIA   -    MD0100PA01X+008546Y+078360X0190Y         S0      
317m6905            VIA   -    MD0080PA01X+033646Y+093065X0160Y    R180 S0      
327m6905            U26   -W66        A01X+033830Y+093169X0177Y    R180 S1      
327m6905            J33   -176        A01X+006932Y+086057X0205Y0590R090 S1      
317m6905            VIA   -    MD0100PA01X+006932Y+086057X0190Y         S0      
317m6906            VIA   -    MD0080PA01X+033091Y+092746X0160Y    R180 S0      
327m6906            U26   -V67        A01X+033275Y+092850X0177Y    R180 S1      
327m6906            J33   -174        A01X+006932Y+085388X0205Y0590R090 S1      
317m6906            VIA   -    MD0100PA01X+006932Y+085388X0190Y         S0      
317m6907            VIA   -    MD0080PA01X+033831Y+092746X0160Y    R180 S0      
327m6907            U26   -V65        A01X+034015Y+092850X0177Y    R180 S1      
327m6907            J33   -31         A01X+008546Y+085723X0205Y0590R090 S1      
317m6907            VIA   -    MD0100PA01X+008546Y+085723X0190Y         S0      
317m6908            VIA   -    MD0080PA01X+033276Y+092427X0160Y    R180 S0      
327m6908            U26   -U67        A01X+033460Y+092532X0177Y    R180 S1      
327m6908            J33   -29         A01X+008546Y+085053X0205Y0590R090 S1      
317m6908            VIA   -    MD0100PA01X+008546Y+085053X0190Y         S0      
317m6909            VIA   -    MD0080PA01X+033646Y+092427X0160Y    R180 S0      
327m6909            U26   -U66        A01X+033830Y+092532X0177Y    R180 S1      
327m6909            J33   -172        A01X+006932Y+084719X0205Y0590R090 S1      
317m6909            VIA   -    MD0100PA01X+006932Y+084719X0190Y         S0      
317m6910            VIA   -    MD0080PA01X+033091Y+092108X0160Y    R180 S0      
327m6910            U26   -T67        A01X+033275Y+092213X0177Y    R180 S1      
327m6910            J33   -170        A01X+006932Y+084049X0205Y0590R090 S1      
317m6910            VIA   -    MD0100PA01X+006932Y+084049X0190Y         S0      
317m6911            VIA   -    MD0080PA01X+033831Y+092108X0160Y    R180 S0      
327m6911            U26   -T65        A01X+034015Y+092213X0177Y    R180 S1      
327m6911            J33   -27         A01X+008546Y+084384X0205Y0590R090 S1      
317m6911            VIA   -    MD0100PA01X+008546Y+084384X0190Y         S0      
317m6912            VIA   -    MD0080PA01X+033276Y+091789X0160Y    R180 S0      
327m6912            U26   -R67        A01X+033460Y+091894X0177Y    R180 S1      
327m6912            J33   -25         A01X+008546Y+083715X0205Y0590R090 S1      
317m6912            VIA   -    MD0100PA01X+008546Y+083715X0190Y         S0      
317m6913            VIA   -    MD0080PA01X+033646Y+091151X0160Y    R180 S0      
327m6913            U26   -N66        A01X+033830Y+091256X0177Y    R180 S1      
327m6913            J33   -165        A01X+006932Y+082376X0205Y0590R090 S1      
317m6913            VIA   -    MD0100PA01X+006932Y+082376X0190Y         S0      
317m6914            VIA   -    MD0080PA01X+033091Y+090832X0160Y    R180 S0      
327m6914            U26   -M67        A01X+033275Y+090937X0177Y    R180 S1      
327m6914            J33   -163        A01X+006932Y+081707X0205Y0590R090 S1      
317m6914            VIA   -    MD0100PA01X+006932Y+081707X0190Y         S0      
317m6915            VIA   -    MD0080PA01X+033276Y+088600X0160Y    R180 S0      
327m6915            U26   -E67        A01X+033460Y+088705X0177Y    R180 S1      
327m6915            J33   -7          A01X+008546Y+077691X0205Y0590R090 S1      
317m6915            VIA   -    MD0100PA01X+008546Y+077691X0190Y         S0      
317m6916            VIA   -    MD0080PA01X+033646Y+099443X0160Y    R180 S0      
327m6916            U26   -AW66       A01X+033830Y+099547X0177Y    R180 S1      
327m6916            J33   -209        A01X+006932Y+097100X0205Y0590R090 S1      
317m6916            VIA   -    MD0100PA01X+006932Y+097100X0190Y         S0      
317m6917            VIA   -    MD0080PA01X+033091Y+099124X0160Y    R180 S0      
327m6917            U26   -AV67       A01X+033275Y+099228X0177Y    R180 S1      
327m6917            J33   -64         A01X+008546Y+096766X0205Y0590R090 S1      
317m6917            VIA   -    MD0100PA01X+008546Y+096766X0190Y         S0      
317m6918            VIA   -    MD0080PA01X+033646Y+098167X0160Y    R180 S0      
327m6918            U26   -AR66       A01X+033830Y+098272X0177Y    R180 S1      
327m6918            J33   -205        A01X+006932Y+095762X0205Y0590R090 S1      
317m6918            VIA   -    MD0100PA01X+006932Y+095762X0190Y         S0      
317m6919            VIA   -    MD0080PA01X+033091Y+097848X0160Y    R180 S0      
327m6919            U26   -AP67       A01X+033275Y+097953X0177Y    R180 S1      
327m6919            J33   -203        A01X+006932Y+095093X0205Y0590R090 S1      
317m6919            VIA   -    MD0100PA01X+006932Y+095093X0190Y         S0      
317m6920            VIA   -    MD0080PA01X+033831Y+097848X0160Y    R180 S0      
327m6920            U26   -AP65       A01X+034015Y+097953X0177Y    R180 S1      
327m6920            J33   -60         A01X+008546Y+095427X0205Y0590R090 S1      
317m6920            VIA   -    MD0100PA01X+008546Y+095427X0190Y         S0      
317m6921            VIA   -    MD0080PA01X+033276Y+097529X0160Y    R180 S0      
327m6921            U26   -AN67       A01X+033460Y+097634X0177Y    R180 S1      
327m6921            J33   -58         A01X+008546Y+094758X0205Y0590R090 S1      
317m6921            VIA   -    MD0100PA01X+008546Y+094758X0190Y         S0      
317m6922            VIA   -    MD0080PA01X+033646Y+096892X0160Y    R180 S0      
327m6922            U26   -AL66       A01X+033830Y+096996X0177Y    R180 S1      
327m6922            J33   -198        A01X+006932Y+093419X0205Y0590R090 S1      
317m6922            VIA   -    MD0100PA01X+006932Y+093419X0190Y         S0      
317m6923            VIA   -    MD0080PA01X+033091Y+096573X0160Y    R180 S0      
327m6923            U26   -AK67       A01X+033275Y+096677X0177Y    R180 S1      
327m6923            J33   -196        A01X+006932Y+092750X0205Y0590R090 S1      
317m6923            VIA   -    MD0100PA01X+006932Y+092750X0190Y         S0      
317m6924            VIA   -    MD0080PA01X+033831Y+096573X0160Y    R180 S0      
327m6924            U26   -AK65       A01X+034015Y+096677X0177Y    R180 S1      
327m6924            J33   -53         A01X+008546Y+093085X0205Y0590R090 S1      
317m6924            VIA   -    MD0100PA01X+008546Y+093085X0190Y         S0      
317m6925            VIA   -    MD0080PA01X+033276Y+096254X0160Y    R180 S0      
327m6925            U26   -AJ67       A01X+033460Y+096358X0177Y    R180 S1      
327m6925            J33   -51         A01X+008546Y+092416X0205Y0590R090 S1      
317m6925            VIA   -    MD0100PA01X+008546Y+092416X0190Y         S0      
317m6926            VIA   -    MD0080PA01X+033831Y+100399X0160Y    R180 S0      
327m6926            U26   -BB65       A01X+034015Y+100504X0177Y    R180 S1      
327m6926            J33   -72         A01X+008546Y+099443X0205Y0590R090 S1      
317m6926            VIA   -    MD0100PA01X+008546Y+099443X0190Y         S0      
317m6927            VIA   -    MD0080PA01X+033091Y+100399X0160Y    R180 S0      
327m6927            U26   -BB67       A01X+033275Y+100504X0177Y    R180 S1      
327m6927            J33   -215        A01X+006932Y+099108X0205Y0590R090 S1      
317m6927            VIA   -    MD0100PA01X+006932Y+099108X0190Y         S0      
317m6928            VIA   -    MD0080PA01X+033276Y+100080X0160Y    R180 S0      
327m6928            U26   -BA67       A01X+033460Y+100185X0177Y    R180 S1      
327m6928            J33   -70         A01X+008546Y+098774X0205Y0590R090 S1      
317m6928            VIA   -    MD0100PA01X+008546Y+098774X0190Y         S0      
317m6929            VIA   -    MD0080PA01X+033646Y+100080X0160Y    R180 S0      
327m6929            U26   -BA66       A01X+033830Y+100185X0177Y    R180 S1      
327m6929            J33   -213        A01X+006932Y+098439X0205Y0590R090 S1      
317m6929            VIA   -    MD0100PA01X+006932Y+098439X0190Y         S0      
317m6930            VIA   -    MD0080PA01X+033831Y+099762X0160Y    R180 S0      
327m6930            U26   -AY65       A01X+034015Y+099866X0177Y    R180 S1      
327m6930            J33   -68         A01X+008546Y+098104X0205Y0590R090 S1      
317m6930            VIA   -    MD0100PA01X+008546Y+098104X0190Y         S0      
317m6931            VIA   -    MD0080PA01X+033091Y+099762X0160Y    R180 S0      
327m6931            U26   -AY67       A01X+033275Y+099866X0177Y    R180 S1      
327m6931            J33   -211        A01X+006932Y+097770X0205Y0590R090 S1      
317m6931            VIA   -    MD0100PA01X+006932Y+097770X0190Y         S0      
317m6932            VIA   -    MD0080PA01X+033276Y+099443X0160Y    R180 S0      
327m6932            U26   -AW67       A01X+033460Y+099547X0177Y    R180 S1      
327m6932            J33   -66         A01X+008546Y+097435X0205Y0590R090 S1      
317m6932            VIA   -    MD0100PA01X+008546Y+097435X0190Y         S0      
317m6933            VIA   -    MD0080PA01X+033646Y+098805X0160Y    R180 S0      
327m6933            U26   -AU66       A01X+033830Y+098910X0177Y    R180 S1      
327m6933            J33   -207        A01X+006932Y+096431X0205Y0590R090 S1      
317m6933            VIA   -    MD0100PA01X+006932Y+096431X0190Y         S0      
317m6934            VIA   -    MD0080PA01X+033276Y+100718X0160Y    R180 S0      
327m6934            U26   -BC67       A01X+033460Y+100823X0177Y    R180 S1      
327m6934            J33   -217        A01X+006932Y+099778X0205Y0590R090 S1      
317m6934            VIA   -    MD0100PA01X+006932Y+099778X0190Y         S0      
317m6935            VIA   -    MD0080PA01X+033091Y+101037X0160Y    R180 S0      
327m6935            U26   -BD67       A01X+033275Y+101142X0177Y    R180 S1      
327m6935            J33   -218        A01X+006932Y+100112X0205Y0590R090 S1      
317m6935            VIA   -    MD0100PA01X+006932Y+100112X0190Y         S0      
317m6936            VIA   -    MD0080PA01X+033831Y+098486X0160Y    R180 S0      
327m6936            U26   -AT65       A01X+034015Y+098591X0177Y    R180 S1      
327m6936            R505  -2          A18X+009096Y+096097X0198Y0197R180 S2      
317m6936            VIA   -    MD0100PA18X+009096Y+096097X0190Y    R180 S0      
327m6937            J33   -62         A01X+008546Y+096097X0205Y0590R090 S1      
317m6937            VIA   -    MD0100PA00X+008546Y+096097X0190Y         S0      
327m6937            R505  -1          A18X+008782Y+096097X0198Y0197R180 S2      
317m6938            VIA   -    MD0080PA01X+130823Y+105357X0160Y         S0      
327m6938            U25   -BP67       A01X+131007Y+105252X0177Y    R180 S1      
317m6938            VIA   -    MD0100PA01X+106161Y+106470X0190Y         S0      
327m6938            J23   -87         A01X+106161Y+106470X0205Y0590R090 S1      
317m6939            VIA   -    MD0080PA01X+131008Y+104400X0160Y         S0      
327m6939            U25   -BL67       A01X+131192Y+104295X0177Y    R180 S1      
317m6939            VIA   -    MD0100PA01X+104546Y+105132X0190Y         S0      
327m6939            J23   -227        A01X+104546Y+105132X0205Y0590R090 S1      
317m6940            VIA   -    MD0080PA01X+130823Y+106632X0160Y         S0      
327m6940            U25   -BV67       A01X+131007Y+106528X0177Y    R180 S1      
317m6940            VIA   -    MD0100PA01X+106161Y+108478X0190Y         S0      
327m6940            J23   -93         A01X+106161Y+108478X0205Y0590R090 S1      
317m6941            VIA   -    MD0080PA01X+131563Y+114924X0160Y         S0      
327m6941            U25   -DD65       A01X+131747Y+114819X0177Y    R180 S1      
317m6941            VIA   -    MD0100PA01X+104546Y+123872X0190Y         S0      
327m6941            J23   -283        A01X+104546Y+123872X0205Y0590R090 S1      
317m6942            VIA   -    MD0080PA01X+131563Y+113010X0160Y         S0      
317m6942            VIA   -    MD0100PA01X+104546Y+120191X0190Y         S0      
327m6942            J23   -272        A01X+104546Y+120191X0205Y0590R090 S1      
327m6942            U25   -CV65       A01X+131747Y+112906X0177Y    R180 S1      
317m6943            VIA   -    MD0080PA01X+131563Y+111097X0160Y         S0      
327m6943            U25   -CM65       A01X+131747Y+110992X0177Y    R180 S1      
317m6943            VIA   -    MD0100PA01X+104546Y+116510X0190Y         S0      
327m6943            J23   -261        A01X+104546Y+116510X0205Y0590R090 S1      
317m6944            VIA   -    MD0080PA01X+131563Y+109184X0160Y         S0      
327m6944            U25   -CF65       A01X+131747Y+109079X0177Y    R180 S1      
317m6944            VIA   -    MD0100PA01X+104546Y+112829X0190Y         S0      
327m6944            J23   -250        A01X+104546Y+112829X0205Y0590R090 S1      
317m6945            VIA   -    MD0080PA01X+131563Y+107270X0160Y         S0      
327m6945            U25   -BY65       A01X+131747Y+107165X0177Y    R180 S1      
317m6945            VIA   -    MD0100PA01X+104546Y+109148X0190Y         S0      
327m6945            J23   -239        A01X+104546Y+109148X0205Y0590R090 S1      
317m6946            VIA   -    MD0080PA01X+130823Y+114286X0160Y         S0      
317m6946            VIA   -    MD0100PA01X+106161Y+123203X0190Y         S0      
327m6946            J23   -137        A01X+106161Y+123203X0205Y0590R090 S1      
327m6946            U25   -DB67       A01X+131007Y+114181X0177Y    R180 S1      
317m6947            VIA   -    MD0080PA01X+130823Y+112372X0160Y         S0      
317m6947            VIA   -    MD0100PA01X+106161Y+119522X0190Y         S0      
327m6947            J23   -126        A01X+106161Y+119522X0205Y0590R090 S1      
327m6947            U25   -CT67       A01X+131007Y+112268X0177Y    R180 S1      
317m6948            VIA   -    MD0080PA01X+130823Y+110459X0160Y         S0      
327m6948            U25   -CK67       A01X+131007Y+110354X0177Y    R180 S1      
327m6948            J23   -115        A01X+106161Y+115841X0205Y0590R090 S1      
317m6948            VIA   -    MD0100PA01X+106161Y+115841X0190Y         S0      
317m6949            VIA   -    MD0080PA01X+130823Y+108546X0160Y         S0      
327m6949            U25   -CD67       A01X+131007Y+108441X0177Y    R180 S1      
317m6949            VIA   -    MD0100PA01X+106161Y+112160X0190Y         S0      
327m6949            J23   -104        A01X+106161Y+112160X0205Y0590R090 S1      
317m6950            VIA   -    MD0080PA01X+131008Y+106951X0160Y         S0      
327m6950            U25   -BW67       A01X+131192Y+106846X0177Y    R180 S1      
317m6950            VIA   -    MD0100PA01X+106161Y+108813X0190Y         S0      
327m6950            J23   -94         A01X+106161Y+108813X0205Y0590R090 S1      
317m6951            VIA   -    MD0080PA01X+131378Y+114605X0160Y         S0      
327m6951            U25   -DC66       A01X+131562Y+114500X0177Y    R180 S1      
317m6951            VIA   -    MD0100PA01X+104546Y+123537X0190Y         S0      
327m6951            J23   -282        A01X+104546Y+123537X0205Y0590R090 S1      
317m6952            VIA   -    MD0080PA01X+131378Y+112691X0160Y         S0      
317m6952            VIA   -    MD0100PA01X+104546Y+119856X0190Y         S0      
327m6952            J23   -271        A01X+104546Y+119856X0205Y0590R090 S1      
327m6952            U25   -CU66       A01X+131562Y+112587X0177Y    R180 S1      
317m6953            VIA   -    MD0080PA01X+131378Y+110778X0160Y         S0      
327m6953            U25   -CL66       A01X+131562Y+110673X0177Y    R180 S1      
317m6953            VIA   -    MD0100PA01X+104546Y+116175X0190Y         S0      
327m6953            J23   -260        A01X+104546Y+116175X0205Y0590R090 S1      
317m6954            VIA   -    MD0080PA01X+131378Y+108865X0160Y         S0      
327m6954            U25   -CE66       A01X+131562Y+108760X0177Y    R180 S1      
317m6954            VIA   -    MD0100PA01X+104546Y+112494X0190Y         S0      
327m6954            J23   -249        A01X+104546Y+112494X0205Y0590R090 S1      
317m6955            VIA   -    MD0080PA01X+131378Y+106951X0160Y         S0      
327m6955            U25   -BW66       A01X+131562Y+106846X0177Y    R180 S1      
317m6955            VIA   -    MD0100PA01X+104546Y+108813X0190Y         S0      
327m6955            J23   -238        A01X+104546Y+108813X0205Y0590R090 S1      
317m6956            VIA   -    MD0080PA01X+131008Y+114605X0160Y         S0      
317m6956            VIA   -    MD0100PA01X+106161Y+123537X0190Y         S0      
327m6956            J23   -138        A01X+106161Y+123537X0205Y0590R090 S1      
327m6956            U25   -DC67       A01X+131192Y+114500X0177Y    R180 S1      
317m6957            VIA   -    MD0080PA01X+131008Y+112691X0160Y         S0      
317m6957            VIA   -    MD0100PA01X+106161Y+119856X0190Y         S0      
327m6957            J23   -127        A01X+106161Y+119856X0205Y0590R090 S1      
327m6957            U25   -CU67       A01X+131192Y+112587X0177Y    R180 S1      
317m6958            VIA   -    MD0080PA01X+131008Y+110778X0160Y         S0      
327m6958            U25   -CL67       A01X+131192Y+110673X0177Y    R180 S1      
327m6958            J23   -116        A01X+106161Y+116175X0205Y0590R090 S1      
317m6958            VIA   -    MD0100PA01X+106161Y+116175X0190Y         S0      
317m6959            VIA   -    MD0080PA01X+131008Y+108865X0160Y         S0      
327m6959            U25   -CE67       A01X+131192Y+108760X0177Y    R180 S1      
317m6959            VIA   -    MD0100PA01X+106161Y+112494X0190Y         S0      
327m6959            J23   -105        A01X+106161Y+112494X0205Y0590R090 S1      
317m6960            VIA   -    MD0080PA01X+131378Y+110140X0160Y         S0      
327m6960            U25   -CJ66       A01X+131562Y+110036X0177Y    R180 S1      
317m6960            VIA   -    MD0100PA01X+106161Y+115171X0190Y         S0      
327m6960            J23   -113        A01X+106161Y+115171X0205Y0590R090 S1      
317m6961            VIA   -    MD0080PA01X+130823Y+109821X0160Y         S0      
327m6961            U25   -CH67       A01X+131007Y+109717X0177Y    R180 S1      
317m6961            VIA   -    MD0100PA01X+106161Y+114502X0190Y         S0      
327m6961            J23   -111        A01X+106161Y+114502X0205Y0590R090 S1      
317m6962            VIA   -    MD0080PA01X+131563Y+109821X0160Y         S0      
327m6962            U25   -CH65       A01X+131747Y+109717X0177Y    R180 S1      
317m6962            VIA   -    MD0100PA01X+104546Y+114167X0190Y         S0      
327m6962            J23   -254        A01X+104546Y+114167X0205Y0590R090 S1      
317m6963            VIA   -    MD0080PA01X+131008Y+109502X0160Y         S0      
327m6963            U25   -CG67       A01X+131192Y+109398X0177Y    R180 S1      
317m6963            VIA   -    MD0100PA01X+104546Y+113498X0190Y         S0      
327m6963            J23   -252        A01X+104546Y+113498X0205Y0590R090 S1      
317m6964            VIA   -    MD0080PA01X+131378Y+109502X0160Y         S0      
327m6964            U25   -CG66       A01X+131562Y+109398X0177Y    R180 S1      
317m6964            VIA   -    MD0100PA01X+106161Y+113833X0190Y         S0      
327m6964            J23   -109        A01X+106161Y+113833X0205Y0590R090 S1      
317m6965            VIA   -    MD0080PA01X+130823Y+109184X0160Y         S0      
327m6965            U25   -CF67       A01X+131007Y+109079X0177Y    R180 S1      
317m6965            VIA   -    MD0100PA01X+106161Y+113163X0190Y         S0      
327m6965            J23   -107        A01X+106161Y+113163X0205Y0590R090 S1      
317m6966            VIA   -    MD0080PA01X+131563Y+108546X0160Y         S0      
327m6966            U25   -CD65       A01X+131747Y+108441X0177Y    R180 S1      
317m6966            VIA   -    MD0100PA01X+104546Y+111825X0190Y         S0      
327m6966            J23   -247        A01X+104546Y+111825X0205Y0590R090 S1      
317m6967            VIA   -    MD0080PA01X+130823Y+115561X0160Y         S0      
327m6967            U25   -DF67       A01X+131007Y+115457X0177Y    R180 S1      
317m6967            VIA   -    MD0100PA01X+104546Y+125211X0190Y         S0      
327m6967            J23   -287        A01X+104546Y+125211X0205Y0590R090 S1      
317m6968            VIA   -    MD0080PA01X+131008Y+115242X0160Y         S0      
317m6968            VIA   -    MD0100PA01X+104546Y+124541X0190Y         S0      
327m6968            J23   -285        A01X+104546Y+124541X0205Y0590R090 S1      
327m6968            U25   -DE67       A01X+131192Y+115138X0177Y    R180 S1      
317m6969            VIA   -    MD0080PA01X+131008Y+108227X0160Y         S0      
327m6969            U25   -CC67       A01X+131192Y+108122X0177Y    R180 S1      
317m6969            VIA   -    MD0100PA01X+104546Y+111156X0190Y         S0      
327m6969            J23   -245        A01X+104546Y+111156X0205Y0590R090 S1      
317m6970            VIA   -    MD0080PA01X+131378Y+115242X0160Y         S0      
317m6970            VIA   -    MD0100PA01X+106161Y+124876X0190Y         S0      
327m6970            J23   -142        A01X+106161Y+124876X0205Y0590R090 S1      
327m6970            U25   -DE66       A01X+131562Y+115138X0177Y    R180 S1      
317m6971            VIA   -    MD0080PA01X+130823Y+114924X0160Y         S0      
317m6971            VIA   -    MD0100PA01X+106161Y+124207X0190Y         S0      
327m6971            J23   -140        A01X+106161Y+124207X0205Y0590R090 S1      
327m6971            U25   -DD67       A01X+131007Y+114819X0177Y    R180 S1      
317m6972            VIA   -    MD0080PA01X+131563Y+114286X0160Y         S0      
327m6972            J23   -280        A01X+104546Y+122868X0205Y0590R090 S1      
317m6972            VIA   -    MD0100PA01X+104546Y+122868X0190Y         S0      
327m6972            U25   -DB65       A01X+131747Y+114181X0177Y    R180 S1      
317m6973            VIA   -    MD0080PA01X+131008Y+113967X0160Y         S0      
317m6973            VIA   -    MD0100PA01X+104546Y+122199X0190Y         S0      
327m6973            J23   -278        A01X+104546Y+122199X0205Y0590R090 S1      
327m6973            U25   -DA67       A01X+131192Y+113862X0177Y    R180 S1      
317m6974            VIA   -    MD0080PA01X+131378Y+113967X0160Y         S0      
327m6974            J23   -135        A01X+106161Y+122534X0205Y0590R090 S1      
317m6974            VIA   -    MD0100PA01X+106161Y+122534X0190Y         S0      
327m6974            U25   -DA66       A01X+131562Y+113862X0177Y    R180 S1      
317m6975            VIA   -    MD0080PA01X+130823Y+113648X0160Y         S0      
317m6975            VIA   -    MD0100PA01X+106161Y+121864X0190Y         S0      
327m6975            J23   -133        A01X+106161Y+121864X0205Y0590R090 S1      
327m6975            U25   -CY67       A01X+131007Y+113543X0177Y    R180 S1      
317m6976            VIA   -    MD0080PA01X+131563Y+113648X0160Y         S0      
327m6976            U25   -CY65       A01X+131747Y+113543X0177Y    R180 S1      
317m6976            VIA   -    MD0100PA01X+104546Y+121530X0190Y         S0      
327m6976            J23   -276        A01X+104546Y+121530X0205Y0590R090 S1      
317m6977            VIA   -    MD0080PA01X+131008Y+113329X0160Y         S0      
317m6977            VIA   -    MD0100PA01X+104546Y+120860X0190Y         S0      
327m6977            J23   -274        A01X+104546Y+120860X0205Y0590R090 S1      
327m6977            U25   -CW67       A01X+131192Y+113224X0177Y    R180 S1      
317m6978            VIA   -    MD0080PA01X+131378Y+113329X0160Y         S0      
317m6978            VIA   -    MD0100PA01X+106161Y+121195X0190Y         S0      
327m6978            J23   -131        A01X+106161Y+121195X0205Y0590R090 S1      
327m6978            U25   -CW66       A01X+131562Y+113224X0177Y    R180 S1      
317m6979            VIA   -    MD0080PA01X+130823Y+113010X0160Y         S0      
317m6979            VIA   -    MD0100PA01X+106161Y+120526X0190Y         S0      
327m6979            J23   -129        A01X+106161Y+120526X0205Y0590R090 S1      
327m6979            U25   -CV67       A01X+131007Y+112906X0177Y    R180 S1      
317m6980            VIA   -    MD0080PA01X+131378Y+108227X0160Y         S0      
327m6980            U25   -CC66       A01X+131562Y+108122X0177Y    R180 S1      
317m6980            VIA   -    MD0100PA01X+106161Y+111490X0190Y         S0      
327m6980            J23   -102        A01X+106161Y+111490X0205Y0590R090 S1      
317m6981            VIA   -    MD0080PA01X+131563Y+112372X0160Y         S0      
317m6981            VIA   -    MD0100PA01X+104546Y+119187X0190Y         S0      
327m6981            J23   -269        A01X+104546Y+119187X0205Y0590R090 S1      
327m6981            U25   -CT65       A01X+131747Y+112268X0177Y    R180 S1      
317m6982            VIA   -    MD0080PA01X+131008Y+112054X0160Y         S0      
327m6982            J23   -267        A01X+104546Y+118518X0205Y0590R090 S1      
317m6982            VIA   -    MD0100PA01X+104546Y+118518X0190Y         S0      
327m6982            U25   -CR67       A01X+131192Y+111949X0177Y    R180 S1      
317m6983            VIA   -    MD0080PA01X+131378Y+112054X0160Y         S0      
317m6983            VIA   -    MD0100PA01X+106161Y+118852X0190Y         S0      
327m6983            J23   -124        A01X+106161Y+118852X0205Y0590R090 S1      
327m6983            U25   -CR66       A01X+131562Y+111949X0177Y    R180 S1      
317m6984            VIA   -    MD0080PA01X+130823Y+111735X0160Y         S0      
327m6984            J23   -122        A01X+106161Y+118183X0205Y0590R090 S1      
317m6984            VIA   -    MD0100PA01X+106161Y+118183X0190Y         S0      
327m6984            U25   -CP67       A01X+131007Y+111630X0177Y    R180 S1      
317m6985            VIA   -    MD0080PA01X+131563Y+111735X0160Y         S0      
327m6985            U25   -CP65       A01X+131747Y+111630X0177Y    R180 S1      
317m6985            VIA   -    MD0100PA01X+104546Y+117848X0190Y         S0      
327m6985            J23   -265        A01X+104546Y+117848X0205Y0590R090 S1      
317m6986            VIA   -    MD0080PA01X+131008Y+111416X0160Y         S0      
327m6986            U25   -CN67       A01X+131192Y+111311X0177Y    R180 S1      
317m6986            VIA   -    MD0100PA01X+104546Y+117179X0190Y         S0      
327m6986            J23   -263        A01X+104546Y+117179X0205Y0590R090 S1      
317m6987            VIA   -    MD0080PA01X+131378Y+111416X0160Y         S0      
327m6987            U25   -CN66       A01X+131562Y+111311X0177Y    R180 S1      
317m6987            VIA   -    MD0100PA01X+106161Y+117514X0190Y         S0      
327m6987            J23   -120        A01X+106161Y+117514X0205Y0590R090 S1      
317m6988            VIA   -    MD0080PA01X+130823Y+111097X0160Y         S0      
327m6988            U25   -CM67       A01X+131007Y+110992X0177Y    R180 S1      
317m6988            VIA   -    MD0100PA01X+106161Y+116844X0190Y         S0      
327m6988            J23   -118        A01X+106161Y+116844X0205Y0590R090 S1      
317m6989            VIA   -    MD0080PA01X+131563Y+110459X0160Y         S0      
327m6989            U25   -CK65       A01X+131747Y+110354X0177Y    R180 S1      
317m6989            VIA   -    MD0100PA01X+104546Y+115506X0190Y         S0      
327m6989            J23   -258        A01X+104546Y+115506X0205Y0590R090 S1      
317m6990            VIA   -    MD0080PA01X+131008Y+110140X0160Y         S0      
327m6990            U25   -CJ67       A01X+131192Y+110036X0177Y    R180 S1      
317m6990            VIA   -    MD0100PA01X+104546Y+114837X0190Y         S0      
327m6990            J23   -256        A01X+104546Y+114837X0205Y0590R090 S1      
317m6991            VIA   -    MD0080PA01X+130823Y+107908X0160Y         S0      
327m6991            U25   -CB67       A01X+131007Y+107803X0177Y    R180 S1      
317m6991            VIA   -    MD0100PA01X+106161Y+110821X0190Y         S0      
327m6991            J23   -100        A01X+106161Y+110821X0205Y0590R090 S1      
317m6992            VIA   -    MD0080PA01X+131008Y+105038X0160Y         S0      
327m6992            U25   -BN67       A01X+131192Y+104933X0177Y    R180 S1      
317m6992            VIA   -    MD0100PA01X+104546Y+105801X0190Y         S0      
327m6992            J23   -229        A01X+104546Y+105801X0205Y0590R090 S1      
317m6993            VIA   -    MD0080PA01X+131563Y+104719X0160Y         S0      
327m6993            U25   -BM65       A01X+131747Y+104614X0177Y    R180 S1      
317m6993            VIA   -    MD0100PA01X+106161Y+105467X0190Y         S0      
327m6993            J23   -84         A01X+106161Y+105467X0205Y0590R090 S1      
317m6994            VIA   -    MD0080PA01X+131563Y+106632X0160Y         S0      
327m6994            U25   -BV65       A01X+131747Y+106528X0177Y    R180 S1      
317m6994            VIA   -    MD0100PA01X+104546Y+108144X0190Y         S0      
327m6994            J23   -236        A01X+104546Y+108144X0205Y0590R090 S1      
317m6995            VIA   -    MD0080PA01X+131008Y+106313X0160Y         S0      
327m6995            U25   -BU67       A01X+131192Y+106209X0177Y    R180 S1      
317m6995            VIA   -    MD0100PA01X+104546Y+107474X0190Y         S0      
327m6995            J23   -234        A01X+104546Y+107474X0205Y0590R090 S1      
317m6996            VIA   -    MD0080PA01X+131378Y+106313X0160Y         S0      
327m6996            U25   -BU66       A01X+131562Y+106209X0177Y    R180 S1      
317m6996            VIA   -    MD0100PA01X+106161Y+107809X0190Y         S0      
327m6996            J23   -91         A01X+106161Y+107809X0205Y0590R090 S1      
317m6997            VIA   -    MD0080PA01X+130823Y+105994X0160Y         S0      
327m6997            U25   -BT67       A01X+131007Y+105890X0177Y    R180 S1      
317m6997            VIA   -    MD0100PA01X+106161Y+107140X0190Y         S0      
327m6997            J23   -89         A01X+106161Y+107140X0205Y0590R090 S1      
317m6998            VIA   -    MD0080PA01X+131563Y+107908X0160Y         S0      
327m6998            U25   -CB65       A01X+131747Y+107803X0177Y    R180 S1      
317m6998            VIA   -    MD0100PA01X+104546Y+110486X0190Y         S0      
327m6998            J23   -243        A01X+104546Y+110486X0205Y0590R090 S1      
317m6999            VIA   -    MD0080PA01X+131008Y+107589X0160Y         S0      
327m6999            U25   -CA67       A01X+131192Y+107484X0177Y    R180 S1      
317m6999            VIA   -    MD0100PA01X+104546Y+109817X0190Y         S0      
327m6999            J23   -241        A01X+104546Y+109817X0205Y0590R090 S1      
317m7000            VIA   -    MD0080PA01X+131378Y+107589X0160Y         S0      
327m7000            U25   -CA66       A01X+131562Y+107484X0177Y    R180 S1      
317m7000            VIA   -    MD0100PA01X+106161Y+110152X0190Y         S0      
327m7000            J23   -98         A01X+106161Y+110152X0205Y0590R090 S1      
317m7001            VIA   -    MD0080PA01X+130823Y+107270X0160Y         S0      
327m7001            U25   -BY67       A01X+131007Y+107165X0177Y    R180 S1      
317m7001            VIA   -    MD0100PA01X+106161Y+109482X0190Y         S0      
327m7001            J23   -96         A01X+106161Y+109482X0205Y0590R090 S1      
317m7002            VIA   -    MD0080PA01X+130823Y+104081X0160Y         S0      
327m7002            U25   -BK67       A01X+131007Y+103976X0177Y    R180 S1      
317m7002            VIA   -    MD0100PA01X+106161Y+104797X0190Y         S0      
327m7002            J23   -82         A01X+106161Y+104797X0205Y0590R090 S1      
317m7003            VIA   -    MD0080PA01X+131563Y+104081X0160Y         S0      
327m7003            U25   -BK65       A01X+131747Y+103976X0177Y    R180 S1      
317m7003            VIA   -    MD0100PA01X+104546Y+104463X0190Y         S0      
327m7003            J23   -225        A01X+104546Y+104463X0205Y0590R090 S1      
317m7004            VIA   -    MD0080PA01X+131378Y+103762X0160Y         S0      
327m7004            U25   -BJ66       A01X+131562Y+103658X0177Y    R180 S1      
317m7004            VIA   -    MD0100PA01X+106161Y+104128X0190Y         S0      
327m7004            J23   -80         A01X+106161Y+104128X0205Y0590R090 S1      
317m7005            VIA   -    MD0080PA01X+131008Y+103762X0160Y         S0      
327m7005            U25   -BJ67       A01X+131192Y+103658X0177Y    R180 S1      
317m7005            VIA   -    MD0100PA01X+104546Y+103793X0190Y         S0      
327m7005            J23   -223        A01X+104546Y+103793X0205Y0590R090 S1      
317m7006            VIA   -    MD0080PA01X+130823Y+103443X0160Y         S0      
327m7006            U25   -BH67       A01X+131007Y+103339X0177Y    R180 S1      
317m7006            VIA   -    MD0100PA01X+106161Y+103459X0190Y         S0      
327m7006            J23   -78         A01X+106161Y+103459X0205Y0590R090 S1      
317m7007            VIA   -    MD0080PA01X+131563Y+103443X0160Y         S0      
327m7007            U25   -BH65       A01X+131747Y+103339X0177Y    R180 S1      
317m7007            VIA   -    MD0100PA01X+104546Y+103124X0190Y         S0      
327m7007            J23   -221        A01X+104546Y+103124X0205Y0590R090 S1      
317m7008            VIA   -    MD0080PA01X+131378Y+103124X0160Y         S0      
327m7008            U25   -BG66       A01X+131562Y+103020X0177Y    R180 S1      
317m7008            VIA   -    MD0100PA01X+106161Y+102789X0190Y         S0      
327m7008            J23   -76         A01X+106161Y+102789X0205Y0590R090 S1      
317m7009            VIA   -    MD0080PA01X+131378Y+105038X0160Y         S0      
327m7009            U25   -BN66       A01X+131562Y+104933X0177Y    R180 S1      
317m7009            VIA   -    MD0100PA01X+106161Y+106136X0190Y         S0      
327m7009            J23   -86         A01X+106161Y+106136X0205Y0590R090 S1      
317m7010            VIA   -    MD0080PA01X+131260Y+100718X0160Y    R180 S0      
327m7010            U25   -BC66       A01X+131444Y+100823X0177Y    R180 S1      
317m7010            VIA   -    MD0100PA01X+106161Y+100112X0190Y         S0      
327m7010            J23   -74         A01X+106161Y+100112X0205Y0590R090 S1      
317m7011            VIA   -    MD0080PA01X+131260Y+097529X0160Y    R180 S0      
327m7011            U25   -AN66       A01X+131444Y+097634X0177Y    R180 S1      
317m7011            VIA   -    MD0100PA01X+104546Y+094423X0190Y         S0      
327m7011            J23   -201        A01X+104546Y+094423X0205Y0590R090 S1      
317m7012            VIA   -    MD0080PA01X+131260Y+095616X0160Y    R180 S0      
327m7012            U25   -AG66       A01X+131444Y+095720X0177Y    R180 S1      
317m7012            VIA   -    MD0100PA01X+104546Y+090742X0190Y         S0      
327m7012            J23   -190        A01X+104546Y+090742X0205Y0590R090 S1      
317m7013            VIA   -    MD0080PA01X+131260Y+093702X0160Y    R180 S0      
327m7013            U25   -AA66       A01X+131444Y+093807X0177Y    R180 S1      
317m7013            VIA   -    MD0100PA01X+104546Y+087061X0190Y         S0      
327m7013            J23   -179        A01X+104546Y+087061X0205Y0590R090 S1      
317m7014            VIA   -    MD0080PA01X+131260Y+091789X0160Y    R180 S0      
327m7014            U25   -R66        A01X+131444Y+091894X0177Y    R180 S1      
317m7014            VIA   -    MD0100PA01X+104546Y+083380X0190Y         S0      
327m7014            J23   -168        A01X+104546Y+083380X0205Y0590R090 S1      
317m7015            VIA   -    MD0080PA01X+131260Y+089876X0160Y    R180 S0      
327m7015            U25   -J66        A01X+131444Y+089980X0177Y    R180 S1      
317m7015            VIA   -    MD0100PA01X+104546Y+079699X0190Y         S0      
327m7015            J23   -157        A01X+104546Y+079699X0205Y0590R090 S1      
317m7016            VIA   -    MD0080PA01X+130890Y+096891X0160Y    R180 S0      
327m7016            U25   -AL67       A01X+131074Y+096996X0177Y    R180 S1      
317m7016            VIA   -    MD0100PA01X+106161Y+093754X0190Y         S0      
327m7016            J23   -55         A01X+106161Y+093754X0205Y0590R090 S1      
317m7017            VIA   -    MD0080PA01X+130890Y+094978X0160Y    R180 S0      
327m7017            U25   -AE67       A01X+131074Y+095083X0177Y    R180 S1      
317m7017            VIA   -    MD0100PA01X+106161Y+090073X0190Y         S0      
327m7017            J23   -44         A01X+106161Y+090073X0205Y0590R090 S1      
317m7018            VIA   -    MD0080PA01X+130890Y+093065X0160Y    R180 S0      
327m7018            U25   -W67        A01X+131074Y+093169X0177Y    R180 S1      
317m7018            VIA   -    MD0100PA01X+106161Y+086392X0190Y         S0      
327m7018            J23   -33         A01X+106161Y+086392X0205Y0590R090 S1      
317m7019            VIA   -    MD0080PA01X+130890Y+091151X0160Y    R180 S0      
327m7019            U25   -N67        A01X+131074Y+091256X0177Y    R180 S1      
317m7019            VIA   -    MD0100PA01X+106161Y+082711X0190Y         S0      
327m7019            J23   -22         A01X+106161Y+082711X0205Y0590R090 S1      
317m7020            VIA   -    MD0080PA01X+130890Y+089238X0160Y    R180 S0      
327m7020            U25   -G67        A01X+131074Y+089343X0177Y    R180 S1      
317m7020            VIA   -    MD0100PA01X+106161Y+079030X0190Y         S0      
327m7020            J23   -11         A01X+106161Y+079030X0205Y0590R090 S1      
317m7021            VIA   -    MD0080PA01X+131445Y+097210X0160Y    R180 S0      
327m7021            U25   -AM65       A01X+131629Y+097315X0177Y    R180 S1      
317m7021            VIA   -    MD0100PA01X+104546Y+094089X0190Y         S0      
327m7021            J23   -200        A01X+104546Y+094089X0205Y0590R090 S1      
317m7022            VIA   -    MD0080PA01X+131445Y+095297X0160Y    R180 S0      
327m7022            U25   -AF65       A01X+131629Y+095402X0177Y    R180 S1      
317m7022            VIA   -    MD0100PA01X+104546Y+090408X0190Y         S0      
327m7022            J23   -189        A01X+104546Y+090408X0205Y0590R090 S1      
317m7023            VIA   -    MD0080PA01X+131445Y+093384X0160Y    R180 S0      
327m7023            U25   -Y65        A01X+131629Y+093488X0177Y    R180 S1      
317m7023            VIA   -    MD0100PA01X+104546Y+086726X0190Y         S0      
327m7023            J23   -178        A01X+104546Y+086726X0205Y0590R090 S1      
317m7024            VIA   -    MD0080PA01X+131445Y+091470X0160Y    R180 S0      
327m7024            U25   -P65        A01X+131629Y+091575X0177Y    R180 S1      
317m7024            VIA   -    MD0100PA01X+104546Y+083045X0190Y         S0      
327m7024            J23   -167        A01X+104546Y+083045X0205Y0590R090 S1      
317m7025            VIA   -    MD0080PA01X+131445Y+089557X0160Y    R180 S0      
327m7025            U25   -H65        A01X+131629Y+089662X0177Y    R180 S1      
317m7025            VIA   -    MD0100PA01X+104546Y+079364X0190Y         S0      
327m7025            J23   -156        A01X+104546Y+079364X0205Y0590R090 S1      
317m7026            VIA   -    MD0080PA01X+130705Y+097210X0160Y    R180 S0      
327m7026            U25   -AM67       A01X+130889Y+097315X0177Y    R180 S1      
317m7026            VIA   -    MD0100PA01X+106161Y+094089X0190Y         S0      
327m7026            J23   -56         A01X+106161Y+094089X0205Y0590R090 S1      
317m7027            VIA   -    MD0080PA01X+130705Y+095297X0160Y    R180 S0      
327m7027            U25   -AF67       A01X+130889Y+095402X0177Y    R180 S1      
317m7027            VIA   -    MD0100PA01X+106161Y+090408X0190Y         S0      
327m7027            J23   -45         A01X+106161Y+090408X0205Y0590R090 S1      
317m7028            VIA   -    MD0080PA01X+130705Y+093384X0160Y    R180 S0      
327m7028            U25   -Y67        A01X+130889Y+093488X0177Y    R180 S1      
317m7028            VIA   -    MD0100PA01X+106161Y+086726X0190Y         S0      
327m7028            J23   -34         A01X+106161Y+086726X0205Y0590R090 S1      
317m7029            VIA   -    MD0080PA01X+130705Y+091470X0160Y    R180 S0      
327m7029            U25   -P67        A01X+130889Y+091575X0177Y    R180 S1      
317m7029            VIA   -    MD0100PA01X+106161Y+083045X0190Y         S0      
327m7029            J23   -23         A01X+106161Y+083045X0205Y0590R090 S1      
317m7030            VIA   -    MD0080PA01X+130705Y+089557X0160Y    R180 S0      
327m7030            U25   -H67        A01X+130889Y+089662X0177Y    R180 S1      
317m7030            VIA   -    MD0100PA01X+106161Y+079364X0190Y         S0      
327m7030            J23   -12         A01X+106161Y+079364X0205Y0590R090 S1      
317m7031            VIA   -    MD0080PA01X+131445Y+090832X0160Y    R180 S0      
327m7031            U25   -M65        A01X+131629Y+090937X0177Y    R180 S1      
317m7031            VIA   -    MD0100PA01X+106161Y+082041X0190Y         S0      
327m7031            J23   -20         A01X+106161Y+082041X0205Y0590R090 S1      
317m7032            VIA   -    MD0080PA01X+130890Y+090513X0160Y    R180 S0      
327m7032            U25   -L67        A01X+131074Y+090618X0177Y    R180 S1      
317m7032            VIA   -    MD0100PA01X+106161Y+081372X0190Y         S0      
327m7032            J23   -18         A01X+106161Y+081372X0205Y0590R090 S1      
317m7033            VIA   -    MD0080PA01X+131260Y+090513X0160Y    R180 S0      
327m7033            U25   -L66        A01X+131444Y+090618X0177Y    R180 S1      
317m7033            VIA   -    MD0100PA01X+104546Y+081037X0190Y         S0      
327m7033            J23   -161        A01X+104546Y+081037X0205Y0590R090 S1      
317m7034            VIA   -    MD0080PA01X+130705Y+090195X0160Y    R180 S0      
327m7034            U25   -K67        A01X+130889Y+090299X0177Y    R180 S1      
317m7034            VIA   -    MD0100PA01X+104546Y+080368X0190Y         S0      
327m7034            J23   -159        A01X+104546Y+080368X0205Y0590R090 S1      
317m7035            VIA   -    MD0080PA01X+131445Y+090195X0160Y    R180 S0      
327m7035            U25   -K65        A01X+131629Y+090299X0177Y    R180 S1      
317m7035            VIA   -    MD0100PA01X+106161Y+080703X0190Y         S0      
327m7035            J23   -16         A01X+106161Y+080703X0205Y0590R090 S1      
317m7036            VIA   -    MD0080PA01X+130890Y+089876X0160Y    R180 S0      
327m7036            U25   -J67        A01X+131074Y+089980X0177Y    R180 S1      
317m7036            VIA   -    MD0100PA01X+106161Y+080034X0190Y         S0      
327m7036            J23   -14         A01X+106161Y+080034X0205Y0590R090 S1      
317m7037            VIA   -    MD0080PA01X+131260Y+089238X0160Y    R180 S0      
327m7037            U25   -G66        A01X+131444Y+089343X0177Y    R180 S1      
317m7037            VIA   -    MD0100PA01X+104546Y+078695X0190Y         S0      
327m7037            J23   -154        A01X+104546Y+078695X0205Y0590R090 S1      
317m7038            VIA   -    MD0080PA01X+131260Y+096254X0160Y    R180 S0      
327m7038            U25   -AJ66       A01X+131444Y+096358X0177Y    R180 S1      
317m7038            VIA   -    MD0100PA01X+104546Y+092081X0190Y         S0      
327m7038            J23   -194        A01X+104546Y+092081X0205Y0590R090 S1      
317m7039            VIA   -    MD0080PA01X+130705Y+095935X0160Y    R180 S0      
327m7039            U25   -AH67       A01X+130889Y+096039X0177Y    R180 S1      
317m7039            VIA   -    MD0100PA01X+104546Y+091411X0190Y         S0      
327m7039            J23   -192        A01X+104546Y+091411X0205Y0590R090 S1      
317m7040            VIA   -    MD0080PA01X+130705Y+088919X0160Y    R180 S0      
327m7040            U25   -F67        A01X+130889Y+089024X0177Y    R180 S1      
317m7040            VIA   -    MD0100PA01X+104546Y+078026X0190Y         S0      
327m7040            J23   -152        A01X+104546Y+078026X0205Y0590R090 S1      
317m7041            VIA   -    MD0080PA01X+131445Y+095935X0160Y    R180 S0      
327m7041            U25   -AH65       A01X+131629Y+096039X0177Y    R180 S1      
317m7041            VIA   -    MD0100PA01X+106161Y+091746X0190Y         S0      
327m7041            J23   -49         A01X+106161Y+091746X0205Y0590R090 S1      
317m7042            VIA   -    MD0080PA01X+130890Y+095616X0160Y    R180 S0      
327m7042            U25   -AG67       A01X+131074Y+095720X0177Y    R180 S1      
317m7042            VIA   -    MD0100PA01X+106161Y+091077X0190Y         S0      
327m7042            J23   -47         A01X+106161Y+091077X0205Y0590R090 S1      
317m7043            VIA   -    MD0080PA01X+131260Y+094978X0160Y    R180 S0      
327m7043            U25   -AE66       A01X+131444Y+095083X0177Y    R180 S1      
317m7043            VIA   -    MD0100PA01X+104546Y+089738X0190Y         S0      
327m7043            J23   -187        A01X+104546Y+089738X0205Y0590R090 S1      
317m7044            VIA   -    MD0080PA01X+130705Y+094659X0160Y    R180 S0      
327m7044            U25   -AD67       A01X+130889Y+094764X0177Y    R180 S1      
317m7044            VIA   -    MD0100PA01X+104546Y+089069X0190Y         S0      
327m7044            J23   -185        A01X+104546Y+089069X0205Y0590R090 S1      
317m7045            VIA   -    MD0080PA01X+131445Y+094659X0160Y    R180 S0      
327m7045            U25   -AD65       A01X+131629Y+094764X0177Y    R180 S1      
317m7045            VIA   -    MD0100PA01X+106161Y+089404X0190Y         S0      
327m7045            J23   -42         A01X+106161Y+089404X0205Y0590R090 S1      
317m7046            VIA   -    MD0080PA01X+130890Y+094340X0160Y    R180 S0      
327m7046            U25   -AC67       A01X+131074Y+094445X0177Y    R180 S1      
317m7046            VIA   -    MD0100PA01X+106161Y+088734X0190Y         S0      
327m7046            J23   -40         A01X+106161Y+088734X0205Y0590R090 S1      
317m7047            VIA   -    MD0080PA01X+131260Y+094340X0160Y    R180 S0      
327m7047            U25   -AC66       A01X+131444Y+094445X0177Y    R180 S1      
317m7047            VIA   -    MD0100PA01X+104546Y+088400X0190Y         S0      
327m7047            J23   -183        A01X+104546Y+088400X0205Y0590R090 S1      
317m7048            VIA   -    MD0080PA01X+130705Y+094021X0160Y    R180 S0      
327m7048            U25   -AB67       A01X+130889Y+094126X0177Y    R180 S1      
317m7048            VIA   -    MD0100PA01X+104546Y+087730X0190Y         S0      
327m7048            J23   -181        A01X+104546Y+087730X0205Y0590R090 S1      
317m7049            VIA   -    MD0080PA01X+131445Y+094021X0160Y    R180 S0      
327m7049            U25   -AB65       A01X+131629Y+094126X0177Y    R180 S1      
317m7049            VIA   -    MD0100PA01X+106161Y+088065X0190Y         S0      
327m7049            J23   -38         A01X+106161Y+088065X0205Y0590R090 S1      
317m7050            VIA   -    MD0080PA01X+130890Y+093702X0160Y    R180 S0      
327m7050            U25   -AA67       A01X+131074Y+093807X0177Y    R180 S1      
317m7050            VIA   -    MD0100PA01X+106161Y+087396X0190Y         S0      
327m7050            J23   -36         A01X+106161Y+087396X0205Y0590R090 S1      
317m7051            VIA   -    MD0080PA01X+131445Y+088919X0160Y    R180 S0      
327m7051            U25   -F65        A01X+131629Y+089024X0177Y    R180 S1      
317m7051            VIA   -    MD0100PA01X+106161Y+078360X0190Y         S0      
327m7051            J23   -9          A01X+106161Y+078360X0205Y0590R090 S1      
317m7052            VIA   -    MD0080PA01X+131260Y+093065X0160Y    R180 S0      
327m7052            U25   -W66        A01X+131444Y+093169X0177Y    R180 S1      
317m7052            VIA   -    MD0100PA01X+104546Y+086057X0190Y         S0      
327m7052            J23   -176        A01X+104546Y+086057X0205Y0590R090 S1      
317m7053            VIA   -    MD0080PA01X+130705Y+092746X0160Y    R180 S0      
327m7053            U25   -V67        A01X+130889Y+092850X0177Y    R180 S1      
317m7053            VIA   -    MD0100PA01X+104546Y+085388X0190Y         S0      
327m7053            J23   -174        A01X+104546Y+085388X0205Y0590R090 S1      
317m7054            VIA   -    MD0080PA01X+131445Y+092746X0160Y    R180 S0      
327m7054            U25   -V65        A01X+131629Y+092850X0177Y    R180 S1      
317m7054            VIA   -    MD0100PA01X+106161Y+085722X0190Y         S0      
327m7054            J23   -31         A01X+106161Y+085722X0205Y0590R090 S1      
317m7055            VIA   -    MD0080PA01X+130890Y+092427X0160Y    R180 S0      
327m7055            U25   -U67        A01X+131074Y+092532X0177Y    R180 S1      
317m7055            VIA   -    MD0100PA01X+106161Y+085053X0190Y         S0      
327m7055            J23   -29         A01X+106161Y+085053X0205Y0590R090 S1      
317m7056            VIA   -    MD0080PA01X+131260Y+092427X0160Y    R180 S0      
327m7056            U25   -U66        A01X+131444Y+092532X0177Y    R180 S1      
317m7056            VIA   -    MD0100PA01X+104546Y+084718X0190Y         S0      
327m7056            J23   -172        A01X+104546Y+084718X0205Y0590R090 S1      
317m7057            VIA   -    MD0080PA01X+130705Y+092108X0160Y    R180 S0      
327m7057            U25   -T67        A01X+130889Y+092213X0177Y    R180 S1      
317m7057            VIA   -    MD0100PA01X+104546Y+084049X0190Y         S0      
327m7057            J23   -170        A01X+104546Y+084049X0205Y0590R090 S1      
317m7058            VIA   -    MD0080PA01X+131445Y+092108X0160Y    R180 S0      
327m7058            U25   -T65        A01X+131629Y+092213X0177Y    R180 S1      
317m7058            VIA   -    MD0100PA01X+106161Y+084384X0190Y         S0      
327m7058            J23   -27         A01X+106161Y+084384X0205Y0590R090 S1      
317m7059            VIA   -    MD0080PA01X+130890Y+091789X0160Y    R180 S0      
327m7059            U25   -R67        A01X+131074Y+091894X0177Y    R180 S1      
317m7059            VIA   -    MD0100PA01X+106161Y+083715X0190Y         S0      
327m7059            J23   -25         A01X+106161Y+083715X0205Y0590R090 S1      
317m7060            VIA   -    MD0080PA01X+131260Y+091151X0160Y    R180 S0      
327m7060            U25   -N66        A01X+131444Y+091256X0177Y    R180 S1      
317m7060            VIA   -    MD0100PA01X+104546Y+082376X0190Y         S0      
327m7060            J23   -165        A01X+104546Y+082376X0205Y0590R090 S1      
317m7061            VIA   -    MD0080PA01X+130705Y+090832X0160Y    R180 S0      
327m7061            U25   -M67        A01X+130889Y+090937X0177Y    R180 S1      
317m7061            VIA   -    MD0100PA01X+104546Y+081707X0190Y         S0      
327m7061            J23   -163        A01X+104546Y+081707X0205Y0590R090 S1      
317m7062            VIA   -    MD0080PA01X+130890Y+088600X0160Y    R180 S0      
327m7062            U25   -E67        A01X+131074Y+088705X0177Y    R180 S1      
317m7062            VIA   -    MD0100PA01X+106161Y+077691X0190Y         S0      
327m7062            J23   -7          A01X+106161Y+077691X0205Y0590R090 S1      
317m7063            VIA   -    MD0080PA01X+131260Y+099443X0160Y    R180 S0      
327m7063            U25   -AW66       A01X+131444Y+099547X0177Y    R180 S1      
317m7063            VIA   -    MD0100PA01X+104546Y+097100X0190Y         S0      
327m7063            J23   -209        A01X+104546Y+097100X0205Y0590R090 S1      
317m7064            VIA   -    MD0080PA01X+130705Y+099124X0160Y    R180 S0      
327m7064            U25   -AV67       A01X+130889Y+099228X0177Y    R180 S1      
317m7064            VIA   -    MD0100PA01X+106161Y+096766X0190Y         S0      
327m7064            J23   -64         A01X+106161Y+096766X0205Y0590R090 S1      
317m7065            VIA   -    MD0080PA01X+131260Y+098167X0160Y    R180 S0      
327m7065            U25   -AR66       A01X+131444Y+098272X0177Y    R180 S1      
317m7065            VIA   -    MD0100PA01X+104546Y+095762X0190Y         S0      
327m7065            J23   -205        A01X+104546Y+095762X0205Y0590R090 S1      
317m7066            VIA   -    MD0080PA01X+130705Y+097848X0160Y    R180 S0      
327m7066            U25   -AP67       A01X+130889Y+097953X0177Y    R180 S1      
317m7066            VIA   -    MD0100PA01X+104546Y+095092X0190Y         S0      
327m7066            J23   -203        A01X+104546Y+095092X0205Y0590R090 S1      
317m7067            VIA   -    MD0080PA01X+131445Y+097848X0160Y    R180 S0      
327m7067            U25   -AP65       A01X+131629Y+097953X0177Y    R180 S1      
317m7067            VIA   -    MD0100PA01X+106161Y+095427X0190Y         S0      
327m7067            J23   -60         A01X+106161Y+095427X0205Y0590R090 S1      
317m7068            VIA   -    MD0080PA01X+130890Y+097529X0160Y    R180 S0      
327m7068            U25   -AN67       A01X+131074Y+097634X0177Y    R180 S1      
317m7068            VIA   -    MD0100PA01X+106161Y+094758X0190Y         S0      
327m7068            J23   -58         A01X+106161Y+094758X0205Y0590R090 S1      
317m7069            VIA   -    MD0080PA01X+131260Y+096891X0160Y    R180 S0      
327m7069            U25   -AL66       A01X+131444Y+096996X0177Y    R180 S1      
317m7069            VIA   -    MD0100PA01X+104546Y+093419X0190Y         S0      
327m7069            J23   -198        A01X+104546Y+093419X0205Y0590R090 S1      
317m7070            VIA   -    MD0080PA01X+130705Y+096572X0160Y    R180 S0      
327m7070            U25   -AK67       A01X+130889Y+096677X0177Y    R180 S1      
317m7070            VIA   -    MD0100PA01X+104546Y+092750X0190Y         S0      
327m7070            J23   -196        A01X+104546Y+092750X0205Y0590R090 S1      
317m7071            VIA   -    MD0080PA01X+131445Y+096572X0160Y    R180 S0      
327m7071            U25   -AK65       A01X+131629Y+096677X0177Y    R180 S1      
317m7071            VIA   -    MD0100PA01X+106161Y+093085X0190Y         S0      
327m7071            J23   -53         A01X+106161Y+093085X0205Y0590R090 S1      
317m7072            VIA   -    MD0080PA01X+130890Y+096254X0160Y    R180 S0      
327m7072            U25   -AJ67       A01X+131074Y+096358X0177Y    R180 S1      
317m7072            VIA   -    MD0100PA01X+106161Y+092415X0190Y         S0      
327m7072            J23   -51         A01X+106161Y+092415X0205Y0590R090 S1      
317m7073            VIA   -    MD0080PA01X+131445Y+100399X0160Y    R180 S0      
327m7073            U25   -BB65       A01X+131629Y+100504X0177Y    R180 S1      
317m7073            VIA   -    MD0100PA01X+106161Y+099443X0190Y         S0      
327m7073            J23   -72         A01X+106161Y+099443X0205Y0590R090 S1      
317m7074            VIA   -    MD0080PA01X+130705Y+100399X0160Y    R180 S0      
327m7074            U25   -BB67       A01X+130889Y+100504X0177Y    R180 S1      
317m7074            VIA   -    MD0100PA01X+104546Y+099108X0190Y         S0      
327m7074            J23   -215        A01X+104546Y+099108X0205Y0590R090 S1      
317m7075            VIA   -    MD0080PA01X+130890Y+100080X0160Y    R180 S0      
327m7075            U25   -BA67       A01X+131074Y+100185X0177Y    R180 S1      
317m7075            VIA   -    MD0100PA01X+106161Y+098774X0190Y         S0      
327m7075            J23   -70         A01X+106161Y+098774X0205Y0590R090 S1      
317m7076            VIA   -    MD0080PA01X+131260Y+100080X0160Y    R180 S0      
327m7076            U25   -BA66       A01X+131444Y+100185X0177Y    R180 S1      
317m7076            VIA   -    MD0100PA01X+104546Y+098439X0190Y         S0      
327m7076            J23   -213        A01X+104546Y+098439X0205Y0590R090 S1      
317m7077            VIA   -    MD0080PA01X+131445Y+099762X0160Y    R180 S0      
327m7077            U25   -AY65       A01X+131629Y+099866X0177Y    R180 S1      
317m7077            VIA   -    MD0100PA01X+106161Y+098104X0190Y         S0      
327m7077            J23   -68         A01X+106161Y+098104X0205Y0590R090 S1      
317m7078            VIA   -    MD0080PA01X+130705Y+099762X0160Y    R180 S0      
327m7078            U25   -AY67       A01X+130889Y+099866X0177Y    R180 S1      
317m7078            VIA   -    MD0100PA01X+104546Y+097770X0190Y         S0      
327m7078            J23   -211        A01X+104546Y+097770X0205Y0590R090 S1      
317m7079            VIA   -    MD0080PA01X+130890Y+099443X0160Y    R180 S0      
327m7079            U25   -AW67       A01X+131074Y+099547X0177Y    R180 S1      
317m7079            VIA   -    MD0100PA01X+106161Y+097435X0190Y         S0      
327m7079            J23   -66         A01X+106161Y+097435X0205Y0590R090 S1      
317m7080            VIA   -    MD0080PA01X+131260Y+098805X0160Y    R180 S0      
327m7080            U25   -AU66       A01X+131444Y+098910X0177Y    R180 S1      
317m7080            VIA   -    MD0100PA01X+104546Y+096431X0190Y         S0      
327m7080            J23   -207        A01X+104546Y+096431X0205Y0590R090 S1      
317m7081            VIA   -    MD0080PA01X+130890Y+100718X0160Y    R180 S0      
327m7081            U25   -BC67       A01X+131074Y+100823X0177Y    R180 S1      
317m7081            VIA   -    MD0100PA01X+104546Y+099778X0190Y         S0      
327m7081            J23   -217        A01X+104546Y+099778X0205Y0590R090 S1      
317m7082            VIA   -    MD0080PA01X+130705Y+101037X0160Y    R180 S0      
327m7082            U25   -BD67       A01X+130889Y+101142X0177Y    R180 S1      
317m7082            VIA   -    MD0100PA01X+104546Y+100112X0190Y         S0      
327m7082            J23   -218        A01X+104546Y+100112X0205Y0590R090 S1      
317m7083            VIA   -    MD0080PA01X+131445Y+098486X0160Y    R180 S0      
327m7083            U25   -AT65       A01X+131629Y+098591X0177Y    R180 S1      
317m7083            VIA   -    MD0100PA18X+106711Y+096096X0190Y         S0      
327m7083            R380  -2          A18X+106711Y+096096X0198Y0197R180 S2      
327m7084            J23   -62         A01X+106161Y+096096X0205Y0590R090 S1      
317m7084            VIA   -    MD0100PA00X+106161Y+096096X0190Y         S0      
327m7084            R380  -1          A18X+106396Y+096096X0198Y0197R180 S2      
317m7085            VIA   -    MD0080PA01X+032099Y+105357X0160Y         S0      
327m7085            U26   -BP70       A01X+032283Y+105252X0177Y    R180 S1      
317m7085            VIA   -    MD0100PA01X+011517Y+106471X0190Y         S0      
327m7085            J32   -87         A01X+011517Y+106471X0205Y0590R090 S1      
317m7086            VIA   -    MD0080PA01X+031914Y+104400X0160Y         S0      
327m7086            U26   -BL71       A01X+032098Y+104295X0177Y    R180 S1      
317m7086            VIA   -    MD0100PA01X+009902Y+105132X0190Y         S0      
327m7086            J32   -227        A01X+009902Y+105132X0205Y0590R090 S1      
317m7087            VIA   -    MD0080PA01X+032099Y+106632X0160Y         S0      
327m7087            U26   -BV70       A01X+032283Y+106528X0177Y    R180 S1      
317m7087            VIA   -    MD0100PA01X+011517Y+108478X0190Y         S0      
327m7087            J32   -93         A01X+011517Y+108478X0205Y0590R090 S1      
317m7088            VIA   -    MD0080PA01X+032469Y+114924X0160Y         S0      
327m7088            U26   -DD69       A01X+032653Y+114819X0177Y    R180 S1      
317m7088            VIA   -    MD0100PA01X+009902Y+123872X0190Y         S0      
327m7088            J32   -283        A01X+009902Y+123872X0205Y0590R090 S1      
317m7089            VIA   -    MD0080PA01X+032469Y+113010X0160Y         S0      
327m7089            U26   -CV69       A01X+032653Y+112906X0177Y    R180 S1      
317m7089            VIA   -    MD0100PA01X+009902Y+120191X0190Y         S0      
327m7089            J32   -272        A01X+009902Y+120191X0205Y0590R090 S1      
317m7090            VIA   -    MD0080PA01X+032469Y+111097X0160Y         S0      
327m7090            U26   -CM69       A01X+032653Y+110992X0177Y    R180 S1      
317m7090            VIA   -    MD0100PA01X+009902Y+116510X0190Y         S0      
327m7090            J32   -261        A01X+009902Y+116510X0205Y0590R090 S1      
317m7091            VIA   -    MD0080PA01X+032469Y+109184X0160Y         S0      
327m7091            U26   -CF69       A01X+032653Y+109079X0177Y    R180 S1      
317m7091            VIA   -    MD0100PA01X+009902Y+112829X0190Y         S0      
327m7091            J32   -250        A01X+009902Y+112829X0205Y0590R090 S1      
317m7092            VIA   -    MD0080PA01X+032469Y+107270X0160Y         S0      
327m7092            U26   -BY69       A01X+032653Y+107166X0177Y    R180 S1      
317m7092            VIA   -    MD0100PA01X+009902Y+109148X0190Y         S0      
327m7092            J32   -239        A01X+009902Y+109148X0205Y0590R090 S1      
317m7093            VIA   -    MD0080PA01X+032099Y+114286X0160Y         S0      
327m7093            U26   -DB70       A01X+032283Y+114181X0177Y    R180 S1      
317m7093            VIA   -    MD0100PA01X+011517Y+123203X0190Y         S0      
327m7093            J32   -137        A01X+011517Y+123203X0205Y0590R090 S1      
317m7094            VIA   -    MD0080PA01X+032099Y+112373X0160Y         S0      
327m7094            U26   -CT70       A01X+032283Y+112268X0177Y    R180 S1      
317m7094            VIA   -    MD0100PA01X+011517Y+119522X0190Y         S0      
327m7094            J32   -126        A01X+011517Y+119522X0205Y0590R090 S1      
317m7095            VIA   -    MD0080PA01X+032099Y+110459X0160Y         S0      
327m7095            U26   -CK70       A01X+032283Y+110354X0177Y    R180 S1      
317m7095            VIA   -    MD0100PA01X+011517Y+115841X0190Y         S0      
327m7095            J32   -115        A01X+011517Y+115841X0205Y0590R090 S1      
317m7096            VIA   -    MD0080PA01X+032099Y+108546X0160Y         S0      
327m7096            U26   -CD70       A01X+032283Y+108441X0177Y    R180 S1      
317m7096            VIA   -    MD0100PA01X+011517Y+112160X0190Y         S0      
327m7096            J32   -104        A01X+011517Y+112160X0205Y0590R090 S1      
317m7097            VIA   -    MD0080PA01X+031914Y+106951X0160Y         S0      
327m7097            U26   -BW71       A01X+032098Y+106847X0177Y    R180 S1      
317m7097            VIA   -    MD0100PA01X+011517Y+108813X0190Y         S0      
327m7097            J32   -94         A01X+011517Y+108813X0205Y0590R090 S1      
317m7098            VIA   -    MD0080PA01X+032654Y+114605X0160Y         S0      
327m7098            U26   -DC69       A01X+032838Y+114500X0177Y    R180 S1      
317m7098            VIA   -    MD0100PA01X+009902Y+123538X0190Y         S0      
327m7098            J32   -282        A01X+009902Y+123538X0205Y0590R090 S1      
317m7099            VIA   -    MD0080PA01X+032654Y+112692X0160Y         S0      
327m7099            U26   -CU69       A01X+032838Y+112587X0177Y    R180 S1      
317m7099            VIA   -    MD0100PA01X+009902Y+119856X0190Y         S0      
327m7099            J32   -271        A01X+009902Y+119856X0205Y0590R090 S1      
317m7100            VIA   -    MD0080PA01X+032654Y+110778X0160Y         S0      
327m7100            U26   -CL69       A01X+032838Y+110673X0177Y    R180 S1      
317m7100            VIA   -    MD0100PA01X+009902Y+116175X0190Y         S0      
327m7100            J32   -260        A01X+009902Y+116175X0205Y0590R090 S1      
317m7101            VIA   -    MD0080PA01X+032654Y+108865X0160Y         S0      
327m7101            U26   -CE69       A01X+032838Y+108760X0177Y    R180 S1      
317m7101            VIA   -    MD0100PA01X+009902Y+112494X0190Y         S0      
327m7101            J32   -249        A01X+009902Y+112494X0205Y0590R090 S1      
317m7102            VIA   -    MD0080PA01X+032654Y+106951X0160Y         S0      
327m7102            U26   -BW69       A01X+032838Y+106847X0177Y    R180 S1      
317m7102            VIA   -    MD0100PA01X+009902Y+108813X0190Y         S0      
327m7102            J32   -238        A01X+009902Y+108813X0205Y0590R090 S1      
317m7103            VIA   -    MD0080PA01X+031914Y+114605X0160Y         S0      
327m7103            U26   -DC71       A01X+032098Y+114500X0177Y    R180 S1      
317m7103            VIA   -    MD0100PA01X+011517Y+123538X0190Y         S0      
327m7103            J32   -138        A01X+011517Y+123538X0205Y0590R090 S1      
317m7104            VIA   -    MD0080PA01X+031914Y+112692X0160Y         S0      
327m7104            U26   -CU71       A01X+032098Y+112587X0177Y    R180 S1      
317m7104            VIA   -    MD0100PA01X+011517Y+119856X0190Y         S0      
327m7104            J32   -127        A01X+011517Y+119856X0205Y0590R090 S1      
317m7105            VIA   -    MD0080PA01X+031914Y+110778X0160Y         S0      
327m7105            U26   -CL71       A01X+032098Y+110673X0177Y    R180 S1      
317m7105            VIA   -    MD0100PA01X+011517Y+116175X0190Y         S0      
327m7105            J32   -116        A01X+011517Y+116175X0205Y0590R090 S1      
317m7106            VIA   -    MD0080PA01X+031914Y+108865X0160Y         S0      
327m7106            U26   -CE71       A01X+032098Y+108760X0177Y    R180 S1      
317m7106            VIA   -    MD0100PA01X+011517Y+112494X0190Y         S0      
327m7106            J32   -105        A01X+011517Y+112494X0205Y0590R090 S1      
317m7107            VIA   -    MD0080PA01X+032654Y+110140X0160Y         S0      
327m7107            U26   -CJ69       A01X+032838Y+110036X0177Y    R180 S1      
317m7107            VIA   -    MD0100PA01X+011517Y+115171X0190Y         S0      
327m7107            J32   -113        A01X+011517Y+115171X0205Y0590R090 S1      
317m7108            VIA   -    MD0080PA01X+032099Y+109821X0160Y         S0      
327m7108            U26   -CH70       A01X+032283Y+109717X0177Y    R180 S1      
317m7108            VIA   -    MD0100PA01X+011517Y+114502X0190Y         S0      
327m7108            J32   -111        A01X+011517Y+114502X0205Y0590R090 S1      
317m7109            VIA   -    MD0080PA01X+032469Y+109821X0160Y         S0      
327m7109            U26   -CH69       A01X+032653Y+109717X0177Y    R180 S1      
317m7109            VIA   -    MD0100PA01X+009902Y+114168X0190Y         S0      
327m7109            J32   -254        A01X+009902Y+114168X0205Y0590R090 S1      
317m7110            VIA   -    MD0080PA01X+031914Y+109502X0160Y         S0      
327m7110            U26   -CG71       A01X+032098Y+109398X0177Y    R180 S1      
317m7110            VIA   -    MD0100PA01X+009902Y+113498X0190Y         S0      
327m7110            J32   -252        A01X+009902Y+113498X0205Y0590R090 S1      
317m7111            VIA   -    MD0080PA01X+032654Y+109502X0160Y         S0      
327m7111            U26   -CG69       A01X+032838Y+109398X0177Y    R180 S1      
317m7111            VIA   -    MD0100PA01X+011517Y+113833X0190Y         S0      
327m7111            J32   -109        A01X+011517Y+113833X0205Y0590R090 S1      
317m7112            VIA   -    MD0080PA01X+032099Y+109184X0160Y         S0      
327m7112            U26   -CF70       A01X+032283Y+109079X0177Y    R180 S1      
317m7112            VIA   -    MD0100PA01X+011517Y+113164X0190Y         S0      
327m7112            J32   -107        A01X+011517Y+113164X0205Y0590R090 S1      
317m7113            VIA   -    MD0080PA01X+032469Y+108546X0160Y         S0      
327m7113            U26   -CD69       A01X+032653Y+108441X0177Y    R180 S1      
317m7113            VIA   -    MD0100PA01X+009902Y+111825X0190Y         S0      
327m7113            J32   -247        A01X+009902Y+111825X0205Y0590R090 S1      
317m7114            VIA   -    MD0080PA01X+032469Y+115562X0160Y         S0      
327m7114            U26   -DF69       A01X+032653Y+115457X0177Y    R180 S1      
317m7114            VIA   -    MD0100PA01X+009902Y+125211X0190Y         S0      
327m7114            J32   -287        A01X+009902Y+125211X0205Y0590R090 S1      
317m7115            VIA   -    MD0080PA01X+031914Y+115243X0160Y         S0      
327m7115            U26   -DE71       A01X+032098Y+115138X0177Y    R180 S1      
317m7115            VIA   -    MD0100PA01X+009902Y+124542X0190Y         S0      
327m7115            J32   -285        A01X+009902Y+124542X0205Y0590R090 S1      
317m7116            VIA   -    MD0080PA01X+031914Y+108227X0160Y         S0      
327m7116            U26   -CC71       A01X+032098Y+108122X0177Y    R180 S1      
317m7116            VIA   -    MD0100PA01X+009902Y+111156X0190Y         S0      
327m7116            J32   -245        A01X+009902Y+111156X0205Y0590R090 S1      
317m7117            VIA   -    MD0080PA01X+032654Y+115243X0160Y         S0      
327m7117            U26   -DE69       A01X+032838Y+115138X0177Y    R180 S1      
317m7117            VIA   -    MD0100PA01X+011517Y+124876X0190Y         S0      
327m7117            J32   -142        A01X+011517Y+124876X0205Y0590R090 S1      
317m7118            VIA   -    MD0080PA01X+032099Y+114924X0160Y         S0      
327m7118            U26   -DD70       A01X+032283Y+114819X0177Y    R180 S1      
317m7118            VIA   -    MD0100PA01X+011517Y+124207X0190Y         S0      
327m7118            J32   -140        A01X+011517Y+124207X0205Y0590R090 S1      
317m7119            VIA   -    MD0080PA01X+032469Y+114286X0160Y         S0      
327m7119            U26   -DB69       A01X+032653Y+114181X0177Y    R180 S1      
317m7119            VIA   -    MD0100PA01X+009902Y+122868X0190Y         S0      
327m7119            J32   -280        A01X+009902Y+122868X0205Y0590R090 S1      
317m7120            VIA   -    MD0080PA01X+031914Y+113967X0160Y         S0      
327m7120            U26   -DA71       A01X+032098Y+113862X0177Y    R180 S1      
317m7120            VIA   -    MD0100PA01X+009902Y+122199X0190Y         S0      
327m7120            J32   -278        A01X+009902Y+122199X0205Y0590R090 S1      
317m7121            VIA   -    MD0080PA01X+032654Y+113967X0160Y         S0      
327m7121            U26   -DA69       A01X+032838Y+113862X0177Y    R180 S1      
317m7121            VIA   -    MD0100PA01X+011517Y+122534X0190Y         S0      
327m7121            J32   -135        A01X+011517Y+122534X0205Y0590R090 S1      
317m7122            VIA   -    MD0080PA01X+032099Y+113648X0160Y         S0      
327m7122            U26   -CY70       A01X+032283Y+113543X0177Y    R180 S1      
317m7122            VIA   -    MD0100PA01X+011517Y+121864X0190Y         S0      
327m7122            J32   -133        A01X+011517Y+121864X0205Y0590R090 S1      
317m7123            VIA   -    MD0080PA01X+032469Y+113648X0160Y         S0      
327m7123            U26   -CY69       A01X+032653Y+113543X0177Y    R180 S1      
317m7123            VIA   -    MD0100PA01X+009902Y+121530X0190Y         S0      
327m7123            J32   -276        A01X+009902Y+121530X0205Y0590R090 S1      
317m7124            VIA   -    MD0080PA01X+031914Y+113329X0160Y         S0      
327m7124            U26   -CW71       A01X+032098Y+113225X0177Y    R180 S1      
317m7124            VIA   -    MD0100PA01X+009902Y+120860X0190Y         S0      
327m7124            J32   -274        A01X+009902Y+120860X0205Y0590R090 S1      
317m7125            VIA   -    MD0080PA01X+032654Y+113329X0160Y         S0      
327m7125            U26   -CW69       A01X+032838Y+113225X0177Y    R180 S1      
317m7125            VIA   -    MD0100PA01X+011517Y+121195X0190Y         S0      
327m7125            J32   -131        A01X+011517Y+121195X0205Y0590R090 S1      
317m7126            VIA   -    MD0080PA01X+032099Y+113010X0160Y         S0      
327m7126            U26   -CV70       A01X+032283Y+112906X0177Y    R180 S1      
327m7126            J32   -129        A01X+011517Y+120526X0205Y0590R090 S1      
317m7126            VIA   -    MD0100PA01X+011517Y+120526X0190Y         S0      
317m7127            VIA   -    MD0080PA01X+032654Y+108227X0160Y         S0      
327m7127            U26   -CC69       A01X+032838Y+108122X0177Y    R180 S1      
317m7127            VIA   -    MD0100PA01X+011517Y+111490X0190Y         S0      
327m7127            J32   -102        A01X+011517Y+111490X0205Y0590R090 S1      
317m7128            VIA   -    MD0080PA01X+032469Y+112373X0160Y         S0      
327m7128            U26   -CT69       A01X+032653Y+112268X0177Y    R180 S1      
317m7128            VIA   -    MD0100PA01X+009902Y+119187X0190Y         S0      
327m7128            J32   -269        A01X+009902Y+119187X0205Y0590R090 S1      
317m7129            VIA   -    MD0080PA01X+031914Y+112054X0160Y         S0      
327m7129            U26   -CR71       A01X+032098Y+111949X0177Y    R180 S1      
317m7129            VIA   -    MD0100PA01X+009902Y+118518X0190Y         S0      
327m7129            J32   -267        A01X+009902Y+118518X0205Y0590R090 S1      
317m7130            VIA   -    MD0080PA01X+032654Y+112054X0160Y         S0      
327m7130            U26   -CR69       A01X+032838Y+111949X0177Y    R180 S1      
317m7130            VIA   -    MD0100PA01X+011517Y+118852X0190Y         S0      
327m7130            J32   -124        A01X+011517Y+118852X0205Y0590R090 S1      
317m7131            VIA   -    MD0080PA01X+032099Y+111735X0160Y         S0      
327m7131            U26   -CP70       A01X+032283Y+111630X0177Y    R180 S1      
317m7131            VIA   -    MD0100PA01X+011517Y+118183X0190Y         S0      
327m7131            J32   -122        A01X+011517Y+118183X0205Y0590R090 S1      
317m7132            VIA   -    MD0080PA01X+032469Y+111735X0160Y         S0      
327m7132            U26   -CP69       A01X+032653Y+111630X0177Y    R180 S1      
317m7132            VIA   -    MD0100PA01X+009902Y+117849X0190Y         S0      
327m7132            J32   -265        A01X+009902Y+117849X0205Y0590R090 S1      
317m7133            VIA   -    MD0080PA01X+031914Y+111416X0160Y         S0      
327m7133            U26   -CN71       A01X+032098Y+111311X0177Y    R180 S1      
317m7133            VIA   -    MD0100PA01X+009902Y+117179X0190Y         S0      
327m7133            J32   -263        A01X+009902Y+117179X0205Y0590R090 S1      
317m7134            VIA   -    MD0080PA01X+032654Y+111416X0160Y         S0      
327m7134            U26   -CN69       A01X+032838Y+111311X0177Y    R180 S1      
317m7134            VIA   -    MD0100PA01X+011517Y+117514X0190Y         S0      
327m7134            J32   -120        A01X+011517Y+117514X0205Y0590R090 S1      
317m7135            VIA   -    MD0080PA01X+032099Y+111097X0160Y         S0      
327m7135            U26   -CM70       A01X+032283Y+110992X0177Y    R180 S1      
317m7135            VIA   -    MD0100PA01X+011517Y+116845X0190Y         S0      
327m7135            J32   -118        A01X+011517Y+116845X0205Y0590R090 S1      
317m7136            VIA   -    MD0080PA01X+032469Y+110459X0160Y         S0      
327m7136            U26   -CK69       A01X+032653Y+110354X0177Y    R180 S1      
317m7136            VIA   -    MD0100PA01X+009902Y+115506X0190Y         S0      
327m7136            J32   -258        A01X+009902Y+115506X0205Y0590R090 S1      
317m7137            VIA   -    MD0080PA01X+031914Y+110140X0160Y         S0      
327m7137            U26   -CJ71       A01X+032098Y+110036X0177Y    R180 S1      
317m7137            VIA   -    MD0100PA01X+009902Y+114837X0190Y         S0      
327m7137            J32   -256        A01X+009902Y+114837X0205Y0590R090 S1      
317m7138            VIA   -    MD0080PA01X+032099Y+107908X0160Y         S0      
327m7138            U26   -CB70       A01X+032283Y+107803X0177Y    R180 S1      
317m7138            VIA   -    MD0100PA01X+011517Y+110821X0190Y         S0      
327m7138            J32   -100        A01X+011517Y+110821X0205Y0590R090 S1      
317m7139            VIA   -    MD0080PA01X+031914Y+105038X0160Y         S0      
327m7139            U26   -BN71       A01X+032098Y+104933X0177Y    R180 S1      
317m7139            VIA   -    MD0100PA01X+009902Y+105801X0190Y         S0      
327m7139            J32   -229        A01X+009902Y+105801X0205Y0590R090 S1      
317m7140            VIA   -    MD0080PA01X+032469Y+104719X0160Y         S0      
327m7140            U26   -BM69       A01X+032653Y+104614X0177Y    R180 S1      
317m7140            VIA   -    MD0100PA01X+011517Y+105467X0190Y         S0      
327m7140            J32   -84         A01X+011517Y+105467X0205Y0590R090 S1      
317m7141            VIA   -    MD0080PA01X+032469Y+106632X0160Y         S0      
327m7141            U26   -BV69       A01X+032653Y+106528X0177Y    R180 S1      
317m7141            VIA   -    MD0100PA01X+009902Y+108144X0190Y         S0      
327m7141            J32   -236        A01X+009902Y+108144X0205Y0590R090 S1      
317m7142            VIA   -    MD0080PA01X+031914Y+106314X0160Y         S0      
327m7142            U26   -BU71       A01X+032098Y+106209X0177Y    R180 S1      
317m7142            VIA   -    MD0100PA01X+009902Y+107474X0190Y         S0      
327m7142            J32   -234        A01X+009902Y+107474X0205Y0590R090 S1      
317m7143            VIA   -    MD0080PA01X+032654Y+106314X0160Y         S0      
327m7143            U26   -BU69       A01X+032838Y+106209X0177Y    R180 S1      
317m7143            VIA   -    MD0100PA01X+011517Y+107809X0190Y         S0      
327m7143            J32   -91         A01X+011517Y+107809X0205Y0590R090 S1      
317m7144            VIA   -    MD0080PA01X+032099Y+105995X0160Y         S0      
327m7144            U26   -BT70       A01X+032283Y+105890X0177Y    R180 S1      
317m7144            VIA   -    MD0100PA01X+011517Y+107140X0190Y         S0      
327m7144            J32   -89         A01X+011517Y+107140X0205Y0590R090 S1      
317m7145            VIA   -    MD0080PA01X+032469Y+107908X0160Y         S0      
327m7145            U26   -CB69       A01X+032653Y+107803X0177Y    R180 S1      
317m7145            VIA   -    MD0100PA01X+009902Y+110486X0190Y         S0      
327m7145            J32   -243        A01X+009902Y+110486X0205Y0590R090 S1      
317m7146            VIA   -    MD0080PA01X+031914Y+107589X0160Y         S0      
327m7146            U26   -CA71       A01X+032098Y+107484X0177Y    R180 S1      
317m7146            VIA   -    MD0100PA01X+009902Y+109817X0190Y         S0      
327m7146            J32   -241        A01X+009902Y+109817X0205Y0590R090 S1      
317m7147            VIA   -    MD0080PA01X+032654Y+107589X0160Y         S0      
327m7147            U26   -CA69       A01X+032838Y+107484X0177Y    R180 S1      
317m7147            VIA   -    MD0100PA01X+011517Y+110152X0190Y         S0      
327m7147            J32   -98         A01X+011517Y+110152X0205Y0590R090 S1      
317m7148            VIA   -    MD0080PA01X+032099Y+107270X0160Y         S0      
327m7148            U26   -BY70       A01X+032283Y+107166X0177Y    R180 S1      
317m7148            VIA   -    MD0100PA01X+011517Y+109482X0190Y         S0      
327m7148            J32   -96         A01X+011517Y+109482X0205Y0590R090 S1      
317m7149            VIA   -    MD0080PA01X+032099Y+104081X0160Y         S0      
327m7149            U26   -BK70       A01X+032283Y+103976X0177Y    R180 S1      
317m7149            VIA   -    MD0100PA01X+011517Y+104797X0190Y         S0      
327m7149            J32   -82         A01X+011517Y+104797X0205Y0590R090 S1      
317m7150            VIA   -    MD0080PA01X+032469Y+104081X0160Y         S0      
327m7150            U26   -BK69       A01X+032653Y+103976X0177Y    R180 S1      
317m7150            VIA   -    MD0100PA01X+009902Y+104463X0190Y         S0      
327m7150            J32   -225        A01X+009902Y+104463X0205Y0590R090 S1      
317m7151            VIA   -    MD0080PA01X+032654Y+103762X0160Y         S0      
327m7151            U26   -BJ69       A01X+032838Y+103658X0177Y    R180 S1      
317m7151            VIA   -    MD0100PA01X+011517Y+104128X0190Y         S0      
327m7151            J32   -80         A01X+011517Y+104128X0205Y0590R090 S1      
317m7152            VIA   -    MD0080PA01X+031914Y+103762X0160Y         S0      
327m7152            U26   -BJ71       A01X+032098Y+103658X0177Y    R180 S1      
317m7152            VIA   -    MD0100PA01X+009902Y+103793X0190Y         S0      
327m7152            J32   -223        A01X+009902Y+103793X0205Y0590R090 S1      
317m7153            VIA   -    MD0080PA01X+032099Y+103443X0160Y         S0      
327m7153            U26   -BH70       A01X+032283Y+103339X0177Y    R180 S1      
317m7153            VIA   -    MD0100PA01X+011517Y+103459X0190Y         S0      
327m7153            J32   -78         A01X+011517Y+103459X0205Y0590R090 S1      
317m7154            VIA   -    MD0080PA01X+032469Y+103443X0160Y         S0      
327m7154            U26   -BH69       A01X+032653Y+103339X0177Y    R180 S1      
317m7154            VIA   -    MD0100PA01X+009902Y+103124X0190Y         S0      
327m7154            J32   -221        A01X+009902Y+103124X0205Y0590R090 S1      
317m7155            VIA   -    MD0080PA01X+032654Y+103124X0160Y         S0      
327m7155            U26   -BG69       A01X+032838Y+103020X0177Y    R180 S1      
317m7155            VIA   -    MD0100PA01X+011517Y+102790X0190Y         S0      
327m7155            J32   -76         A01X+011517Y+102790X0205Y0590R090 S1      
317m7156            VIA   -    MD0080PA01X+032654Y+105038X0160Y         S0      
327m7156            U26   -BN69       A01X+032838Y+104933X0177Y    R180 S1      
317m7156            VIA   -    MD0100PA01X+011517Y+106136X0190Y         S0      
327m7156            J32   -86         A01X+011517Y+106136X0205Y0590R090 S1      
317m7157            VIA   -    MD0080PA01X+032536Y+100718X0160Y    R180 S0      
327m7157            U26   -BC69       A01X+032720Y+100823X0177Y    R180 S1      
317m7157            VIA   -    MD0100PA01X+011517Y+100112X0190Y         S0      
327m7157            J32   -74         A01X+011517Y+100112X0205Y0590R090 S1      
317m7158            VIA   -    MD0080PA01X+032536Y+097529X0160Y    R180 S0      
327m7158            U26   -AN69       A01X+032720Y+097634X0177Y    R180 S1      
317m7158            VIA   -    MD0100PA01X+009902Y+094423X0190Y         S0      
327m7158            J32   -201        A01X+009902Y+094423X0205Y0590R090 S1      
317m7159            VIA   -    MD0080PA01X+032536Y+095616X0160Y    R180 S0      
327m7159            U26   -AG69       A01X+032720Y+095721X0177Y    R180 S1      
317m7159            VIA   -    MD0100PA01X+009902Y+090742X0190Y         S0      
327m7159            J32   -190        A01X+009902Y+090742X0205Y0590R090 S1      
317m7160            VIA   -    MD0080PA01X+032536Y+093702X0160Y    R180 S0      
327m7160            U26   -AA69       A01X+032720Y+093807X0177Y    R180 S1      
317m7160            VIA   -    MD0100PA01X+009902Y+087061X0190Y         S0      
327m7160            J32   -179        A01X+009902Y+087061X0205Y0590R090 S1      
317m7161            VIA   -    MD0080PA01X+032536Y+091789X0160Y    R180 S0      
327m7161            U26   -R69        A01X+032720Y+091894X0177Y    R180 S1      
317m7161            VIA   -    MD0100PA01X+009902Y+083380X0190Y         S0      
327m7161            J32   -168        A01X+009902Y+083380X0205Y0590R090 S1      
317m7162            VIA   -    MD0080PA01X+032536Y+089876X0160Y    R180 S0      
327m7162            U26   -J69        A01X+032720Y+089980X0177Y    R180 S1      
317m7162            VIA   -    MD0100PA01X+009902Y+079699X0190Y         S0      
327m7162            J32   -157        A01X+009902Y+079699X0205Y0590R090 S1      
317m7163            VIA   -    MD0080PA01X+031796Y+096892X0160Y    R180 S0      
327m7163            U26   -AL71       A01X+031980Y+096996X0177Y    R180 S1      
317m7163            VIA   -    MD0100PA01X+011517Y+093754X0190Y         S0      
327m7163            J32   -55         A01X+011517Y+093754X0205Y0590R090 S1      
317m7164            VIA   -    MD0080PA01X+031796Y+094978X0160Y    R180 S0      
327m7164            U26   -AE71       A01X+031980Y+095083X0177Y    R180 S1      
317m7164            VIA   -    MD0100PA01X+011517Y+090073X0190Y         S0      
327m7164            J32   -44         A01X+011517Y+090073X0205Y0590R090 S1      
317m7165            VIA   -    MD0080PA01X+031796Y+093065X0160Y    R180 S0      
327m7165            U26   -W71        A01X+031980Y+093169X0177Y    R180 S1      
317m7165            VIA   -    MD0100PA01X+011517Y+086392X0190Y         S0      
327m7165            J32   -33         A01X+011517Y+086392X0205Y0590R090 S1      
317m7166            VIA   -    MD0080PA01X+031796Y+091151X0160Y    R180 S0      
327m7166            U26   -N71        A01X+031980Y+091256X0177Y    R180 S1      
317m7166            VIA   -    MD0100PA01X+011517Y+082711X0190Y         S0      
327m7166            J32   -22         A01X+011517Y+082711X0205Y0590R090 S1      
317m7167            VIA   -    MD0080PA01X+031796Y+089238X0160Y    R180 S0      
327m7167            U26   -G71        A01X+031980Y+089343X0177Y    R180 S1      
317m7167            VIA   -    MD0100PA01X+011517Y+079030X0190Y         S0      
327m7167            J32   -11         A01X+011517Y+079030X0205Y0590R090 S1      
317m7168            VIA   -    MD0080PA01X+032351Y+097210X0160Y    R180 S0      
327m7168            U26   -AM69       A01X+032535Y+097315X0177Y    R180 S1      
317m7168            VIA   -    MD0100PA01X+009902Y+094089X0190Y         S0      
327m7168            J32   -200        A01X+009902Y+094089X0205Y0590R090 S1      
317m7169            VIA   -    MD0080PA01X+032351Y+095297X0160Y    R180 S0      
327m7169            U26   -AF69       A01X+032535Y+095402X0177Y    R180 S1      
317m7169            VIA   -    MD0100PA01X+009902Y+090408X0190Y         S0      
327m7169            J32   -189        A01X+009902Y+090408X0205Y0590R090 S1      
317m7170            VIA   -    MD0080PA01X+032351Y+093384X0160Y    R180 S0      
327m7170            U26   -Y69        A01X+032535Y+093488X0177Y    R180 S1      
317m7170            VIA   -    MD0100PA01X+009902Y+086726X0190Y         S0      
327m7170            J32   -178        A01X+009902Y+086726X0205Y0590R090 S1      
317m7171            VIA   -    MD0080PA01X+032351Y+091470X0160Y    R180 S0      
327m7171            U26   -P69        A01X+032535Y+091575X0177Y    R180 S1      
317m7171            VIA   -    MD0100PA01X+009902Y+083045X0190Y         S0      
327m7171            J32   -167        A01X+009902Y+083045X0205Y0590R090 S1      
317m7172            VIA   -    MD0080PA01X+032351Y+089557X0160Y    R180 S0      
327m7172            U26   -H69        A01X+032535Y+089662X0177Y    R180 S1      
317m7172            VIA   -    MD0100PA01X+009902Y+079364X0190Y         S0      
327m7172            J32   -156        A01X+009902Y+079364X0205Y0590R090 S1      
317m7173            VIA   -    MD0080PA01X+031981Y+097210X0160Y    R180 S0      
327m7173            U26   -AM70       A01X+032164Y+097315X0177Y    R180 S1      
317m7173            VIA   -    MD0100PA01X+011517Y+094089X0190Y         S0      
327m7173            J32   -56         A01X+011517Y+094089X0205Y0590R090 S1      
317m7174            VIA   -    MD0080PA01X+031981Y+095297X0160Y    R180 S0      
327m7174            U26   -AF70       A01X+032164Y+095402X0177Y    R180 S1      
317m7174            VIA   -    MD0100PA01X+011517Y+090408X0190Y         S0      
327m7174            J32   -45         A01X+011517Y+090408X0205Y0590R090 S1      
317m7175            VIA   -    MD0080PA01X+031981Y+093384X0160Y    R180 S0      
327m7175            U26   -Y70        A01X+032164Y+093488X0177Y    R180 S1      
317m7175            VIA   -    MD0100PA01X+011517Y+086726X0190Y         S0      
327m7175            J32   -34         A01X+011517Y+086726X0205Y0590R090 S1      
317m7176            VIA   -    MD0080PA01X+031981Y+091470X0160Y    R180 S0      
327m7176            U26   -P70        A01X+032164Y+091575X0177Y    R180 S1      
317m7176            VIA   -    MD0100PA01X+011517Y+083045X0190Y         S0      
327m7176            J32   -23         A01X+011517Y+083045X0205Y0590R090 S1      
317m7177            VIA   -    MD0080PA01X+031981Y+089557X0160Y    R180 S0      
327m7177            U26   -H70        A01X+032164Y+089662X0177Y    R180 S1      
317m7177            VIA   -    MD0100PA01X+011517Y+079364X0190Y         S0      
327m7177            J32   -12         A01X+011517Y+079364X0205Y0590R090 S1      
317m7178            VIA   -    MD0080PA01X+032351Y+090832X0160Y    R180 S0      
327m7178            U26   -M69        A01X+032535Y+090937X0177Y    R180 S1      
317m7178            VIA   -    MD0100PA01X+011517Y+082042X0190Y         S0      
327m7178            J32   -20         A01X+011517Y+082042X0205Y0590R090 S1      
317m7179            VIA   -    MD0080PA01X+031796Y+090514X0160Y    R180 S0      
327m7179            U26   -L71        A01X+031980Y+090618X0177Y    R180 S1      
317m7179            VIA   -    MD0100PA01X+011517Y+081372X0190Y         S0      
327m7179            J32   -18         A01X+011517Y+081372X0205Y0590R090 S1      
317m7180            VIA   -    MD0080PA01X+032536Y+090514X0160Y    R180 S0      
327m7180            U26   -L69        A01X+032720Y+090618X0177Y    R180 S1      
317m7180            VIA   -    MD0100PA01X+009902Y+081038X0190Y         S0      
327m7180            J32   -161        A01X+009902Y+081038X0205Y0590R090 S1      
317m7181            VIA   -    MD0080PA01X+031981Y+090195X0160Y    R180 S0      
327m7181            U26   -K70        A01X+032164Y+090299X0177Y    R180 S1      
317m7181            VIA   -    MD0100PA01X+009902Y+080368X0190Y         S0      
327m7181            J32   -159        A01X+009902Y+080368X0205Y0590R090 S1      
317m7182            VIA   -    MD0080PA01X+032351Y+090195X0160Y    R180 S0      
327m7182            U26   -K69        A01X+032535Y+090299X0177Y    R180 S1      
317m7182            VIA   -    MD0100PA01X+011517Y+080703X0190Y         S0      
327m7182            J32   -16         A01X+011517Y+080703X0205Y0590R090 S1      
317m7183            VIA   -    MD0080PA01X+031796Y+089876X0160Y    R180 S0      
327m7183            U26   -J71        A01X+031980Y+089980X0177Y    R180 S1      
317m7183            VIA   -    MD0100PA01X+011517Y+080034X0190Y         S0      
327m7183            J32   -14         A01X+011517Y+080034X0205Y0590R090 S1      
317m7184            VIA   -    MD0080PA01X+032536Y+089238X0160Y    R180 S0      
327m7184            U26   -G69        A01X+032720Y+089343X0177Y    R180 S1      
317m7184            VIA   -    MD0100PA01X+009902Y+078695X0190Y         S0      
327m7184            J32   -154        A01X+009902Y+078695X0205Y0590R090 S1      
317m7185            VIA   -    MD0080PA01X+032536Y+096254X0160Y    R180 S0      
327m7185            U26   -AJ69       A01X+032720Y+096358X0177Y    R180 S1      
317m7185            VIA   -    MD0100PA01X+009902Y+092081X0190Y         S0      
327m7185            J32   -194        A01X+009902Y+092081X0205Y0590R090 S1      
317m7186            VIA   -    MD0080PA01X+031981Y+095935X0160Y    R180 S0      
327m7186            U26   -AH70       A01X+032164Y+096040X0177Y    R180 S1      
317m7186            VIA   -    MD0100PA01X+009902Y+091412X0190Y         S0      
327m7186            J32   -192        A01X+009902Y+091412X0205Y0590R090 S1      
317m7187            VIA   -    MD0080PA01X+031981Y+088919X0160Y    R180 S0      
327m7187            U26   -F70        A01X+032164Y+089024X0177Y    R180 S1      
317m7187            VIA   -    MD0100PA01X+009902Y+078026X0190Y         S0      
327m7187            J32   -152        A01X+009902Y+078026X0205Y0590R090 S1      
317m7188            VIA   -    MD0080PA01X+032351Y+095935X0160Y    R180 S0      
327m7188            U26   -AH69       A01X+032535Y+096040X0177Y    R180 S1      
317m7188            VIA   -    MD0100PA01X+011517Y+091746X0190Y         S0      
327m7188            J32   -49         A01X+011517Y+091746X0205Y0590R090 S1      
317m7189            VIA   -    MD0080PA01X+031796Y+095616X0160Y    R180 S0      
327m7189            U26   -AG71       A01X+031980Y+095721X0177Y    R180 S1      
317m7189            VIA   -    MD0100PA01X+011517Y+091077X0190Y         S0      
327m7189            J32   -47         A01X+011517Y+091077X0205Y0590R090 S1      
317m7190            VIA   -    MD0080PA01X+032536Y+094978X0160Y    R180 S0      
327m7190            U26   -AE69       A01X+032720Y+095083X0177Y    R180 S1      
317m7190            VIA   -    MD0100PA01X+009902Y+089738X0190Y         S0      
327m7190            J32   -187        A01X+009902Y+089738X0205Y0590R090 S1      
317m7191            VIA   -    MD0080PA01X+031981Y+094659X0160Y    R180 S0      
327m7191            U26   -AD70       A01X+032164Y+094764X0177Y    R180 S1      
317m7191            VIA   -    MD0100PA01X+009902Y+089069X0190Y         S0      
327m7191            J32   -185        A01X+009902Y+089069X0205Y0590R090 S1      
317m7192            VIA   -    MD0080PA01X+032351Y+094659X0160Y    R180 S0      
327m7192            U26   -AD69       A01X+032535Y+094764X0177Y    R180 S1      
317m7192            VIA   -    MD0100PA01X+011517Y+089404X0190Y         S0      
327m7192            J32   -42         A01X+011517Y+089404X0205Y0590R090 S1      
317m7193            VIA   -    MD0080PA01X+031796Y+094340X0160Y    R180 S0      
327m7193            U26   -AC71       A01X+031980Y+094445X0177Y    R180 S1      
317m7193            VIA   -    MD0100PA01X+011517Y+088734X0190Y         S0      
327m7193            J32   -40         A01X+011517Y+088734X0205Y0590R090 S1      
317m7194            VIA   -    MD0080PA01X+032536Y+094340X0160Y    R180 S0      
327m7194            U26   -AC69       A01X+032720Y+094445X0177Y    R180 S1      
317m7194            VIA   -    MD0100PA01X+009902Y+088400X0190Y         S0      
327m7194            J32   -183        A01X+009902Y+088400X0205Y0590R090 S1      
317m7195            VIA   -    MD0080PA01X+031981Y+094021X0160Y    R180 S0      
327m7195            U26   -AB70       A01X+032164Y+094126X0177Y    R180 S1      
317m7195            VIA   -    MD0100PA01X+009902Y+087730X0190Y         S0      
327m7195            J32   -181        A01X+009902Y+087730X0205Y0590R090 S1      
317m7196            VIA   -    MD0080PA01X+032351Y+094021X0160Y    R180 S0      
327m7196            U26   -AB69       A01X+032535Y+094126X0177Y    R180 S1      
317m7196            VIA   -    MD0100PA01X+011517Y+088065X0190Y         S0      
327m7196            J32   -38         A01X+011517Y+088065X0205Y0590R090 S1      
317m7197            VIA   -    MD0080PA01X+031796Y+093702X0160Y    R180 S0      
327m7197            U26   -AA71       A01X+031980Y+093807X0177Y    R180 S1      
317m7197            VIA   -    MD0100PA01X+011517Y+087396X0190Y         S0      
327m7197            J32   -36         A01X+011517Y+087396X0205Y0590R090 S1      
317m7198            VIA   -    MD0080PA01X+032351Y+088919X0160Y    R180 S0      
327m7198            U26   -F69        A01X+032535Y+089024X0177Y    R180 S1      
317m7198            VIA   -    MD0100PA01X+011517Y+078360X0190Y         S0      
327m7198            J32   -9          A01X+011517Y+078360X0205Y0590R090 S1      
317m7199            VIA   -    MD0080PA01X+032536Y+093065X0160Y    R180 S0      
327m7199            U26   -W69        A01X+032720Y+093169X0177Y    R180 S1      
317m7199            VIA   -    MD0100PA01X+009902Y+086057X0190Y         S0      
327m7199            J32   -176        A01X+009902Y+086057X0205Y0590R090 S1      
317m7200            VIA   -    MD0080PA01X+031981Y+092746X0160Y    R180 S0      
327m7200            U26   -V70        A01X+032164Y+092850X0177Y    R180 S1      
317m7200            VIA   -    MD0100PA01X+009902Y+085388X0190Y         S0      
327m7200            J32   -174        A01X+009902Y+085388X0205Y0590R090 S1      
317m7201            VIA   -    MD0080PA01X+032351Y+092746X0160Y    R180 S0      
327m7201            U26   -V69        A01X+032535Y+092850X0177Y    R180 S1      
317m7201            VIA   -    MD0100PA01X+011517Y+085723X0190Y         S0      
327m7201            J32   -31         A01X+011517Y+085723X0205Y0590R090 S1      
317m7202            VIA   -    MD0080PA01X+031796Y+092427X0160Y    R180 S0      
327m7202            U26   -U71        A01X+031980Y+092532X0177Y    R180 S1      
317m7202            VIA   -    MD0100PA01X+011517Y+085053X0190Y         S0      
327m7202            J32   -29         A01X+011517Y+085053X0205Y0590R090 S1      
317m7203            VIA   -    MD0080PA01X+032536Y+092427X0160Y    R180 S0      
327m7203            U26   -U69        A01X+032720Y+092532X0177Y    R180 S1      
317m7203            VIA   -    MD0100PA01X+009902Y+084719X0190Y         S0      
327m7203            J32   -172        A01X+009902Y+084719X0205Y0590R090 S1      
317m7204            VIA   -    MD0080PA01X+031981Y+092108X0160Y    R180 S0      
327m7204            U26   -T70        A01X+032164Y+092213X0177Y    R180 S1      
317m7204            VIA   -    MD0100PA01X+009902Y+084049X0190Y         S0      
327m7204            J32   -170        A01X+009902Y+084049X0205Y0590R090 S1      
317m7205            VIA   -    MD0080PA01X+032351Y+092108X0160Y    R180 S0      
327m7205            U26   -T69        A01X+032535Y+092213X0177Y    R180 S1      
317m7205            VIA   -    MD0100PA01X+011517Y+084384X0190Y         S0      
327m7205            J32   -27         A01X+011517Y+084384X0205Y0590R090 S1      
317m7206            VIA   -    MD0080PA01X+031796Y+091789X0160Y    R180 S0      
327m7206            U26   -R71        A01X+031980Y+091894X0177Y    R180 S1      
317m7206            VIA   -    MD0100PA01X+011517Y+083715X0190Y         S0      
327m7206            J32   -25         A01X+011517Y+083715X0205Y0590R090 S1      
317m7207            VIA   -    MD0080PA01X+032536Y+091151X0160Y    R180 S0      
327m7207            U26   -N69        A01X+032720Y+091256X0177Y    R180 S1      
317m7207            VIA   -    MD0100PA01X+009902Y+082376X0190Y         S0      
327m7207            J32   -165        A01X+009902Y+082376X0205Y0590R090 S1      
317m7208            VIA   -    MD0080PA01X+031981Y+090832X0160Y    R180 S0      
327m7208            U26   -M70        A01X+032164Y+090937X0177Y    R180 S1      
317m7208            VIA   -    MD0100PA01X+009902Y+081707X0190Y         S0      
327m7208            J32   -163        A01X+009902Y+081707X0205Y0590R090 S1      
317m7209            VIA   -    MD0080PA01X+031796Y+088600X0160Y    R180 S0      
327m7209            U26   -E71        A01X+031980Y+088705X0177Y    R180 S1      
317m7209            VIA   -    MD0100PA01X+011517Y+077691X0190Y         S0      
327m7209            J32   -7          A01X+011517Y+077691X0205Y0590R090 S1      
317m7210            VIA   -    MD0080PA01X+032536Y+099443X0160Y    R180 S0      
327m7210            U26   -AW69       A01X+032720Y+099547X0177Y    R180 S1      
317m7210            VIA   -    MD0100PA01X+009902Y+097100X0190Y         S0      
327m7210            J32   -209        A01X+009902Y+097100X0205Y0590R090 S1      
317m7211            VIA   -    MD0080PA01X+031981Y+099124X0160Y    R180 S0      
327m7211            U26   -AV70       A01X+032164Y+099228X0177Y    R180 S1      
317m7211            VIA   -    MD0100PA01X+011517Y+096766X0190Y         S0      
327m7211            J32   -64         A01X+011517Y+096766X0205Y0590R090 S1      
317m7212            VIA   -    MD0080PA01X+032536Y+098167X0160Y    R180 S0      
327m7212            U26   -AR69       A01X+032720Y+098272X0177Y    R180 S1      
317m7212            VIA   -    MD0100PA01X+009902Y+095762X0190Y         S0      
327m7212            J32   -205        A01X+009902Y+095762X0205Y0590R090 S1      
317m7213            VIA   -    MD0080PA01X+031981Y+097848X0160Y    R180 S0      
327m7213            U26   -AP70       A01X+032164Y+097953X0177Y    R180 S1      
317m7213            VIA   -    MD0100PA01X+009902Y+095093X0190Y         S0      
327m7213            J32   -203        A01X+009902Y+095093X0205Y0590R090 S1      
317m7214            VIA   -    MD0080PA01X+032351Y+097848X0160Y    R180 S0      
327m7214            U26   -AP69       A01X+032535Y+097953X0177Y    R180 S1      
317m7214            VIA   -    MD0100PA01X+011517Y+095427X0190Y         S0      
327m7214            J32   -60         A01X+011517Y+095427X0205Y0590R090 S1      
317m7215            VIA   -    MD0080PA01X+031796Y+097529X0160Y    R180 S0      
327m7215            U26   -AN71       A01X+031980Y+097634X0177Y    R180 S1      
317m7215            VIA   -    MD0100PA01X+011517Y+094758X0190Y         S0      
327m7215            J32   -58         A01X+011517Y+094758X0205Y0590R090 S1      
317m7216            VIA   -    MD0080PA01X+032536Y+096892X0160Y    R180 S0      
327m7216            U26   -AL69       A01X+032720Y+096996X0177Y    R180 S1      
317m7216            VIA   -    MD0100PA01X+009902Y+093419X0190Y         S0      
327m7216            J32   -198        A01X+009902Y+093419X0205Y0590R090 S1      
317m7217            VIA   -    MD0080PA01X+031981Y+096573X0160Y    R180 S0      
327m7217            U26   -AK70       A01X+032164Y+096677X0177Y    R180 S1      
317m7217            VIA   -    MD0100PA01X+009902Y+092750X0190Y         S0      
327m7217            J32   -196        A01X+009902Y+092750X0205Y0590R090 S1      
317m7218            VIA   -    MD0080PA01X+032351Y+096573X0160Y    R180 S0      
327m7218            U26   -AK69       A01X+032535Y+096677X0177Y    R180 S1      
317m7218            VIA   -    MD0100PA01X+011517Y+093085X0190Y         S0      
327m7218            J32   -53         A01X+011517Y+093085X0205Y0590R090 S1      
317m7219            VIA   -    MD0080PA01X+031796Y+096254X0160Y    R180 S0      
327m7219            U26   -AJ71       A01X+031980Y+096358X0177Y    R180 S1      
317m7219            VIA   -    MD0100PA01X+011517Y+092416X0190Y         S0      
327m7219            J32   -51         A01X+011517Y+092416X0205Y0590R090 S1      
317m7220            VIA   -    MD0080PA01X+032351Y+100399X0160Y    R180 S0      
327m7220            U26   -BB69       A01X+032535Y+100504X0177Y    R180 S1      
317m7220            VIA   -    MD0100PA01X+011517Y+099443X0190Y         S0      
327m7220            J32   -72         A01X+011517Y+099443X0205Y0590R090 S1      
317m7221            VIA   -    MD0080PA01X+031981Y+100399X0160Y    R180 S0      
327m7221            U26   -BB70       A01X+032164Y+100504X0177Y    R180 S1      
317m7221            VIA   -    MD0100PA01X+009902Y+099108X0190Y         S0      
327m7221            J32   -215        A01X+009902Y+099108X0205Y0590R090 S1      
317m7222            VIA   -    MD0080PA01X+031796Y+100080X0160Y    R180 S0      
327m7222            U26   -BA71       A01X+031980Y+100185X0177Y    R180 S1      
317m7222            VIA   -    MD0100PA01X+011517Y+098774X0190Y         S0      
327m7222            J32   -70         A01X+011517Y+098774X0205Y0590R090 S1      
317m7223            VIA   -    MD0080PA01X+032536Y+100080X0160Y    R180 S0      
327m7223            U26   -BA69       A01X+032720Y+100185X0177Y    R180 S1      
317m7223            VIA   -    MD0100PA01X+009902Y+098439X0190Y         S0      
327m7223            J32   -213        A01X+009902Y+098439X0205Y0590R090 S1      
317m7224            VIA   -    MD0080PA01X+032351Y+099762X0160Y    R180 S0      
327m7224            U26   -AY69       A01X+032535Y+099866X0177Y    R180 S1      
317m7224            VIA   -    MD0100PA01X+011517Y+098104X0190Y         S0      
327m7224            J32   -68         A01X+011517Y+098104X0205Y0590R090 S1      
317m7225            VIA   -    MD0080PA01X+031981Y+099762X0160Y    R180 S0      
327m7225            U26   -AY70       A01X+032164Y+099866X0177Y    R180 S1      
317m7225            VIA   -    MD0100PA01X+009902Y+097770X0190Y         S0      
327m7225            J32   -211        A01X+009902Y+097770X0205Y0590R090 S1      
317m7226            VIA   -    MD0080PA01X+031796Y+099443X0160Y    R180 S0      
327m7226            U26   -AW71       A01X+031980Y+099547X0177Y    R180 S1      
317m7226            VIA   -    MD0100PA01X+011517Y+097435X0190Y         S0      
327m7226            J32   -66         A01X+011517Y+097435X0205Y0590R090 S1      
317m7227            VIA   -    MD0080PA01X+032536Y+098805X0160Y    R180 S0      
327m7227            U26   -AU69       A01X+032720Y+098910X0177Y    R180 S1      
317m7227            VIA   -    MD0100PA01X+009902Y+096431X0190Y         S0      
327m7227            J32   -207        A01X+009902Y+096431X0205Y0590R090 S1      
317m7228            VIA   -    MD0080PA01X+031796Y+100718X0160Y    R180 S0      
327m7228            U26   -BC71       A01X+031980Y+100823X0177Y    R180 S1      
317m7228            VIA   -    MD0100PA01X+009902Y+099778X0190Y         S0      
327m7228            J32   -217        A01X+009902Y+099778X0205Y0590R090 S1      
317m7229            VIA   -    MD0080PA01X+031981Y+101037X0160Y    R180 S0      
327m7229            U26   -BD70       A01X+032164Y+101142X0177Y    R180 S1      
317m7229            VIA   -    MD0100PA01X+009902Y+100112X0190Y         S0      
327m7229            J32   -218        A01X+009902Y+100112X0205Y0590R090 S1      
317m7230            VIA   -    MD0080PA01X+032351Y+098486X0160Y    R180 S0      
327m7230            U26   -AT69       A01X+032535Y+098591X0177Y    R180 S1      
317m7230            VIA   -    MD0100PA18X+012067Y+096097X0190Y    R180 S0      
327m7230            R504  -2          A18X+012067Y+096097X0198Y0197R180 S2      
327m7231            J32   -62         A01X+011517Y+096097X0205Y0590R090 S1      
317m7231            VIA   -    MD0100PA00X+011517Y+096097X0190Y         S0      
327m7231            R504  -1          A18X+011752Y+096097X0198Y0197R180 S2      
317m7232            VIA   -    MD0080PA01X+129713Y+105357X0160Y         S0      
327m7232            U25   -BP70       A01X+129897Y+105252X0177Y    R180 S1      
317m7232            VIA   -    MD0100PA01X+109131Y+106470X0190Y         S0      
327m7232            J21   -87         A01X+109131Y+106470X0205Y0590R090 S1      
317m7233            VIA   -    MD0080PA01X+129528Y+104400X0160Y         S0      
327m7233            U25   -BL71       A01X+129712Y+104295X0177Y    R180 S1      
317m7233            VIA   -    MD0100PA01X+107517Y+105132X0190Y         S0      
327m7233            J21   -227        A01X+107517Y+105132X0205Y0590R090 S1      
317m7234            VIA   -    MD0080PA01X+129713Y+106632X0160Y         S0      
327m7234            U25   -BV70       A01X+129897Y+106528X0177Y    R180 S1      
317m7234            VIA   -    MD0100PA01X+109131Y+108478X0190Y         S0      
327m7234            J21   -93         A01X+109131Y+108478X0205Y0590R090 S1      
317m7235            VIA   -    MD0080PA01X+130083Y+114924X0160Y         S0      
327m7235            U25   -DD69       A01X+130267Y+114819X0177Y    R180 S1      
317m7235            VIA   -    MD0100PA01X+107517Y+123872X0190Y         S0      
327m7235            J21   -283        A01X+107517Y+123872X0205Y0590R090 S1      
317m7236            VIA   -    MD0080PA01X+130083Y+113010X0160Y         S0      
327m7236            U25   -CV69       A01X+130267Y+112906X0177Y    R180 S1      
317m7236            VIA   -    MD0100PA01X+107517Y+120191X0190Y         S0      
327m7236            J21   -272        A01X+107517Y+120191X0205Y0590R090 S1      
317m7237            VIA   -    MD0080PA01X+130083Y+111097X0160Y         S0      
327m7237            U25   -CM69       A01X+130267Y+110992X0177Y    R180 S1      
317m7237            VIA   -    MD0100PA01X+107517Y+116510X0190Y         S0      
327m7237            J21   -261        A01X+107517Y+116510X0205Y0590R090 S1      
317m7238            VIA   -    MD0080PA01X+130083Y+109184X0160Y         S0      
327m7238            U25   -CF69       A01X+130267Y+109079X0177Y    R180 S1      
317m7238            VIA   -    MD0100PA01X+107517Y+112829X0190Y         S0      
327m7238            J21   -250        A01X+107517Y+112829X0205Y0590R090 S1      
317m7239            VIA   -    MD0080PA01X+130083Y+107270X0160Y         S0      
327m7239            U25   -BY69       A01X+130267Y+107165X0177Y    R180 S1      
317m7239            VIA   -    MD0100PA01X+107517Y+109148X0190Y         S0      
327m7239            J21   -239        A01X+107517Y+109148X0205Y0590R090 S1      
317m7240            VIA   -    MD0080PA01X+129713Y+114286X0160Y         S0      
327m7240            U25   -DB70       A01X+129897Y+114181X0177Y    R180 S1      
317m7240            VIA   -    MD0100PA01X+109131Y+123203X0190Y         S0      
327m7240            J21   -137        A01X+109131Y+123203X0205Y0590R090 S1      
317m7241            VIA   -    MD0080PA01X+129713Y+112372X0160Y         S0      
327m7241            U25   -CT70       A01X+129897Y+112268X0177Y    R180 S1      
317m7241            VIA   -    MD0100PA01X+109131Y+119522X0190Y         S0      
327m7241            J21   -126        A01X+109131Y+119522X0205Y0590R090 S1      
317m7242            VIA   -    MD0080PA01X+129713Y+110459X0160Y         S0      
327m7242            U25   -CK70       A01X+129897Y+110354X0177Y    R180 S1      
317m7242            VIA   -    MD0100PA01X+109131Y+115841X0190Y         S0      
327m7242            J21   -115        A01X+109131Y+115841X0205Y0590R090 S1      
317m7243            VIA   -    MD0080PA01X+129713Y+108546X0160Y         S0      
327m7243            U25   -CD70       A01X+129897Y+108441X0177Y    R180 S1      
317m7243            VIA   -    MD0100PA01X+109131Y+112160X0190Y         S0      
327m7243            J21   -104        A01X+109131Y+112160X0205Y0590R090 S1      
317m7244            VIA   -    MD0080PA01X+129528Y+106951X0160Y         S0      
327m7244            U25   -BW71       A01X+129712Y+106846X0177Y    R180 S1      
317m7244            VIA   -    MD0100PA01X+109131Y+108813X0190Y         S0      
327m7244            J21   -94         A01X+109131Y+108813X0205Y0590R090 S1      
317m7245            VIA   -    MD0080PA01X+130268Y+114605X0160Y         S0      
327m7245            U25   -DC69       A01X+130452Y+114500X0177Y    R180 S1      
317m7245            VIA   -    MD0100PA01X+107517Y+123537X0190Y         S0      
327m7245            J21   -282        A01X+107517Y+123537X0205Y0590R090 S1      
317m7246            VIA   -    MD0080PA01X+130268Y+112691X0160Y         S0      
327m7246            U25   -CU69       A01X+130452Y+112587X0177Y    R180 S1      
317m7246            VIA   -    MD0100PA01X+107517Y+119856X0190Y         S0      
327m7246            J21   -271        A01X+107517Y+119856X0205Y0590R090 S1      
317m7247            VIA   -    MD0080PA01X+130268Y+110778X0160Y         S0      
327m7247            U25   -CL69       A01X+130452Y+110673X0177Y    R180 S1      
317m7247            VIA   -    MD0100PA01X+107517Y+116175X0190Y         S0      
327m7247            J21   -260        A01X+107517Y+116175X0205Y0590R090 S1      
317m7248            VIA   -    MD0080PA01X+130268Y+108865X0160Y         S0      
327m7248            U25   -CE69       A01X+130452Y+108760X0177Y    R180 S1      
317m7248            VIA   -    MD0100PA01X+107517Y+112494X0190Y         S0      
327m7248            J21   -249        A01X+107517Y+112494X0205Y0590R090 S1      
317m7249            VIA   -    MD0080PA01X+130268Y+106951X0160Y         S0      
327m7249            U25   -BW69       A01X+130452Y+106846X0177Y    R180 S1      
317m7249            VIA   -    MD0100PA01X+107517Y+108813X0190Y         S0      
327m7249            J21   -238        A01X+107517Y+108813X0205Y0590R090 S1      
317m7250            VIA   -    MD0080PA01X+129528Y+114605X0160Y         S0      
327m7250            U25   -DC71       A01X+129712Y+114500X0177Y    R180 S1      
317m7250            VIA   -    MD0100PA01X+109131Y+123537X0190Y         S0      
327m7250            J21   -138        A01X+109131Y+123537X0205Y0590R090 S1      
317m7251            VIA   -    MD0080PA01X+129528Y+112691X0160Y         S0      
327m7251            U25   -CU71       A01X+129712Y+112587X0177Y    R180 S1      
317m7251            VIA   -    MD0100PA01X+109131Y+119856X0190Y         S0      
327m7251            J21   -127        A01X+109131Y+119856X0205Y0590R090 S1      
317m7252            VIA   -    MD0080PA01X+129528Y+110778X0160Y         S0      
327m7252            U25   -CL71       A01X+129712Y+110673X0177Y    R180 S1      
317m7252            VIA   -    MD0100PA01X+109131Y+116175X0190Y         S0      
327m7252            J21   -116        A01X+109131Y+116175X0205Y0590R090 S1      
317m7253            VIA   -    MD0080PA01X+129528Y+108865X0160Y         S0      
327m7253            U25   -CE71       A01X+129712Y+108760X0177Y    R180 S1      
317m7253            VIA   -    MD0100PA01X+109131Y+112494X0190Y         S0      
327m7253            J21   -105        A01X+109131Y+112494X0205Y0590R090 S1      
317m7254            VIA   -    MD0080PA01X+130268Y+110140X0160Y         S0      
327m7254            U25   -CJ69       A01X+130452Y+110036X0177Y    R180 S1      
317m7254            VIA   -    MD0100PA01X+109131Y+115171X0190Y         S0      
327m7254            J21   -113        A01X+109131Y+115171X0205Y0590R090 S1      
317m7255            VIA   -    MD0080PA01X+129713Y+109821X0160Y         S0      
327m7255            U25   -CH70       A01X+129897Y+109717X0177Y    R180 S1      
317m7255            VIA   -    MD0100PA01X+109131Y+114502X0190Y         S0      
327m7255            J21   -111        A01X+109131Y+114502X0205Y0590R090 S1      
317m7256            VIA   -    MD0080PA01X+130083Y+109821X0160Y         S0      
327m7256            U25   -CH69       A01X+130267Y+109717X0177Y    R180 S1      
317m7256            VIA   -    MD0100PA01X+107517Y+114167X0190Y         S0      
327m7256            J21   -254        A01X+107517Y+114167X0205Y0590R090 S1      
317m7257            VIA   -    MD0080PA01X+129528Y+109502X0160Y         S0      
327m7257            U25   -CG71       A01X+129712Y+109398X0177Y    R180 S1      
317m7257            VIA   -    MD0100PA01X+107517Y+113498X0190Y         S0      
327m7257            J21   -252        A01X+107517Y+113498X0205Y0590R090 S1      
317m7258            VIA   -    MD0080PA01X+130268Y+109502X0160Y         S0      
327m7258            U25   -CG69       A01X+130452Y+109398X0177Y    R180 S1      
317m7258            VIA   -    MD0100PA01X+109131Y+113833X0190Y         S0      
327m7258            J21   -109        A01X+109131Y+113833X0205Y0590R090 S1      
317m7259            VIA   -    MD0080PA01X+129713Y+109184X0160Y         S0      
327m7259            U25   -CF70       A01X+129897Y+109079X0177Y    R180 S1      
317m7259            VIA   -    MD0100PA01X+109131Y+113163X0190Y         S0      
327m7259            J21   -107        A01X+109131Y+113163X0205Y0590R090 S1      
317m7260            VIA   -    MD0080PA01X+130083Y+108546X0160Y         S0      
327m7260            U25   -CD69       A01X+130267Y+108441X0177Y    R180 S1      
317m7260            VIA   -    MD0100PA01X+107517Y+111825X0190Y         S0      
327m7260            J21   -247        A01X+107517Y+111825X0205Y0590R090 S1      
317m7261            VIA   -    MD0080PA01X+130083Y+115561X0160Y         S0      
317m7261            VIA   -    MD0100PA01X+107517Y+125211X0190Y         S0      
327m7261            J21   -287        A01X+107517Y+125211X0205Y0590R090 S1      
327m7261            U25   -DF69       A01X+130267Y+115457X0177Y    R180 S1      
317m7262            VIA   -    MD0080PA01X+129528Y+115242X0160Y         S0      
327m7262            U25   -DE71       A01X+129712Y+115138X0177Y    R180 S1      
317m7262            VIA   -    MD0100PA01X+107517Y+124541X0190Y         S0      
327m7262            J21   -285        A01X+107517Y+124541X0205Y0590R090 S1      
317m7263            VIA   -    MD0080PA01X+129528Y+108227X0160Y         S0      
327m7263            U25   -CC71       A01X+129712Y+108122X0177Y    R180 S1      
317m7263            VIA   -    MD0100PA01X+107517Y+111156X0190Y         S0      
327m7263            J21   -245        A01X+107517Y+111156X0205Y0590R090 S1      
317m7264            VIA   -    MD0080PA01X+130268Y+115242X0160Y         S0      
327m7264            U25   -DE69       A01X+130452Y+115138X0177Y    R180 S1      
317m7264            VIA   -    MD0100PA01X+109131Y+124876X0190Y         S0      
327m7264            J21   -142        A01X+109131Y+124876X0205Y0590R090 S1      
317m7265            VIA   -    MD0080PA01X+129713Y+114924X0160Y         S0      
327m7265            U25   -DD70       A01X+129897Y+114819X0177Y    R180 S1      
317m7265            VIA   -    MD0100PA01X+109131Y+124207X0190Y         S0      
327m7265            J21   -140        A01X+109131Y+124207X0205Y0590R090 S1      
317m7266            VIA   -    MD0080PA01X+130083Y+114286X0160Y         S0      
327m7266            U25   -DB69       A01X+130267Y+114181X0177Y    R180 S1      
317m7266            VIA   -    MD0100PA01X+107517Y+122868X0190Y         S0      
327m7266            J21   -280        A01X+107517Y+122868X0205Y0590R090 S1      
317m7267            VIA   -    MD0080PA01X+129528Y+113967X0160Y         S0      
327m7267            U25   -DA71       A01X+129712Y+113862X0177Y    R180 S1      
317m7267            VIA   -    MD0100PA01X+107517Y+122199X0190Y         S0      
327m7267            J21   -278        A01X+107517Y+122199X0205Y0590R090 S1      
317m7268            VIA   -    MD0080PA01X+130268Y+113967X0160Y         S0      
327m7268            U25   -DA69       A01X+130452Y+113862X0177Y    R180 S1      
317m7268            VIA   -    MD0100PA01X+109131Y+122534X0190Y         S0      
327m7268            J21   -135        A01X+109131Y+122534X0205Y0590R090 S1      
317m7269            VIA   -    MD0080PA01X+129713Y+113648X0160Y         S0      
327m7269            U25   -CY70       A01X+129897Y+113543X0177Y    R180 S1      
317m7269            VIA   -    MD0100PA01X+109131Y+121864X0190Y         S0      
327m7269            J21   -133        A01X+109131Y+121864X0205Y0590R090 S1      
317m7270            VIA   -    MD0080PA01X+130083Y+113648X0160Y         S0      
327m7270            U25   -CY69       A01X+130267Y+113543X0177Y    R180 S1      
317m7270            VIA   -    MD0100PA01X+107517Y+121530X0190Y         S0      
327m7270            J21   -276        A01X+107517Y+121530X0205Y0590R090 S1      
317m7271            VIA   -    MD0080PA01X+129528Y+113329X0160Y         S0      
327m7271            U25   -CW71       A01X+129712Y+113224X0177Y    R180 S1      
317m7271            VIA   -    MD0100PA01X+107517Y+120860X0190Y         S0      
327m7271            J21   -274        A01X+107517Y+120860X0205Y0590R090 S1      
317m7272            VIA   -    MD0080PA01X+130268Y+113329X0160Y         S0      
327m7272            U25   -CW69       A01X+130452Y+113224X0177Y    R180 S1      
317m7272            VIA   -    MD0100PA01X+109131Y+121195X0190Y         S0      
327m7272            J21   -131        A01X+109131Y+121195X0205Y0590R090 S1      
317m7273            VIA   -    MD0080PA01X+129713Y+113010X0160Y         S0      
327m7273            U25   -CV70       A01X+129897Y+112906X0177Y    R180 S1      
327m7273            J21   -129        A01X+109131Y+120526X0205Y0590R090 S1      
317m7273            VIA   -    MD0100PA01X+109131Y+120526X0190Y         S0      
317m7274            VIA   -    MD0080PA01X+130268Y+108227X0160Y         S0      
327m7274            U25   -CC69       A01X+130452Y+108122X0177Y    R180 S1      
317m7274            VIA   -    MD0100PA01X+109131Y+111490X0190Y         S0      
327m7274            J21   -102        A01X+109131Y+111490X0205Y0590R090 S1      
317m7275            VIA   -    MD0080PA01X+130083Y+112372X0160Y         S0      
327m7275            U25   -CT69       A01X+130267Y+112268X0177Y    R180 S1      
317m7275            VIA   -    MD0100PA01X+107517Y+119187X0190Y         S0      
327m7275            J21   -269        A01X+107517Y+119187X0205Y0590R090 S1      
317m7276            VIA   -    MD0080PA01X+129528Y+112054X0160Y         S0      
327m7276            U25   -CR71       A01X+129712Y+111949X0177Y    R180 S1      
317m7276            VIA   -    MD0100PA01X+107517Y+118518X0190Y         S0      
327m7276            J21   -267        A01X+107517Y+118518X0205Y0590R090 S1      
317m7277            VIA   -    MD0080PA01X+130268Y+112054X0160Y         S0      
327m7277            U25   -CR69       A01X+130452Y+111949X0177Y    R180 S1      
317m7277            VIA   -    MD0100PA01X+109131Y+118852X0190Y         S0      
327m7277            J21   -124        A01X+109131Y+118852X0205Y0590R090 S1      
317m7278            VIA   -    MD0080PA01X+129713Y+111735X0160Y         S0      
327m7278            U25   -CP70       A01X+129897Y+111630X0177Y    R180 S1      
317m7278            VIA   -    MD0100PA01X+109131Y+118183X0190Y         S0      
327m7278            J21   -122        A01X+109131Y+118183X0205Y0590R090 S1      
317m7279            VIA   -    MD0080PA01X+130083Y+111735X0160Y         S0      
327m7279            U25   -CP69       A01X+130267Y+111630X0177Y    R180 S1      
317m7279            VIA   -    MD0100PA01X+107517Y+117848X0190Y         S0      
327m7279            J21   -265        A01X+107517Y+117848X0205Y0590R090 S1      
317m7280            VIA   -    MD0080PA01X+129528Y+111416X0160Y         S0      
327m7280            U25   -CN71       A01X+129712Y+111311X0177Y    R180 S1      
317m7280            VIA   -    MD0100PA01X+107517Y+117179X0190Y         S0      
327m7280            J21   -263        A01X+107517Y+117179X0205Y0590R090 S1      
317m7281            VIA   -    MD0080PA01X+130268Y+111416X0160Y         S0      
327m7281            U25   -CN69       A01X+130452Y+111311X0177Y    R180 S1      
317m7281            VIA   -    MD0100PA01X+109131Y+117514X0190Y         S0      
327m7281            J21   -120        A01X+109131Y+117514X0205Y0590R090 S1      
317m7282            VIA   -    MD0080PA01X+129713Y+111097X0160Y         S0      
327m7282            U25   -CM70       A01X+129897Y+110992X0177Y    R180 S1      
317m7282            VIA   -    MD0100PA01X+109131Y+116844X0190Y         S0      
327m7282            J21   -118        A01X+109131Y+116844X0205Y0590R090 S1      
317m7283            VIA   -    MD0080PA01X+130083Y+110459X0160Y         S0      
327m7283            U25   -CK69       A01X+130267Y+110354X0177Y    R180 S1      
317m7283            VIA   -    MD0100PA01X+107517Y+115506X0190Y         S0      
327m7283            J21   -258        A01X+107517Y+115506X0205Y0590R090 S1      
317m7284            VIA   -    MD0080PA01X+129528Y+110140X0160Y         S0      
327m7284            U25   -CJ71       A01X+129712Y+110036X0177Y    R180 S1      
317m7284            VIA   -    MD0100PA01X+107517Y+114837X0190Y         S0      
327m7284            J21   -256        A01X+107517Y+114837X0205Y0590R090 S1      
317m7285            VIA   -    MD0080PA01X+129713Y+107908X0160Y         S0      
327m7285            U25   -CB70       A01X+129897Y+107803X0177Y    R180 S1      
317m7285            VIA   -    MD0100PA01X+109131Y+110821X0190Y         S0      
327m7285            J21   -100        A01X+109131Y+110821X0205Y0590R090 S1      
317m7286            VIA   -    MD0080PA01X+129528Y+105038X0160Y         S0      
327m7286            U25   -BN71       A01X+129712Y+104933X0177Y    R180 S1      
317m7286            VIA   -    MD0100PA01X+107517Y+105801X0190Y         S0      
327m7286            J21   -229        A01X+107517Y+105801X0205Y0590R090 S1      
317m7287            VIA   -    MD0080PA01X+130083Y+104719X0160Y         S0      
327m7287            U25   -BM69       A01X+130267Y+104614X0177Y    R180 S1      
317m7287            VIA   -    MD0100PA01X+109131Y+105467X0190Y         S0      
327m7287            J21   -84         A01X+109131Y+105467X0205Y0590R090 S1      
317m7288            VIA   -    MD0080PA01X+130083Y+106632X0160Y         S0      
327m7288            U25   -BV69       A01X+130267Y+106528X0177Y    R180 S1      
317m7288            VIA   -    MD0100PA01X+107517Y+108144X0190Y         S0      
327m7288            J21   -236        A01X+107517Y+108144X0205Y0590R090 S1      
317m7289            VIA   -    MD0080PA01X+129528Y+106313X0160Y         S0      
327m7289            U25   -BU71       A01X+129712Y+106209X0177Y    R180 S1      
317m7289            VIA   -    MD0100PA01X+107517Y+107474X0190Y         S0      
327m7289            J21   -234        A01X+107517Y+107474X0205Y0590R090 S1      
317m7290            VIA   -    MD0080PA01X+130268Y+106313X0160Y         S0      
327m7290            U25   -BU69       A01X+130452Y+106209X0177Y    R180 S1      
317m7290            VIA   -    MD0100PA01X+109131Y+107809X0190Y         S0      
327m7290            J21   -91         A01X+109131Y+107809X0205Y0590R090 S1      
317m7291            VIA   -    MD0080PA01X+129713Y+105994X0160Y         S0      
327m7291            U25   -BT70       A01X+129897Y+105890X0177Y    R180 S1      
317m7291            VIA   -    MD0100PA01X+109131Y+107140X0190Y         S0      
327m7291            J21   -89         A01X+109131Y+107140X0205Y0590R090 S1      
317m7292            VIA   -    MD0080PA01X+130083Y+107908X0160Y         S0      
327m7292            U25   -CB69       A01X+130267Y+107803X0177Y    R180 S1      
317m7292            VIA   -    MD0100PA01X+107517Y+110486X0190Y         S0      
327m7292            J21   -243        A01X+107517Y+110486X0205Y0590R090 S1      
317m7293            VIA   -    MD0080PA01X+129528Y+107589X0160Y         S0      
327m7293            U25   -CA71       A01X+129712Y+107484X0177Y    R180 S1      
317m7293            VIA   -    MD0100PA01X+107517Y+109817X0190Y         S0      
327m7293            J21   -241        A01X+107517Y+109817X0205Y0590R090 S1      
317m7294            VIA   -    MD0080PA01X+130268Y+107589X0160Y         S0      
327m7294            U25   -CA69       A01X+130452Y+107484X0177Y    R180 S1      
317m7294            VIA   -    MD0100PA01X+109131Y+110152X0190Y         S0      
327m7294            J21   -98         A01X+109131Y+110152X0205Y0590R090 S1      
317m7295            VIA   -    MD0080PA01X+129713Y+107270X0160Y         S0      
327m7295            U25   -BY70       A01X+129897Y+107165X0177Y    R180 S1      
317m7295            VIA   -    MD0100PA01X+109131Y+109482X0190Y         S0      
327m7295            J21   -96         A01X+109131Y+109482X0205Y0590R090 S1      
317m7296            VIA   -    MD0080PA01X+129713Y+104081X0160Y         S0      
327m7296            U25   -BK70       A01X+129897Y+103976X0177Y    R180 S1      
317m7296            VIA   -    MD0100PA01X+109131Y+104797X0190Y         S0      
327m7296            J21   -82         A01X+109131Y+104797X0205Y0590R090 S1      
317m7297            VIA   -    MD0080PA01X+130083Y+104081X0160Y         S0      
327m7297            U25   -BK69       A01X+130267Y+103976X0177Y    R180 S1      
317m7297            VIA   -    MD0100PA01X+107517Y+104463X0190Y         S0      
327m7297            J21   -225        A01X+107517Y+104463X0205Y0590R090 S1      
317m7298            VIA   -    MD0080PA01X+130268Y+103762X0160Y         S0      
327m7298            U25   -BJ69       A01X+130452Y+103658X0177Y    R180 S1      
317m7298            VIA   -    MD0100PA01X+109131Y+104128X0190Y         S0      
327m7298            J21   -80         A01X+109131Y+104128X0205Y0590R090 S1      
317m7299            VIA   -    MD0080PA01X+129528Y+103762X0160Y         S0      
327m7299            U25   -BJ71       A01X+129712Y+103658X0177Y    R180 S1      
317m7299            VIA   -    MD0100PA01X+107517Y+103793X0190Y         S0      
327m7299            J21   -223        A01X+107517Y+103793X0205Y0590R090 S1      
317m7300            VIA   -    MD0080PA01X+129713Y+103443X0160Y         S0      
327m7300            U25   -BH70       A01X+129897Y+103339X0177Y    R180 S1      
317m7300            VIA   -    MD0100PA01X+109131Y+103459X0190Y         S0      
327m7300            J21   -78         A01X+109131Y+103459X0205Y0590R090 S1      
317m7301            VIA   -    MD0080PA01X+130083Y+103443X0160Y         S0      
327m7301            U25   -BH69       A01X+130267Y+103339X0177Y    R180 S1      
317m7301            VIA   -    MD0100PA01X+107517Y+103124X0190Y         S0      
327m7301            J21   -221        A01X+107517Y+103124X0205Y0590R090 S1      
317m7302            VIA   -    MD0080PA01X+130268Y+103124X0160Y         S0      
327m7302            U25   -BG69       A01X+130452Y+103020X0177Y    R180 S1      
317m7302            VIA   -    MD0100PA01X+109131Y+102789X0190Y         S0      
327m7302            J21   -76         A01X+109131Y+102789X0205Y0590R090 S1      
317m7303            VIA   -    MD0080PA01X+130268Y+105038X0160Y         S0      
327m7303            U25   -BN69       A01X+130452Y+104933X0177Y    R180 S1      
317m7303            VIA   -    MD0100PA01X+109131Y+106136X0190Y         S0      
327m7303            J21   -86         A01X+109131Y+106136X0205Y0590R090 S1      
317m7304            VIA   -    MD0080PA01X+130150Y+100718X0160Y    R180 S0      
327m7304            U25   -BC69       A01X+130334Y+100823X0177Y    R180 S1      
317m7304            VIA   -    MD0100PA01X+109131Y+100112X0190Y         S0      
327m7304            J21   -74         A01X+109131Y+100112X0205Y0590R090 S1      
317m7305            VIA   -    MD0080PA01X+130150Y+097529X0160Y    R180 S0      
327m7305            U25   -AN69       A01X+130334Y+097634X0177Y    R180 S1      
317m7305            VIA   -    MD0100PA01X+107517Y+094423X0190Y         S0      
327m7305            J21   -201        A01X+107517Y+094423X0205Y0590R090 S1      
317m7306            VIA   -    MD0080PA01X+130150Y+095616X0160Y    R180 S0      
327m7306            U25   -AG69       A01X+130334Y+095720X0177Y    R180 S1      
317m7306            VIA   -    MD0100PA01X+107517Y+090742X0190Y         S0      
327m7306            J21   -190        A01X+107517Y+090742X0205Y0590R090 S1      
317m7307            VIA   -    MD0080PA01X+130150Y+093702X0160Y    R180 S0      
327m7307            U25   -AA69       A01X+130334Y+093807X0177Y    R180 S1      
317m7307            VIA   -    MD0100PA01X+107517Y+087061X0190Y         S0      
327m7307            J21   -179        A01X+107517Y+087061X0205Y0590R090 S1      
317m7308            VIA   -    MD0080PA01X+130150Y+091789X0160Y    R180 S0      
327m7308            U25   -R69        A01X+130334Y+091894X0177Y    R180 S1      
317m7308            VIA   -    MD0100PA01X+107517Y+083380X0190Y         S0      
327m7308            J21   -168        A01X+107517Y+083380X0205Y0590R090 S1      
317m7309            VIA   -    MD0080PA01X+130150Y+089876X0160Y    R180 S0      
327m7309            U25   -J69        A01X+130334Y+089980X0177Y    R180 S1      
317m7309            VIA   -    MD0100PA01X+107517Y+079699X0190Y         S0      
327m7309            J21   -157        A01X+107517Y+079699X0205Y0590R090 S1      
317m7310            VIA   -    MD0080PA01X+129410Y+096891X0160Y    R180 S0      
327m7310            U25   -AL71       A01X+129594Y+096996X0177Y    R180 S1      
317m7310            VIA   -    MD0100PA01X+109131Y+093754X0190Y         S0      
327m7310            J21   -55         A01X+109131Y+093754X0205Y0590R090 S1      
317m7311            VIA   -    MD0080PA01X+129410Y+094978X0160Y    R180 S0      
327m7311            U25   -AE71       A01X+129594Y+095083X0177Y    R180 S1      
317m7311            VIA   -    MD0100PA01X+109131Y+090073X0190Y         S0      
327m7311            J21   -44         A01X+109131Y+090073X0205Y0590R090 S1      
317m7312            VIA   -    MD0080PA01X+129410Y+093065X0160Y    R180 S0      
327m7312            U25   -W71        A01X+129594Y+093169X0177Y    R180 S1      
317m7312            VIA   -    MD0100PA01X+109131Y+086392X0190Y         S0      
327m7312            J21   -33         A01X+109131Y+086392X0205Y0590R090 S1      
317m7313            VIA   -    MD0080PA01X+129410Y+091151X0160Y    R180 S0      
327m7313            U25   -N71        A01X+129594Y+091256X0177Y    R180 S1      
317m7313            VIA   -    MD0100PA01X+109131Y+082711X0190Y         S0      
327m7313            J21   -22         A01X+109131Y+082711X0205Y0590R090 S1      
317m7314            VIA   -    MD0080PA01X+129410Y+089238X0160Y    R180 S0      
327m7314            U25   -G71        A01X+129594Y+089343X0177Y    R180 S1      
317m7314            VIA   -    MD0100PA01X+109131Y+079030X0190Y         S0      
327m7314            J21   -11         A01X+109131Y+079030X0205Y0590R090 S1      
317m7315            VIA   -    MD0080PA01X+129965Y+097210X0160Y    R180 S0      
327m7315            U25   -AM69       A01X+130149Y+097315X0177Y    R180 S1      
317m7315            VIA   -    MD0100PA01X+107517Y+094089X0190Y         S0      
327m7315            J21   -200        A01X+107517Y+094089X0205Y0590R090 S1      
317m7316            VIA   -    MD0080PA01X+129965Y+095297X0160Y    R180 S0      
327m7316            U25   -AF69       A01X+130149Y+095402X0177Y    R180 S1      
317m7316            VIA   -    MD0100PA01X+107517Y+090408X0190Y         S0      
327m7316            J21   -189        A01X+107517Y+090408X0205Y0590R090 S1      
317m7317            VIA   -    MD0080PA01X+129965Y+093384X0160Y    R180 S0      
327m7317            U25   -Y69        A01X+130149Y+093488X0177Y    R180 S1      
317m7317            VIA   -    MD0100PA01X+107517Y+086726X0190Y         S0      
327m7317            J21   -178        A01X+107517Y+086726X0205Y0590R090 S1      
317m7318            VIA   -    MD0080PA01X+129965Y+091470X0160Y    R180 S0      
327m7318            U25   -P69        A01X+130149Y+091575X0177Y    R180 S1      
317m7318            VIA   -    MD0100PA01X+107517Y+083045X0190Y         S0      
327m7318            J21   -167        A01X+107517Y+083045X0205Y0590R090 S1      
317m7319            VIA   -    MD0080PA01X+129965Y+089557X0160Y    R180 S0      
327m7319            U25   -H69        A01X+130149Y+089662X0177Y    R180 S1      
317m7319            VIA   -    MD0100PA01X+107517Y+079364X0190Y         S0      
327m7319            J21   -156        A01X+107517Y+079364X0205Y0590R090 S1      
317m7320            VIA   -    MD0080PA01X+129595Y+097210X0160Y    R180 S0      
327m7320            U25   -AM70       A01X+129779Y+097315X0177Y    R180 S1      
317m7320            VIA   -    MD0100PA01X+109131Y+094089X0190Y         S0      
327m7320            J21   -56         A01X+109131Y+094089X0205Y0590R090 S1      
317m7321            VIA   -    MD0080PA01X+129595Y+095297X0160Y    R180 S0      
327m7321            U25   -AF70       A01X+129779Y+095402X0177Y    R180 S1      
317m7321            VIA   -    MD0100PA01X+109131Y+090408X0190Y         S0      
327m7321            J21   -45         A01X+109131Y+090408X0205Y0590R090 S1      
317m7322            VIA   -    MD0080PA01X+129595Y+093384X0160Y    R180 S0      
327m7322            U25   -Y70        A01X+129779Y+093488X0177Y    R180 S1      
317m7322            VIA   -    MD0100PA01X+109131Y+086726X0190Y         S0      
327m7322            J21   -34         A01X+109131Y+086726X0205Y0590R090 S1      
317m7323            VIA   -    MD0080PA01X+129595Y+091470X0160Y    R180 S0      
327m7323            U25   -P70        A01X+129779Y+091575X0177Y    R180 S1      
317m7323            VIA   -    MD0100PA01X+109131Y+083045X0190Y         S0      
327m7323            J21   -23         A01X+109131Y+083045X0205Y0590R090 S1      
317m7324            VIA   -    MD0080PA01X+129595Y+089557X0160Y    R180 S0      
327m7324            U25   -H70        A01X+129779Y+089662X0177Y    R180 S1      
317m7324            VIA   -    MD0100PA01X+109131Y+079364X0190Y         S0      
327m7324            J21   -12         A01X+109131Y+079364X0205Y0590R090 S1      
317m7325            VIA   -    MD0080PA01X+129965Y+090832X0160Y    R180 S0      
327m7325            U25   -M69        A01X+130149Y+090937X0177Y    R180 S1      
317m7325            VIA   -    MD0100PA01X+109131Y+082041X0190Y         S0      
327m7325            J21   -20         A01X+109131Y+082041X0205Y0590R090 S1      
317m7326            VIA   -    MD0080PA01X+129410Y+090513X0160Y    R180 S0      
327m7326            U25   -L71        A01X+129594Y+090618X0177Y    R180 S1      
317m7326            VIA   -    MD0100PA01X+109131Y+081372X0190Y         S0      
327m7326            J21   -18         A01X+109131Y+081372X0205Y0590R090 S1      
317m7327            VIA   -    MD0080PA01X+130150Y+090513X0160Y    R180 S0      
327m7327            U25   -L69        A01X+130334Y+090618X0177Y    R180 S1      
317m7327            VIA   -    MD0100PA01X+107517Y+081037X0190Y         S0      
327m7327            J21   -161        A01X+107517Y+081037X0205Y0590R090 S1      
317m7328            VIA   -    MD0080PA01X+129595Y+090195X0160Y    R180 S0      
327m7328            U25   -K70        A01X+129779Y+090299X0177Y    R180 S1      
317m7328            VIA   -    MD0100PA01X+107517Y+080368X0190Y         S0      
327m7328            J21   -159        A01X+107517Y+080368X0205Y0590R090 S1      
317m7329            VIA   -    MD0080PA01X+129965Y+090195X0160Y    R180 S0      
327m7329            U25   -K69        A01X+130149Y+090299X0177Y    R180 S1      
317m7329            VIA   -    MD0100PA01X+109131Y+080703X0190Y         S0      
327m7329            J21   -16         A01X+109131Y+080703X0205Y0590R090 S1      
317m7330            VIA   -    MD0080PA01X+129410Y+089876X0160Y    R180 S0      
327m7330            U25   -J71        A01X+129594Y+089980X0177Y    R180 S1      
317m7330            VIA   -    MD0100PA01X+109131Y+080034X0190Y         S0      
327m7330            J21   -14         A01X+109131Y+080034X0205Y0590R090 S1      
317m7331            VIA   -    MD0080PA01X+130150Y+089238X0160Y    R180 S0      
327m7331            U25   -G69        A01X+130334Y+089343X0177Y    R180 S1      
317m7331            VIA   -    MD0100PA01X+107517Y+078695X0190Y         S0      
327m7331            J21   -154        A01X+107517Y+078695X0205Y0590R090 S1      
317m7332            VIA   -    MD0080PA01X+130150Y+096254X0160Y    R180 S0      
327m7332            U25   -AJ69       A01X+130334Y+096358X0177Y    R180 S1      
317m7332            VIA   -    MD0100PA01X+107517Y+092081X0190Y         S0      
327m7332            J21   -194        A01X+107517Y+092081X0205Y0590R090 S1      
317m7333            VIA   -    MD0080PA01X+129595Y+095935X0160Y    R180 S0      
327m7333            U25   -AH70       A01X+129779Y+096039X0177Y    R180 S1      
317m7333            VIA   -    MD0100PA01X+107517Y+091411X0190Y         S0      
327m7333            J21   -192        A01X+107517Y+091411X0205Y0590R090 S1      
317m7334            VIA   -    MD0080PA01X+129595Y+088919X0160Y    R180 S0      
327m7334            U25   -F70        A01X+129779Y+089024X0177Y    R180 S1      
317m7334            VIA   -    MD0100PA01X+107517Y+078026X0190Y         S0      
327m7334            J21   -152        A01X+107517Y+078026X0205Y0590R090 S1      
317m7335            VIA   -    MD0080PA01X+129965Y+095935X0160Y    R180 S0      
327m7335            U25   -AH69       A01X+130149Y+096039X0177Y    R180 S1      
317m7335            VIA   -    MD0100PA01X+109131Y+091746X0190Y         S0      
327m7335            J21   -49         A01X+109131Y+091746X0205Y0590R090 S1      
317m7336            VIA   -    MD0080PA01X+129410Y+095616X0160Y    R180 S0      
327m7336            U25   -AG71       A01X+129594Y+095720X0177Y    R180 S1      
317m7336            VIA   -    MD0100PA01X+109131Y+091077X0190Y         S0      
327m7336            J21   -47         A01X+109131Y+091077X0205Y0590R090 S1      
317m7337            VIA   -    MD0080PA01X+130150Y+094978X0160Y    R180 S0      
327m7337            U25   -AE69       A01X+130334Y+095083X0177Y    R180 S1      
317m7337            VIA   -    MD0100PA01X+107517Y+089738X0190Y         S0      
327m7337            J21   -187        A01X+107517Y+089738X0205Y0590R090 S1      
317m7338            VIA   -    MD0080PA01X+129595Y+094659X0160Y    R180 S0      
327m7338            U25   -AD70       A01X+129779Y+094764X0177Y    R180 S1      
317m7338            VIA   -    MD0100PA01X+107517Y+089069X0190Y         S0      
327m7338            J21   -185        A01X+107517Y+089069X0205Y0590R090 S1      
317m7339            VIA   -    MD0080PA01X+129965Y+094659X0160Y    R180 S0      
327m7339            U25   -AD69       A01X+130149Y+094764X0177Y    R180 S1      
317m7339            VIA   -    MD0100PA01X+109131Y+089404X0190Y         S0      
327m7339            J21   -42         A01X+109131Y+089404X0205Y0590R090 S1      
317m7340            VIA   -    MD0080PA01X+129410Y+094340X0160Y    R180 S0      
327m7340            U25   -AC71       A01X+129594Y+094445X0177Y    R180 S1      
317m7340            VIA   -    MD0100PA01X+109131Y+088734X0190Y         S0      
327m7340            J21   -40         A01X+109131Y+088734X0205Y0590R090 S1      
317m7341            VIA   -    MD0080PA01X+130150Y+094340X0160Y    R180 S0      
327m7341            U25   -AC69       A01X+130334Y+094445X0177Y    R180 S1      
317m7341            VIA   -    MD0100PA01X+107517Y+088400X0190Y         S0      
327m7341            J21   -183        A01X+107517Y+088400X0205Y0590R090 S1      
317m7342            VIA   -    MD0080PA01X+129595Y+094021X0160Y    R180 S0      
327m7342            U25   -AB70       A01X+129779Y+094126X0177Y    R180 S1      
317m7342            VIA   -    MD0100PA01X+107517Y+087730X0190Y         S0      
327m7342            J21   -181        A01X+107517Y+087730X0205Y0590R090 S1      
317m7343            VIA   -    MD0080PA01X+129965Y+094021X0160Y    R180 S0      
327m7343            U25   -AB69       A01X+130149Y+094126X0177Y    R180 S1      
317m7343            VIA   -    MD0100PA01X+109131Y+088065X0190Y         S0      
327m7343            J21   -38         A01X+109131Y+088065X0205Y0590R090 S1      
317m7344            VIA   -    MD0080PA01X+129410Y+093702X0160Y    R180 S0      
327m7344            U25   -AA71       A01X+129594Y+093807X0177Y    R180 S1      
317m7344            VIA   -    MD0100PA01X+109131Y+087396X0190Y         S0      
327m7344            J21   -36         A01X+109131Y+087396X0205Y0590R090 S1      
317m7345            VIA   -    MD0080PA01X+129965Y+088919X0160Y    R180 S0      
327m7345            U25   -F69        A01X+130149Y+089024X0177Y    R180 S1      
317m7345            VIA   -    MD0100PA01X+109131Y+078360X0190Y         S0      
327m7345            J21   -9          A01X+109131Y+078360X0205Y0590R090 S1      
317m7346            VIA   -    MD0080PA01X+130150Y+093065X0160Y    R180 S0      
327m7346            U25   -W69        A01X+130334Y+093169X0177Y    R180 S1      
317m7346            VIA   -    MD0100PA01X+107517Y+086057X0190Y         S0      
327m7346            J21   -176        A01X+107517Y+086057X0205Y0590R090 S1      
317m7347            VIA   -    MD0080PA01X+129595Y+092746X0160Y    R180 S0      
327m7347            U25   -V70        A01X+129779Y+092850X0177Y    R180 S1      
317m7347            VIA   -    MD0100PA01X+107517Y+085388X0190Y         S0      
327m7347            J21   -174        A01X+107517Y+085388X0205Y0590R090 S1      
317m7348            VIA   -    MD0080PA01X+129965Y+092746X0160Y    R180 S0      
327m7348            U25   -V69        A01X+130149Y+092850X0177Y    R180 S1      
317m7348            VIA   -    MD0100PA01X+109131Y+085722X0190Y         S0      
327m7348            J21   -31         A01X+109131Y+085722X0205Y0590R090 S1      
317m7349            VIA   -    MD0080PA01X+129410Y+092427X0160Y    R180 S0      
327m7349            U25   -U71        A01X+129594Y+092532X0177Y    R180 S1      
317m7349            VIA   -    MD0100PA01X+109131Y+085053X0190Y         S0      
327m7349            J21   -29         A01X+109131Y+085053X0205Y0590R090 S1      
317m7350            VIA   -    MD0080PA01X+130150Y+092427X0160Y    R180 S0      
327m7350            U25   -U69        A01X+130334Y+092532X0177Y    R180 S1      
317m7350            VIA   -    MD0100PA01X+107517Y+084718X0190Y         S0      
327m7350            J21   -172        A01X+107517Y+084718X0205Y0590R090 S1      
317m7351            VIA   -    MD0080PA01X+129595Y+092108X0160Y    R180 S0      
327m7351            U25   -T70        A01X+129779Y+092213X0177Y    R180 S1      
317m7351            VIA   -    MD0100PA01X+107517Y+084049X0190Y         S0      
327m7351            J21   -170        A01X+107517Y+084049X0205Y0590R090 S1      
317m7352            VIA   -    MD0080PA01X+129965Y+092108X0160Y    R180 S0      
327m7352            U25   -T69        A01X+130149Y+092213X0177Y    R180 S1      
317m7352            VIA   -    MD0100PA01X+109131Y+084384X0190Y         S0      
327m7352            J21   -27         A01X+109131Y+084384X0205Y0590R090 S1      
317m7353            VIA   -    MD0080PA01X+129410Y+091789X0160Y    R180 S0      
327m7353            U25   -R71        A01X+129594Y+091894X0177Y    R180 S1      
317m7353            VIA   -    MD0100PA01X+109131Y+083715X0190Y         S0      
327m7353            J21   -25         A01X+109131Y+083715X0205Y0590R090 S1      
317m7354            VIA   -    MD0080PA01X+130150Y+091151X0160Y    R180 S0      
327m7354            U25   -N69        A01X+130334Y+091256X0177Y    R180 S1      
317m7354            VIA   -    MD0100PA01X+107517Y+082376X0190Y         S0      
327m7354            J21   -165        A01X+107517Y+082376X0205Y0590R090 S1      
317m7355            VIA   -    MD0080PA01X+129595Y+090832X0160Y    R180 S0      
327m7355            U25   -M70        A01X+129779Y+090937X0177Y    R180 S1      
317m7355            VIA   -    MD0100PA01X+107517Y+081707X0190Y         S0      
327m7355            J21   -163        A01X+107517Y+081707X0205Y0590R090 S1      
317m7356            VIA   -    MD0080PA01X+129410Y+088600X0160Y    R180 S0      
327m7356            U25   -E71        A01X+129594Y+088705X0177Y    R180 S1      
317m7356            VIA   -    MD0100PA01X+109131Y+077691X0190Y         S0      
327m7356            J21   -7          A01X+109131Y+077691X0205Y0590R090 S1      
317m7357            VIA   -    MD0080PA01X+130150Y+099443X0160Y    R180 S0      
327m7357            U25   -AW69       A01X+130334Y+099547X0177Y    R180 S1      
317m7357            VIA   -    MD0100PA01X+107517Y+097100X0190Y         S0      
327m7357            J21   -209        A01X+107517Y+097100X0205Y0590R090 S1      
317m7358            VIA   -    MD0080PA01X+129595Y+099124X0160Y    R180 S0      
327m7358            U25   -AV70       A01X+129779Y+099228X0177Y    R180 S1      
317m7358            VIA   -    MD0100PA01X+109131Y+096766X0190Y         S0      
327m7358            J21   -64         A01X+109131Y+096766X0205Y0590R090 S1      
317m7359            VIA   -    MD0080PA01X+130150Y+098167X0160Y    R180 S0      
327m7359            U25   -AR69       A01X+130334Y+098272X0177Y    R180 S1      
317m7359            VIA   -    MD0100PA01X+107517Y+095762X0190Y         S0      
327m7359            J21   -205        A01X+107517Y+095762X0205Y0590R090 S1      
317m7360            VIA   -    MD0080PA01X+129595Y+097848X0160Y    R180 S0      
327m7360            U25   -AP70       A01X+129779Y+097953X0177Y    R180 S1      
317m7360            VIA   -    MD0100PA01X+107517Y+095092X0190Y         S0      
327m7360            J21   -203        A01X+107517Y+095092X0205Y0590R090 S1      
317m7361            VIA   -    MD0080PA01X+129965Y+097848X0160Y    R180 S0      
327m7361            U25   -AP69       A01X+130149Y+097953X0177Y    R180 S1      
317m7361            VIA   -    MD0100PA01X+109131Y+095427X0190Y         S0      
327m7361            J21   -60         A01X+109131Y+095427X0205Y0590R090 S1      
317m7362            VIA   -    MD0080PA01X+129410Y+097529X0160Y    R180 S0      
327m7362            U25   -AN71       A01X+129594Y+097634X0177Y    R180 S1      
317m7362            VIA   -    MD0100PA01X+109131Y+094758X0190Y         S0      
327m7362            J21   -58         A01X+109131Y+094758X0205Y0590R090 S1      
317m7363            VIA   -    MD0080PA01X+130150Y+096891X0160Y    R180 S0      
327m7363            U25   -AL69       A01X+130334Y+096996X0177Y    R180 S1      
317m7363            VIA   -    MD0100PA01X+107517Y+093419X0190Y         S0      
327m7363            J21   -198        A01X+107517Y+093419X0205Y0590R090 S1      
317m7364            VIA   -    MD0080PA01X+129595Y+096572X0160Y    R180 S0      
327m7364            U25   -AK70       A01X+129779Y+096677X0177Y    R180 S1      
317m7364            VIA   -    MD0100PA01X+107517Y+092750X0190Y         S0      
327m7364            J21   -196        A01X+107517Y+092750X0205Y0590R090 S1      
317m7365            VIA   -    MD0080PA01X+129965Y+096572X0160Y    R180 S0      
327m7365            U25   -AK69       A01X+130149Y+096677X0177Y    R180 S1      
317m7365            VIA   -    MD0100PA01X+109131Y+093085X0190Y         S0      
327m7365            J21   -53         A01X+109131Y+093085X0205Y0590R090 S1      
317m7366            VIA   -    MD0080PA01X+129410Y+096254X0160Y    R180 S0      
327m7366            U25   -AJ71       A01X+129594Y+096358X0177Y    R180 S1      
317m7366            VIA   -    MD0100PA01X+109131Y+092415X0190Y         S0      
327m7366            J21   -51         A01X+109131Y+092415X0205Y0590R090 S1      
317m7367            VIA   -    MD0080PA01X+129965Y+100399X0160Y    R180 S0      
327m7367            U25   -BB69       A01X+130149Y+100504X0177Y    R180 S1      
317m7367            VIA   -    MD0100PA01X+109131Y+099443X0190Y         S0      
327m7367            J21   -72         A01X+109131Y+099443X0205Y0590R090 S1      
317m7368            VIA   -    MD0080PA01X+129595Y+100399X0160Y    R180 S0      
327m7368            U25   -BB70       A01X+129779Y+100504X0177Y    R180 S1      
317m7368            VIA   -    MD0100PA01X+107517Y+099108X0190Y         S0      
327m7368            J21   -215        A01X+107517Y+099108X0205Y0590R090 S1      
317m7369            VIA   -    MD0080PA01X+129410Y+100080X0160Y    R180 S0      
327m7369            U25   -BA71       A01X+129594Y+100185X0177Y    R180 S1      
317m7369            VIA   -    MD0100PA01X+109131Y+098774X0190Y         S0      
327m7369            J21   -70         A01X+109131Y+098774X0205Y0590R090 S1      
317m7370            VIA   -    MD0080PA01X+130150Y+100080X0160Y    R180 S0      
327m7370            U25   -BA69       A01X+130334Y+100185X0177Y    R180 S1      
317m7370            VIA   -    MD0100PA01X+107517Y+098439X0190Y         S0      
327m7370            J21   -213        A01X+107517Y+098439X0205Y0590R090 S1      
317m7371            VIA   -    MD0080PA01X+129965Y+099762X0160Y    R180 S0      
327m7371            U25   -AY69       A01X+130149Y+099866X0177Y    R180 S1      
317m7371            VIA   -    MD0100PA01X+109131Y+098104X0190Y         S0      
327m7371            J21   -68         A01X+109131Y+098104X0205Y0590R090 S1      
317m7372            VIA   -    MD0080PA01X+129595Y+099762X0160Y    R180 S0      
327m7372            U25   -AY70       A01X+129779Y+099866X0177Y    R180 S1      
317m7372            VIA   -    MD0100PA01X+107517Y+097770X0190Y         S0      
327m7372            J21   -211        A01X+107517Y+097770X0205Y0590R090 S1      
317m7373            VIA   -    MD0080PA01X+129410Y+099443X0160Y    R180 S0      
327m7373            U25   -AW71       A01X+129594Y+099547X0177Y    R180 S1      
317m7373            VIA   -    MD0100PA01X+109131Y+097435X0190Y         S0      
327m7373            J21   -66         A01X+109131Y+097435X0205Y0590R090 S1      
317m7374            VIA   -    MD0080PA01X+130150Y+098805X0160Y    R180 S0      
327m7374            U25   -AU69       A01X+130334Y+098910X0177Y    R180 S1      
317m7374            VIA   -    MD0100PA01X+107517Y+096431X0190Y         S0      
327m7374            J21   -207        A01X+107517Y+096431X0205Y0590R090 S1      
317m7375            VIA   -    MD0080PA01X+129410Y+100718X0160Y    R180 S0      
327m7375            U25   -BC71       A01X+129594Y+100823X0177Y    R180 S1      
317m7375            VIA   -    MD0100PA01X+107517Y+099778X0190Y         S0      
327m7375            J21   -217        A01X+107517Y+099778X0205Y0590R090 S1      
317m7376            VIA   -    MD0080PA01X+129595Y+101037X0160Y    R180 S0      
327m7376            U25   -BD70       A01X+129779Y+101142X0177Y    R180 S1      
317m7376            VIA   -    MD0100PA01X+107517Y+100112X0190Y         S0      
327m7376            J21   -218        A01X+107517Y+100112X0205Y0590R090 S1      
317m7377            VIA   -    MD0080PA01X+129965Y+098486X0160Y    R180 S0      
327m7377            U25   -AT69       A01X+130149Y+098591X0177Y    R180 S1      
317m7377            VIA   -    MD0100PA18X+109681Y+096096X0190Y         S0      
327m7377            R379  -2          A18X+109681Y+096096X0198Y0197R180 S2      
327m7378            J21   -62         A01X+109131Y+096096X0205Y0590R090 S1      
317m7378            VIA   -    MD0100PA00X+109131Y+096096X0190Y         S0      
327m7378            R379  -1          A18X+109366Y+096096X0198Y0197R180 S2      
317m7379            VIA   -    MD0080PA01X+035800Y+105357X0160Y         S0      
327m7379            U26   -BP60       A01X+035983Y+105252X0177Y    R180 S1      
327m7379            J30   -87         A01X+014487Y+106471X0205Y0590R090 S1      
317m7379            VIA   -    MD0100PA01X+014487Y+106471X0190Y         S0      
317m7380            VIA   -    MD0080PA01X+035985Y+104400X0160Y         S0      
327m7380            U26   -BL60       A01X+036168Y+104295X0177Y    R180 S1      
327m7380            J30   -227        A01X+012872Y+105132X0205Y0590R090 S1      
317m7380            VIA   -    MD0100PA01X+012872Y+105132X0190Y         S0      
317m7381            VIA   -    MD0080PA01X+035800Y+106632X0160Y         S0      
327m7381            U26   -BV60       A01X+035983Y+106528X0177Y    R180 S1      
327m7381            J30   -93         A01X+014487Y+108478X0205Y0590R090 S1      
317m7381            VIA   -    MD0100PA01X+014487Y+108478X0190Y         S0      
317m7382            VIA   -    MD0080PA01X+036540Y+114924X0160Y         S0      
327m7382            U26   -DD58       A01X+036724Y+114819X0177Y    R180 S1      
327m7382            J30   -283        A01X+012872Y+123872X0205Y0590R090 S1      
317m7382            VIA   -    MD0100PA01X+012872Y+123872X0190Y         S0      
317m7383            VIA   -    MD0080PA01X+036540Y+113010X0160Y         S0      
327m7383            U26   -CV58       A01X+036724Y+112906X0177Y    R180 S1      
327m7383            J30   -272        A01X+012872Y+120191X0205Y0590R090 S1      
317m7383            VIA   -    MD0100PA01X+012872Y+120191X0190Y         S0      
317m7384            VIA   -    MD0080PA01X+036540Y+111097X0160Y         S0      
327m7384            U26   -CM58       A01X+036724Y+110992X0177Y    R180 S1      
327m7384            J30   -261        A01X+012872Y+116510X0205Y0590R090 S1      
317m7384            VIA   -    MD0100PA01X+012872Y+116510X0190Y         S0      
317m7385            VIA   -    MD0080PA01X+036540Y+109184X0160Y         S0      
327m7385            U26   -CF58       A01X+036724Y+109079X0177Y    R180 S1      
327m7385            J30   -250        A01X+012872Y+112829X0205Y0590R090 S1      
317m7385            VIA   -    MD0100PA01X+012872Y+112829X0190Y         S0      
317m7386            VIA   -    MD0080PA01X+036540Y+107270X0160Y         S0      
327m7386            U26   -BY58       A01X+036724Y+107166X0177Y    R180 S1      
327m7386            J30   -239        A01X+012872Y+109148X0205Y0590R090 S1      
317m7386            VIA   -    MD0100PA01X+012872Y+109148X0190Y         S0      
317m7387            VIA   -    MD0080PA01X+035800Y+114286X0160Y         S0      
327m7387            U26   -DB60       A01X+035983Y+114181X0177Y    R180 S1      
327m7387            J30   -137        A01X+014487Y+123203X0205Y0590R090 S1      
317m7387            VIA   -    MD0100PA01X+014487Y+123203X0190Y         S0      
317m7388            VIA   -    MD0080PA01X+035800Y+112373X0160Y         S0      
327m7388            U26   -CT60       A01X+035983Y+112268X0177Y    R180 S1      
327m7388            J30   -126        A01X+014487Y+119522X0205Y0590R090 S1      
317m7388            VIA   -    MD0100PA01X+014487Y+119522X0190Y         S0      
317m7389            VIA   -    MD0080PA01X+035800Y+110459X0160Y         S0      
327m7389            U26   -CK60       A01X+035983Y+110354X0177Y    R180 S1      
327m7389            J30   -115        A01X+014487Y+115841X0205Y0590R090 S1      
317m7389            VIA   -    MD0100PA01X+014487Y+115841X0190Y         S0      
317m7390            VIA   -    MD0080PA01X+035800Y+108546X0160Y         S0      
327m7390            U26   -CD60       A01X+035983Y+108441X0177Y    R180 S1      
327m7390            J30   -104        A01X+014487Y+112160X0205Y0590R090 S1      
317m7390            VIA   -    MD0100PA01X+014487Y+112160X0190Y         S0      
317m7391            VIA   -    MD0080PA01X+035985Y+106951X0160Y         S0      
327m7391            U26   -BW60       A01X+036168Y+106847X0177Y    R180 S1      
327m7391            J30   -94         A01X+014487Y+108813X0205Y0590R090 S1      
317m7391            VIA   -    MD0100PA01X+014487Y+108813X0190Y         S0      
317m7392            VIA   -    MD0080PA01X+036355Y+114605X0160Y         S0      
327m7392            U26   -DC59       A01X+036538Y+114500X0177Y    R180 S1      
327m7392            J30   -282        A01X+012872Y+123538X0205Y0590R090 S1      
317m7392            VIA   -    MD0100PA01X+012872Y+123538X0190Y         S0      
317m7393            VIA   -    MD0080PA01X+036355Y+112692X0160Y         S0      
327m7393            U26   -CU59       A01X+036538Y+112587X0177Y    R180 S1      
327m7393            J30   -271        A01X+012872Y+119856X0205Y0590R090 S1      
317m7393            VIA   -    MD0100PA01X+012872Y+119856X0190Y         S0      
317m7394            VIA   -    MD0080PA01X+036355Y+110778X0160Y         S0      
327m7394            U26   -CL59       A01X+036538Y+110673X0177Y    R180 S1      
327m7394            J30   -260        A01X+012872Y+116175X0205Y0590R090 S1      
317m7394            VIA   -    MD0100PA01X+012872Y+116175X0190Y         S0      
317m7395            VIA   -    MD0080PA01X+036355Y+108865X0160Y         S0      
327m7395            U26   -CE59       A01X+036538Y+108760X0177Y    R180 S1      
327m7395            J30   -249        A01X+012872Y+112494X0205Y0590R090 S1      
317m7395            VIA   -    MD0100PA01X+012872Y+112494X0190Y         S0      
317m7396            VIA   -    MD0080PA01X+036355Y+106951X0160Y         S0      
327m7396            U26   -BW59       A01X+036538Y+106847X0177Y    R180 S1      
327m7396            J30   -238        A01X+012872Y+108813X0205Y0590R090 S1      
317m7396            VIA   -    MD0100PA01X+012872Y+108813X0190Y         S0      
317m7397            VIA   -    MD0080PA01X+035985Y+114605X0160Y         S0      
327m7397            U26   -DC60       A01X+036168Y+114500X0177Y    R180 S1      
327m7397            J30   -138        A01X+014487Y+123538X0205Y0590R090 S1      
317m7397            VIA   -    MD0100PA01X+014487Y+123538X0190Y         S0      
317m7398            VIA   -    MD0080PA01X+035985Y+112692X0160Y         S0      
327m7398            U26   -CU60       A01X+036168Y+112587X0177Y    R180 S1      
327m7398            J30   -127        A01X+014487Y+119856X0205Y0590R090 S1      
317m7398            VIA   -    MD0100PA01X+014487Y+119856X0190Y         S0      
317m7399            VIA   -    MD0080PA01X+035985Y+110778X0160Y         S0      
327m7399            U26   -CL60       A01X+036168Y+110673X0177Y    R180 S1      
327m7399            J30   -116        A01X+014487Y+116175X0205Y0590R090 S1      
317m7399            VIA   -    MD0100PA01X+014487Y+116175X0190Y         S0      
317m7400            VIA   -    MD0080PA01X+035985Y+108865X0160Y         S0      
327m7400            U26   -CE60       A01X+036168Y+108760X0177Y    R180 S1      
327m7400            J30   -105        A01X+014487Y+112494X0205Y0590R090 S1      
317m7400            VIA   -    MD0100PA01X+014487Y+112494X0190Y         S0      
317m7401            VIA   -    MD0080PA01X+036355Y+110140X0160Y         S0      
327m7401            U26   -CJ59       A01X+036538Y+110036X0177Y    R180 S1      
327m7401            J30   -113        A01X+014487Y+115171X0205Y0590R090 S1      
317m7401            VIA   -    MD0100PA01X+014487Y+115171X0190Y         S0      
317m7402            VIA   -    MD0080PA01X+035800Y+109821X0160Y         S0      
327m7402            U26   -CH60       A01X+035983Y+109717X0177Y    R180 S1      
317m7402            VIA   -    MD0100PA01X+014487Y+114502X0190Y         S0      
327m7402            J30   -111        A01X+014487Y+114502X0205Y0590R090 S1      
317m7403            VIA   -    MD0080PA01X+036540Y+109821X0160Y         S0      
327m7403            U26   -CH58       A01X+036724Y+109717X0177Y    R180 S1      
327m7403            J30   -254        A01X+012872Y+114168X0205Y0590R090 S1      
317m7403            VIA   -    MD0100PA01X+012872Y+114168X0190Y         S0      
317m7404            VIA   -    MD0080PA01X+035985Y+109502X0160Y         S0      
327m7404            U26   -CG60       A01X+036168Y+109398X0177Y    R180 S1      
327m7404            J30   -252        A01X+012872Y+113498X0205Y0590R090 S1      
317m7404            VIA   -    MD0100PA01X+012872Y+113498X0190Y         S0      
317m7405            VIA   -    MD0080PA01X+036355Y+109502X0160Y         S0      
327m7405            U26   -CG59       A01X+036538Y+109398X0177Y    R180 S1      
327m7405            J30   -109        A01X+014487Y+113833X0205Y0590R090 S1      
317m7405            VIA   -    MD0100PA01X+014487Y+113833X0190Y         S0      
317m7406            VIA   -    MD0080PA01X+035800Y+109184X0160Y         S0      
327m7406            U26   -CF60       A01X+035983Y+109079X0177Y    R180 S1      
327m7406            J30   -107        A01X+014487Y+113164X0205Y0590R090 S1      
317m7406            VIA   -    MD0100PA01X+014487Y+113164X0190Y         S0      
317m7407            VIA   -    MD0080PA01X+036540Y+108546X0160Y         S0      
327m7407            U26   -CD58       A01X+036724Y+108441X0177Y    R180 S1      
327m7407            J30   -247        A01X+012872Y+111825X0205Y0590R090 S1      
317m7407            VIA   -    MD0100PA01X+012872Y+111825X0190Y         S0      
317m7408            VIA   -    MD0080PA01X+035800Y+115562X0160Y         S0      
327m7408            U26   -DF60       A01X+035983Y+115457X0177Y    R180 S1      
327m7408            J30   -287        A01X+012872Y+125211X0205Y0590R090 S1      
317m7408            VIA   -    MD0100PA01X+012872Y+125211X0190Y         S0      
317m7409            VIA   -    MD0080PA01X+035985Y+115243X0160Y         S0      
327m7409            U26   -DE60       A01X+036168Y+115138X0177Y    R180 S1      
327m7409            J30   -285        A01X+012872Y+124542X0205Y0590R090 S1      
317m7409            VIA   -    MD0100PA01X+012872Y+124542X0190Y         S0      
317m7410            VIA   -    MD0080PA01X+035985Y+108227X0160Y         S0      
327m7410            U26   -CC60       A01X+036168Y+108122X0177Y    R180 S1      
327m7410            J30   -245        A01X+012872Y+111156X0205Y0590R090 S1      
317m7410            VIA   -    MD0100PA01X+012872Y+111156X0190Y         S0      
317m7411            VIA   -    MD0080PA01X+036355Y+115243X0160Y         S0      
327m7411            U26   -DE59       A01X+036538Y+115138X0177Y    R180 S1      
327m7411            J30   -142        A01X+014487Y+124876X0205Y0590R090 S1      
317m7411            VIA   -    MD0100PA01X+014487Y+124876X0190Y         S0      
317m7412            VIA   -    MD0080PA01X+035800Y+114924X0160Y         S0      
327m7412            U26   -DD60       A01X+035983Y+114819X0177Y    R180 S1      
327m7412            J30   -140        A01X+014487Y+124207X0205Y0590R090 S1      
317m7412            VIA   -    MD0100PA01X+014487Y+124207X0190Y         S0      
317m7413            VIA   -    MD0080PA01X+036540Y+114286X0160Y         S0      
327m7413            U26   -DB58       A01X+036724Y+114181X0177Y    R180 S1      
327m7413            J30   -280        A01X+012872Y+122868X0205Y0590R090 S1      
317m7413            VIA   -    MD0100PA01X+012872Y+122868X0190Y         S0      
317m7414            VIA   -    MD0080PA01X+035985Y+113967X0160Y         S0      
327m7414            U26   -DA60       A01X+036168Y+113862X0177Y    R180 S1      
327m7414            J30   -278        A01X+012872Y+122199X0205Y0590R090 S1      
317m7414            VIA   -    MD0100PA01X+012872Y+122199X0190Y         S0      
317m7415            VIA   -    MD0080PA01X+036355Y+113967X0160Y         S0      
327m7415            U26   -DA59       A01X+036538Y+113862X0177Y    R180 S1      
327m7415            J30   -135        A01X+014487Y+122534X0205Y0590R090 S1      
317m7415            VIA   -    MD0100PA01X+014487Y+122534X0190Y         S0      
317m7416            VIA   -    MD0080PA01X+035800Y+113648X0160Y         S0      
327m7416            U26   -CY60       A01X+035983Y+113543X0177Y    R180 S1      
327m7416            J30   -133        A01X+014487Y+121864X0205Y0590R090 S1      
317m7416            VIA   -    MD0100PA01X+014487Y+121864X0190Y         S0      
317m7417            VIA   -    MD0080PA01X+036540Y+113648X0160Y         S0      
327m7417            U26   -CY58       A01X+036724Y+113543X0177Y    R180 S1      
327m7417            J30   -276        A01X+012872Y+121530X0205Y0590R090 S1      
317m7417            VIA   -    MD0100PA01X+012872Y+121530X0190Y         S0      
317m7418            VIA   -    MD0080PA01X+035985Y+113329X0160Y         S0      
327m7418            U26   -CW60       A01X+036168Y+113225X0177Y    R180 S1      
327m7418            J30   -274        A01X+012872Y+120860X0205Y0590R090 S1      
317m7418            VIA   -    MD0100PA01X+012872Y+120860X0190Y         S0      
317m7419            VIA   -    MD0080PA01X+036355Y+113329X0160Y         S0      
327m7419            U26   -CW59       A01X+036538Y+113225X0177Y    R180 S1      
327m7419            J30   -131        A01X+014487Y+121195X0205Y0590R090 S1      
317m7419            VIA   -    MD0100PA01X+014487Y+121195X0190Y         S0      
317m7420            VIA   -    MD0080PA01X+035800Y+113010X0160Y         S0      
327m7420            U26   -CV60       A01X+035983Y+112906X0177Y    R180 S1      
327m7420            J30   -129        A01X+014487Y+120526X0205Y0590R090 S1      
317m7420            VIA   -    MD0100PA01X+014487Y+120526X0190Y         S0      
317m7421            VIA   -    MD0080PA01X+036355Y+108227X0160Y         S0      
327m7421            U26   -CC59       A01X+036538Y+108122X0177Y    R180 S1      
327m7421            J30   -102        A01X+014487Y+111490X0205Y0590R090 S1      
317m7421            VIA   -    MD0100PA01X+014487Y+111490X0190Y         S0      
317m7422            VIA   -    MD0080PA01X+036540Y+112373X0160Y         S0      
327m7422            U26   -CT58       A01X+036724Y+112268X0177Y    R180 S1      
327m7422            J30   -269        A01X+012872Y+119187X0205Y0590R090 S1      
317m7422            VIA   -    MD0100PA01X+012872Y+119187X0190Y         S0      
317m7423            VIA   -    MD0080PA01X+035985Y+112054X0160Y         S0      
327m7423            U26   -CR60       A01X+036168Y+111949X0177Y    R180 S1      
327m7423            J30   -267        A01X+012872Y+118518X0205Y0590R090 S1      
317m7423            VIA   -    MD0100PA01X+012872Y+118518X0190Y         S0      
317m7424            VIA   -    MD0080PA01X+036355Y+112054X0160Y         S0      
327m7424            U26   -CR59       A01X+036538Y+111949X0177Y    R180 S1      
327m7424            J30   -124        A01X+014487Y+118852X0205Y0590R090 S1      
317m7424            VIA   -    MD0100PA01X+014487Y+118852X0190Y         S0      
317m7425            VIA   -    MD0080PA01X+035800Y+111735X0160Y         S0      
327m7425            U26   -CP60       A01X+035983Y+111630X0177Y    R180 S1      
327m7425            J30   -122        A01X+014487Y+118183X0205Y0590R090 S1      
317m7425            VIA   -    MD0100PA01X+014487Y+118183X0190Y         S0      
317m7426            VIA   -    MD0080PA01X+036540Y+111735X0160Y         S0      
327m7426            U26   -CP58       A01X+036724Y+111630X0177Y    R180 S1      
327m7426            J30   -265        A01X+012872Y+117849X0205Y0590R090 S1      
317m7426            VIA   -    MD0100PA01X+012872Y+117849X0190Y         S0      
317m7427            VIA   -    MD0080PA01X+035985Y+111416X0160Y         S0      
327m7427            U26   -CN60       A01X+036168Y+111311X0177Y    R180 S1      
327m7427            J30   -263        A01X+012872Y+117179X0205Y0590R090 S1      
317m7427            VIA   -    MD0100PA01X+012872Y+117179X0190Y         S0      
317m7428            VIA   -    MD0080PA01X+036355Y+111416X0160Y         S0      
327m7428            U26   -CN59       A01X+036538Y+111311X0177Y    R180 S1      
327m7428            J30   -120        A01X+014487Y+117514X0205Y0590R090 S1      
317m7428            VIA   -    MD0100PA01X+014487Y+117514X0190Y         S0      
317m7429            VIA   -    MD0080PA01X+035800Y+111097X0160Y         S0      
327m7429            U26   -CM60       A01X+035983Y+110992X0177Y    R180 S1      
327m7429            J30   -118        A01X+014487Y+116845X0205Y0590R090 S1      
317m7429            VIA   -    MD0100PA01X+014487Y+116845X0190Y         S0      
317m7430            VIA   -    MD0080PA01X+036540Y+110459X0160Y         S0      
327m7430            U26   -CK58       A01X+036724Y+110354X0177Y    R180 S1      
327m7430            J30   -258        A01X+012872Y+115506X0205Y0590R090 S1      
317m7430            VIA   -    MD0100PA01X+012872Y+115506X0190Y         S0      
317m7431            VIA   -    MD0080PA01X+035985Y+110140X0160Y         S0      
327m7431            U26   -CJ60       A01X+036168Y+110036X0177Y    R180 S1      
317m7431            VIA   -    MD0100PA01X+012872Y+114837X0190Y         S0      
327m7431            J30   -256        A01X+012872Y+114837X0205Y0590R090 S1      
317m7432            VIA   -    MD0080PA01X+035800Y+107908X0160Y         S0      
327m7432            U26   -CB60       A01X+035983Y+107803X0177Y    R180 S1      
327m7432            J30   -100        A01X+014487Y+110821X0205Y0590R090 S1      
317m7432            VIA   -    MD0100PA01X+014487Y+110821X0190Y         S0      
317m7433            VIA   -    MD0080PA01X+035985Y+105038X0160Y         S0      
327m7433            U26   -BN60       A01X+036168Y+104933X0177Y    R180 S1      
327m7433            J30   -229        A01X+012872Y+105801X0205Y0590R090 S1      
317m7433            VIA   -    MD0100PA01X+012872Y+105801X0190Y         S0      
317m7434            VIA   -    MD0080PA01X+036540Y+104719X0160Y         S0      
327m7434            U26   -BM58       A01X+036724Y+104614X0177Y    R180 S1      
327m7434            J30   -84         A01X+014487Y+105467X0205Y0590R090 S1      
317m7434            VIA   -    MD0100PA01X+014487Y+105467X0190Y         S0      
317m7435            VIA   -    MD0080PA01X+036540Y+106632X0160Y         S0      
327m7435            U26   -BV58       A01X+036724Y+106528X0177Y    R180 S1      
327m7435            J30   -236        A01X+012872Y+108144X0205Y0590R090 S1      
317m7435            VIA   -    MD0100PA01X+012872Y+108144X0190Y         S0      
317m7436            VIA   -    MD0080PA01X+035985Y+106314X0160Y         S0      
327m7436            U26   -BU60       A01X+036168Y+106209X0177Y    R180 S1      
327m7436            J30   -234        A01X+012872Y+107474X0205Y0590R090 S1      
317m7436            VIA   -    MD0100PA01X+012872Y+107474X0190Y         S0      
317m7437            VIA   -    MD0080PA01X+036355Y+106314X0160Y         S0      
327m7437            U26   -BU59       A01X+036538Y+106209X0177Y    R180 S1      
327m7437            J30   -91         A01X+014487Y+107809X0205Y0590R090 S1      
317m7437            VIA   -    MD0100PA01X+014487Y+107809X0190Y         S0      
317m7438            VIA   -    MD0080PA01X+035800Y+105995X0160Y         S0      
327m7438            U26   -BT60       A01X+035983Y+105890X0177Y    R180 S1      
327m7438            J30   -89         A01X+014487Y+107140X0205Y0590R090 S1      
317m7438            VIA   -    MD0100PA01X+014487Y+107140X0190Y         S0      
317m7439            VIA   -    MD0080PA01X+036540Y+107908X0160Y         S0      
327m7439            U26   -CB58       A01X+036724Y+107803X0177Y    R180 S1      
327m7439            J30   -243        A01X+012872Y+110486X0205Y0590R090 S1      
317m7439            VIA   -    MD0100PA01X+012872Y+110486X0190Y         S0      
317m7440            VIA   -    MD0080PA01X+035985Y+107589X0160Y         S0      
327m7440            U26   -CA60       A01X+036168Y+107484X0177Y    R180 S1      
327m7440            J30   -241        A01X+012872Y+109817X0205Y0590R090 S1      
317m7440            VIA   -    MD0100PA01X+012872Y+109817X0190Y         S0      
317m7441            VIA   -    MD0080PA01X+036355Y+107589X0160Y         S0      
327m7441            U26   -CA59       A01X+036538Y+107484X0177Y    R180 S1      
327m7441            J30   -98         A01X+014487Y+110152X0205Y0590R090 S1      
317m7441            VIA   -    MD0100PA01X+014487Y+110152X0190Y         S0      
317m7442            VIA   -    MD0080PA01X+035800Y+107270X0160Y         S0      
327m7442            U26   -BY60       A01X+035983Y+107166X0177Y    R180 S1      
327m7442            J30   -96         A01X+014487Y+109482X0205Y0590R090 S1      
317m7442            VIA   -    MD0100PA01X+014487Y+109482X0190Y         S0      
317m7443            VIA   -    MD0080PA01X+035800Y+104081X0160Y         S0      
327m7443            U26   -BK60       A01X+035983Y+103976X0177Y    R180 S1      
327m7443            J30   -82         A01X+014487Y+104797X0205Y0590R090 S1      
317m7443            VIA   -    MD0100PA01X+014487Y+104797X0190Y         S0      
317m7444            VIA   -    MD0080PA01X+036540Y+104081X0160Y         S0      
327m7444            U26   -BK58       A01X+036724Y+103976X0177Y    R180 S1      
327m7444            J30   -225        A01X+012872Y+104463X0205Y0590R090 S1      
317m7444            VIA   -    MD0100PA01X+012872Y+104463X0190Y         S0      
317m7445            VIA   -    MD0080PA01X+036355Y+103762X0160Y         S0      
327m7445            U26   -BJ59       A01X+036538Y+103658X0177Y    R180 S1      
327m7445            J30   -80         A01X+014487Y+104128X0205Y0590R090 S1      
317m7445            VIA   -    MD0100PA01X+014487Y+104128X0190Y         S0      
317m7446            VIA   -    MD0080PA01X+035985Y+103762X0160Y         S0      
327m7446            U26   -BJ60       A01X+036168Y+103658X0177Y    R180 S1      
327m7446            J30   -223        A01X+012872Y+103793X0205Y0590R090 S1      
317m7446            VIA   -    MD0100PA01X+012872Y+103793X0190Y         S0      
317m7447            VIA   -    MD0080PA01X+035800Y+103443X0160Y         S0      
327m7447            U26   -BH60       A01X+035983Y+103339X0177Y    R180 S1      
327m7447            J30   -78         A01X+014487Y+103459X0205Y0590R090 S1      
317m7447            VIA   -    MD0100PA01X+014487Y+103459X0190Y         S0      
317m7448            VIA   -    MD0080PA01X+036540Y+103443X0160Y         S0      
327m7448            U26   -BH58       A01X+036724Y+103339X0177Y    R180 S1      
327m7448            J30   -221        A01X+012872Y+103124X0205Y0590R090 S1      
317m7448            VIA   -    MD0100PA01X+012872Y+103124X0190Y         S0      
317m7449            VIA   -    MD0080PA01X+036355Y+103124X0160Y         S0      
327m7449            U26   -BG59       A01X+036538Y+103020X0177Y    R180 S1      
327m7449            J30   -76         A01X+014487Y+102790X0205Y0590R090 S1      
317m7449            VIA   -    MD0100PA01X+014487Y+102790X0190Y         S0      
317m7450            VIA   -    MD0080PA01X+036355Y+105038X0160Y         S0      
327m7450            U26   -BN59       A01X+036538Y+104933X0177Y    R180 S1      
327m7450            J30   -86         A01X+014487Y+106136X0205Y0590R090 S1      
317m7450            VIA   -    MD0100PA01X+014487Y+106136X0190Y         S0      
317m7451            VIA   -    MD0080PA01X+036237Y+100718X0160Y    R180 S0      
327m7451            U26   -BC59       A01X+036420Y+100823X0177Y    R180 S1      
317m7451            VIA   -    MD0100PA01X+014487Y+100112X0190Y         S0      
327m7451            J30   -74         A01X+014487Y+100112X0205Y0590R090 S1      
317m7452            VIA   -    MD0080PA01X+036237Y+097529X0160Y    R180 S0      
327m7452            U26   -AN59       A01X+036420Y+097634X0177Y    R180 S1      
327m7452            J30   -201        A01X+012872Y+094423X0205Y0590R090 S1      
317m7452            VIA   -    MD0100PA01X+012872Y+094423X0190Y         S0      
317m7453            VIA   -    MD0080PA01X+036237Y+095616X0160Y    R180 S0      
327m7453            U26   -AG59       A01X+036420Y+095721X0177Y    R180 S1      
327m7453            J30   -190        A01X+012872Y+090742X0205Y0590R090 S1      
317m7453            VIA   -    MD0100PA01X+012872Y+090742X0190Y         S0      
317m7454            VIA   -    MD0080PA01X+036237Y+093702X0160Y    R180 S0      
327m7454            U26   -AA59       A01X+036420Y+093807X0177Y    R180 S1      
327m7454            J30   -179        A01X+012872Y+087061X0205Y0590R090 S1      
317m7454            VIA   -    MD0100PA01X+012872Y+087061X0190Y         S0      
317m7455            VIA   -    MD0080PA01X+036237Y+091789X0160Y    R180 S0      
327m7455            U26   -R59        A01X+036420Y+091894X0177Y    R180 S1      
327m7455            J30   -168        A01X+012872Y+083380X0205Y0590R090 S1      
317m7455            VIA   -    MD0100PA01X+012872Y+083380X0190Y         S0      
317m7456            VIA   -    MD0080PA01X+036237Y+089876X0160Y    R180 S0      
327m7456            U26   -J59        A01X+036420Y+089980X0177Y    R180 S1      
327m7456            J30   -157        A01X+012872Y+079699X0205Y0590R090 S1      
317m7456            VIA   -    MD0100PA01X+012872Y+079699X0190Y         S0      
317m7457            VIA   -    MD0080PA01X+035866Y+096892X0160Y    R180 S0      
327m7457            U26   -AL60       A01X+036050Y+096996X0177Y    R180 S1      
327m7457            J30   -55         A01X+014487Y+093754X0205Y0590R090 S1      
317m7457            VIA   -    MD0100PA01X+014487Y+093754X0190Y         S0      
317m7458            VIA   -    MD0080PA01X+035866Y+094978X0160Y    R180 S0      
327m7458            U26   -AE60       A01X+036050Y+095083X0177Y    R180 S1      
327m7458            J30   -44         A01X+014487Y+090073X0205Y0590R090 S1      
317m7458            VIA   -    MD0100PA01X+014487Y+090073X0190Y         S0      
317m7459            VIA   -    MD0080PA01X+035866Y+093065X0160Y    R180 S0      
327m7459            U26   -W60        A01X+036050Y+093169X0177Y    R180 S1      
327m7459            J30   -33         A01X+014487Y+086392X0205Y0590R090 S1      
317m7459            VIA   -    MD0100PA01X+014487Y+086392X0190Y         S0      
317m7460            VIA   -    MD0080PA01X+035866Y+091151X0160Y    R180 S0      
327m7460            U26   -N60        A01X+036050Y+091256X0177Y    R180 S1      
327m7460            J30   -22         A01X+014487Y+082711X0205Y0590R090 S1      
317m7460            VIA   -    MD0100PA01X+014487Y+082711X0190Y         S0      
317m7461            VIA   -    MD0080PA01X+035866Y+089238X0160Y    R180 S0      
327m7461            U26   -G60        A01X+036050Y+089343X0177Y    R180 S1      
327m7461            J30   -11         A01X+014487Y+079030X0205Y0590R090 S1      
317m7461            VIA   -    MD0100PA01X+014487Y+079030X0190Y         S0      
317m7462            VIA   -    MD0080PA01X+036422Y+097210X0160Y    R180 S0      
327m7462            U26   -AM58       A01X+036606Y+097315X0177Y    R180 S1      
327m7462            J30   -200        A01X+012872Y+094089X0205Y0590R090 S1      
317m7462            VIA   -    MD0100PA01X+012872Y+094089X0190Y         S0      
317m7463            VIA   -    MD0080PA01X+036422Y+095297X0160Y    R180 S0      
327m7463            U26   -AF58       A01X+036606Y+095402X0177Y    R180 S1      
327m7463            J30   -189        A01X+012872Y+090408X0205Y0590R090 S1      
317m7463            VIA   -    MD0100PA01X+012872Y+090408X0190Y         S0      
317m7464            VIA   -    MD0080PA01X+036422Y+093384X0160Y    R180 S0      
327m7464            U26   -Y58        A01X+036606Y+093488X0177Y    R180 S1      
327m7464            J30   -178        A01X+012872Y+086726X0205Y0590R090 S1      
317m7464            VIA   -    MD0100PA01X+012872Y+086726X0190Y         S0      
317m7465            VIA   -    MD0080PA01X+036422Y+091470X0160Y    R180 S0      
327m7465            U26   -P58        A01X+036606Y+091575X0177Y    R180 S1      
327m7465            J30   -167        A01X+012872Y+083045X0205Y0590R090 S1      
317m7465            VIA   -    MD0100PA01X+012872Y+083045X0190Y         S0      
317m7466            VIA   -    MD0080PA01X+036422Y+089557X0160Y    R180 S0      
327m7466            U26   -H58        A01X+036606Y+089662X0177Y    R180 S1      
327m7466            J30   -156        A01X+012872Y+079364X0205Y0590R090 S1      
317m7466            VIA   -    MD0100PA01X+012872Y+079364X0190Y         S0      
317m7467            VIA   -    MD0080PA01X+035682Y+097210X0160Y    R180 S0      
327m7467            U26   -AM60       A01X+035865Y+097315X0177Y    R180 S1      
327m7467            J30   -56         A01X+014487Y+094089X0205Y0590R090 S1      
317m7467            VIA   -    MD0100PA01X+014487Y+094089X0190Y         S0      
317m7468            VIA   -    MD0080PA01X+035682Y+095297X0160Y    R180 S0      
327m7468            U26   -AF60       A01X+035865Y+095402X0177Y    R180 S1      
327m7468            J30   -45         A01X+014487Y+090408X0205Y0590R090 S1      
317m7468            VIA   -    MD0100PA01X+014487Y+090408X0190Y         S0      
317m7469            VIA   -    MD0080PA01X+035682Y+093384X0160Y    R180 S0      
327m7469            U26   -Y60        A01X+035865Y+093488X0177Y    R180 S1      
327m7469            J30   -34         A01X+014487Y+086726X0205Y0590R090 S1      
317m7469            VIA   -    MD0100PA01X+014487Y+086726X0190Y         S0      
317m7470            VIA   -    MD0080PA01X+035682Y+091470X0160Y    R180 S0      
327m7470            U26   -P60        A01X+035865Y+091575X0177Y    R180 S1      
327m7470            J30   -23         A01X+014487Y+083045X0205Y0590R090 S1      
317m7470            VIA   -    MD0100PA01X+014487Y+083045X0190Y         S0      
317m7471            VIA   -    MD0080PA01X+035682Y+089557X0160Y    R180 S0      
327m7471            U26   -H60        A01X+035865Y+089662X0177Y    R180 S1      
327m7471            J30   -12         A01X+014487Y+079364X0205Y0590R090 S1      
317m7471            VIA   -    MD0100PA01X+014487Y+079364X0190Y         S0      
317m7472            VIA   -    MD0080PA01X+036422Y+090832X0160Y    R180 S0      
327m7472            U26   -M58        A01X+036606Y+090937X0177Y    R180 S1      
327m7472            J30   -20         A01X+014487Y+082042X0205Y0590R090 S1      
317m7472            VIA   -    MD0100PA01X+014487Y+082042X0190Y         S0      
317m7473            VIA   -    MD0080PA01X+035866Y+090514X0160Y    R180 S0      
327m7473            U26   -L60        A01X+036050Y+090618X0177Y    R180 S1      
327m7473            J30   -18         A01X+014487Y+081372X0205Y0590R090 S1      
317m7473            VIA   -    MD0100PA01X+014487Y+081372X0190Y         S0      
317m7474            VIA   -    MD0080PA01X+036237Y+090514X0160Y    R180 S0      
327m7474            U26   -L59        A01X+036420Y+090618X0177Y    R180 S1      
327m7474            J30   -161        A01X+012872Y+081038X0205Y0590R090 S1      
317m7474            VIA   -    MD0100PA01X+012872Y+081038X0190Y         S0      
317m7475            VIA   -    MD0080PA01X+035682Y+090195X0160Y    R180 S0      
327m7475            U26   -K60        A01X+035865Y+090299X0177Y    R180 S1      
327m7475            J30   -159        A01X+012872Y+080368X0205Y0590R090 S1      
317m7475            VIA   -    MD0100PA01X+012872Y+080368X0190Y         S0      
317m7476            VIA   -    MD0080PA01X+036422Y+090195X0160Y    R180 S0      
327m7476            U26   -K58        A01X+036606Y+090299X0177Y    R180 S1      
327m7476            J30   -16         A01X+014487Y+080703X0205Y0590R090 S1      
317m7476            VIA   -    MD0100PA01X+014487Y+080703X0190Y         S0      
317m7477            VIA   -    MD0080PA01X+035866Y+089876X0160Y    R180 S0      
327m7477            U26   -J60        A01X+036050Y+089980X0177Y    R180 S1      
327m7477            J30   -14         A01X+014487Y+080034X0205Y0590R090 S1      
317m7477            VIA   -    MD0100PA01X+014487Y+080034X0190Y         S0      
317m7478            VIA   -    MD0080PA01X+036237Y+089238X0160Y    R180 S0      
327m7478            U26   -G59        A01X+036420Y+089343X0177Y    R180 S1      
327m7478            J30   -154        A01X+012872Y+078695X0205Y0590R090 S1      
317m7478            VIA   -    MD0100PA01X+012872Y+078695X0190Y         S0      
317m7479            VIA   -    MD0080PA01X+036237Y+096254X0160Y    R180 S0      
327m7479            U26   -AJ59       A01X+036420Y+096358X0177Y    R180 S1      
327m7479            J30   -194        A01X+012872Y+092081X0205Y0590R090 S1      
317m7479            VIA   -    MD0100PA01X+012872Y+092081X0190Y         S0      
317m7480            VIA   -    MD0080PA01X+035682Y+095935X0160Y    R180 S0      
327m7480            U26   -AH60       A01X+035865Y+096040X0177Y    R180 S1      
327m7480            J30   -192        A01X+012872Y+091412X0205Y0590R090 S1      
317m7480            VIA   -    MD0100PA01X+012872Y+091412X0190Y         S0      
317m7481            VIA   -    MD0080PA01X+035682Y+088919X0160Y    R180 S0      
327m7481            U26   -F60        A01X+035865Y+089024X0177Y    R180 S1      
327m7481            J30   -152        A01X+012872Y+078026X0205Y0590R090 S1      
317m7481            VIA   -    MD0100PA01X+012872Y+078026X0190Y         S0      
317m7482            VIA   -    MD0080PA01X+036422Y+095935X0160Y    R180 S0      
327m7482            U26   -AH58       A01X+036606Y+096040X0177Y    R180 S1      
327m7482            J30   -49         A01X+014487Y+091746X0205Y0590R090 S1      
317m7482            VIA   -    MD0100PA01X+014487Y+091746X0190Y         S0      
317m7483            VIA   -    MD0080PA01X+035866Y+095616X0160Y    R180 S0      
327m7483            U26   -AG60       A01X+036050Y+095721X0177Y    R180 S1      
327m7483            J30   -47         A01X+014487Y+091077X0205Y0590R090 S1      
317m7483            VIA   -    MD0100PA01X+014487Y+091077X0190Y         S0      
317m7484            VIA   -    MD0080PA01X+036237Y+094978X0160Y    R180 S0      
327m7484            U26   -AE59       A01X+036420Y+095083X0177Y    R180 S1      
327m7484            J30   -187        A01X+012872Y+089738X0205Y0590R090 S1      
317m7484            VIA   -    MD0100PA01X+012872Y+089738X0190Y         S0      
317m7485            VIA   -    MD0080PA01X+035682Y+094659X0160Y    R180 S0      
327m7485            U26   -AD60       A01X+035865Y+094764X0177Y    R180 S1      
327m7485            J30   -185        A01X+012872Y+089069X0205Y0590R090 S1      
317m7485            VIA   -    MD0100PA01X+012872Y+089069X0190Y         S0      
317m7486            VIA   -    MD0080PA01X+036422Y+094659X0160Y    R180 S0      
327m7486            U26   -AD58       A01X+036606Y+094764X0177Y    R180 S1      
327m7486            J30   -42         A01X+014487Y+089404X0205Y0590R090 S1      
317m7486            VIA   -    MD0100PA01X+014487Y+089404X0190Y         S0      
317m7487            VIA   -    MD0080PA01X+035866Y+094340X0160Y    R180 S0      
327m7487            U26   -AC60       A01X+036050Y+094445X0177Y    R180 S1      
327m7487            J30   -40         A01X+014487Y+088734X0205Y0590R090 S1      
317m7487            VIA   -    MD0100PA01X+014487Y+088734X0190Y         S0      
317m7488            VIA   -    MD0080PA01X+036237Y+094340X0160Y    R180 S0      
317m7488            VIA   -    MD0100PA01X+012872Y+088400X0190Y         S0      
327m7488            J30   -183        A01X+012872Y+088400X0205Y0590R090 S1      
327m7488            U26   -AC59       A01X+036420Y+094445X0177Y    R180 S1      
317m7489            VIA   -    MD0080PA01X+035682Y+094021X0160Y    R180 S0      
327m7489            U26   -AB60       A01X+035865Y+094126X0177Y    R180 S1      
327m7489            J30   -181        A01X+012872Y+087730X0205Y0590R090 S1      
317m7489            VIA   -    MD0100PA01X+012872Y+087730X0190Y         S0      
317m7490            VIA   -    MD0080PA01X+036422Y+094021X0160Y    R180 S0      
327m7490            U26   -AB58       A01X+036606Y+094126X0177Y    R180 S1      
327m7490            J30   -38         A01X+014487Y+088065X0205Y0590R090 S1      
317m7490            VIA   -    MD0100PA01X+014487Y+088065X0190Y         S0      
317m7491            VIA   -    MD0080PA01X+035866Y+093702X0160Y    R180 S0      
327m7491            U26   -AA60       A01X+036050Y+093807X0177Y    R180 S1      
327m7491            J30   -36         A01X+014487Y+087396X0205Y0590R090 S1      
317m7491            VIA   -    MD0100PA01X+014487Y+087396X0190Y         S0      
317m7492            VIA   -    MD0080PA01X+036422Y+088919X0160Y    R180 S0      
327m7492            U26   -F58        A01X+036606Y+089024X0177Y    R180 S1      
327m7492            J30   -9          A01X+014487Y+078360X0205Y0590R090 S1      
317m7492            VIA   -    MD0100PA01X+014487Y+078360X0190Y         S0      
317m7493            VIA   -    MD0080PA01X+036237Y+093065X0160Y    R180 S0      
327m7493            U26   -W59        A01X+036420Y+093169X0177Y    R180 S1      
327m7493            J30   -176        A01X+012872Y+086057X0205Y0590R090 S1      
317m7493            VIA   -    MD0100PA01X+012872Y+086057X0190Y         S0      
317m7494            VIA   -    MD0080PA01X+035682Y+092746X0160Y    R180 S0      
327m7494            U26   -V60        A01X+035865Y+092850X0177Y    R180 S1      
327m7494            J30   -174        A01X+012872Y+085388X0205Y0590R090 S1      
317m7494            VIA   -    MD0100PA01X+012872Y+085388X0190Y         S0      
317m7495            VIA   -    MD0080PA01X+036422Y+092746X0160Y    R180 S0      
327m7495            U26   -V58        A01X+036606Y+092850X0177Y    R180 S1      
327m7495            J30   -31         A01X+014487Y+085723X0205Y0590R090 S1      
317m7495            VIA   -    MD0100PA01X+014487Y+085723X0190Y         S0      
317m7496            VIA   -    MD0080PA01X+035866Y+092427X0160Y    R180 S0      
327m7496            U26   -U60        A01X+036050Y+092532X0177Y    R180 S1      
327m7496            J30   -29         A01X+014487Y+085053X0205Y0590R090 S1      
317m7496            VIA   -    MD0100PA01X+014487Y+085053X0190Y         S0      
317m7497            VIA   -    MD0080PA01X+036237Y+092427X0160Y    R180 S0      
327m7497            U26   -U59        A01X+036420Y+092532X0177Y    R180 S1      
327m7497            J30   -172        A01X+012872Y+084719X0205Y0590R090 S1      
317m7497            VIA   -    MD0100PA01X+012872Y+084719X0190Y         S0      
317m7498            VIA   -    MD0080PA01X+035682Y+092108X0160Y    R180 S0      
327m7498            U26   -T60        A01X+035865Y+092213X0177Y    R180 S1      
327m7498            J30   -170        A01X+012872Y+084049X0205Y0590R090 S1      
317m7498            VIA   -    MD0100PA01X+012872Y+084049X0190Y         S0      
317m7499            VIA   -    MD0080PA01X+036422Y+092108X0160Y    R180 S0      
327m7499            U26   -T58        A01X+036606Y+092213X0177Y    R180 S1      
327m7499            J30   -27         A01X+014487Y+084384X0205Y0590R090 S1      
317m7499            VIA   -    MD0100PA01X+014487Y+084384X0190Y         S0      
317m7500            VIA   -    MD0080PA01X+035866Y+091789X0160Y    R180 S0      
327m7500            U26   -R60        A01X+036050Y+091894X0177Y    R180 S1      
327m7500            J30   -25         A01X+014487Y+083715X0205Y0590R090 S1      
317m7500            VIA   -    MD0100PA01X+014487Y+083715X0190Y         S0      
317m7501            VIA   -    MD0080PA01X+036237Y+091151X0160Y    R180 S0      
327m7501            U26   -N59        A01X+036420Y+091256X0177Y    R180 S1      
327m7501            J30   -165        A01X+012872Y+082376X0205Y0590R090 S1      
317m7501            VIA   -    MD0100PA01X+012872Y+082376X0190Y         S0      
317m7502            VIA   -    MD0080PA01X+035682Y+090832X0160Y    R180 S0      
327m7502            U26   -M60        A01X+035865Y+090937X0177Y    R180 S1      
327m7502            J30   -163        A01X+012872Y+081707X0205Y0590R090 S1      
317m7502            VIA   -    MD0100PA01X+012872Y+081707X0190Y         S0      
317m7503            VIA   -    MD0080PA01X+035866Y+088600X0160Y    R180 S0      
327m7503            U26   -E60        A01X+036050Y+088705X0177Y    R180 S1      
327m7503            J30   -7          A01X+014487Y+077691X0205Y0590R090 S1      
317m7503            VIA   -    MD0100PA01X+014487Y+077691X0190Y         S0      
317m7504            VIA   -    MD0080PA01X+036237Y+099443X0160Y    R180 S0      
327m7504            U26   -AW59       A01X+036420Y+099547X0177Y    R180 S1      
327m7504            J30   -209        A01X+012872Y+097100X0205Y0590R090 S1      
317m7504            VIA   -    MD0100PA01X+012872Y+097100X0190Y         S0      
317m7505            VIA   -    MD0080PA01X+035682Y+099124X0160Y    R180 S0      
327m7505            U26   -AV60       A01X+035865Y+099228X0177Y    R180 S1      
327m7505            J30   -64         A01X+014487Y+096766X0205Y0590R090 S1      
317m7505            VIA   -    MD0100PA01X+014487Y+096766X0190Y         S0      
317m7506            VIA   -    MD0080PA01X+036237Y+098167X0160Y    R180 S0      
327m7506            U26   -AR59       A01X+036420Y+098272X0177Y    R180 S1      
327m7506            J30   -205        A01X+012872Y+095762X0205Y0590R090 S1      
317m7506            VIA   -    MD0100PA01X+012872Y+095762X0190Y         S0      
317m7507            VIA   -    MD0080PA01X+035682Y+097848X0160Y    R180 S0      
327m7507            U26   -AP60       A01X+035865Y+097953X0177Y    R180 S1      
327m7507            J30   -203        A01X+012872Y+095093X0205Y0590R090 S1      
317m7507            VIA   -    MD0100PA01X+012872Y+095093X0190Y         S0      
317m7508            VIA   -    MD0080PA01X+036422Y+097848X0160Y    R180 S0      
327m7508            U26   -AP58       A01X+036606Y+097953X0177Y    R180 S1      
327m7508            J30   -60         A01X+014487Y+095427X0205Y0590R090 S1      
317m7508            VIA   -    MD0100PA01X+014487Y+095427X0190Y         S0      
317m7509            VIA   -    MD0080PA01X+035866Y+097529X0160Y    R180 S0      
327m7509            U26   -AN60       A01X+036050Y+097634X0177Y    R180 S1      
327m7509            J30   -58         A01X+014487Y+094758X0205Y0590R090 S1      
317m7509            VIA   -    MD0100PA01X+014487Y+094758X0190Y         S0      
317m7510            VIA   -    MD0080PA01X+036237Y+096892X0160Y    R180 S0      
327m7510            U26   -AL59       A01X+036420Y+096996X0177Y    R180 S1      
327m7510            J30   -198        A01X+012872Y+093419X0205Y0590R090 S1      
317m7510            VIA   -    MD0100PA01X+012872Y+093419X0190Y         S0      
317m7511            VIA   -    MD0080PA01X+035682Y+096573X0160Y    R180 S0      
327m7511            U26   -AK60       A01X+035865Y+096677X0177Y    R180 S1      
327m7511            J30   -196        A01X+012872Y+092750X0205Y0590R090 S1      
317m7511            VIA   -    MD0100PA01X+012872Y+092750X0190Y         S0      
317m7512            VIA   -    MD0080PA01X+036422Y+096573X0160Y    R180 S0      
327m7512            U26   -AK58       A01X+036606Y+096677X0177Y    R180 S1      
327m7512            J30   -53         A01X+014487Y+093085X0205Y0590R090 S1      
317m7512            VIA   -    MD0100PA01X+014487Y+093085X0190Y         S0      
317m7513            VIA   -    MD0080PA01X+035866Y+096254X0160Y    R180 S0      
327m7513            U26   -AJ60       A01X+036050Y+096358X0177Y    R180 S1      
327m7513            J30   -51         A01X+014487Y+092416X0205Y0590R090 S1      
317m7513            VIA   -    MD0100PA01X+014487Y+092416X0190Y         S0      
317m7514            VIA   -    MD0080PA01X+036422Y+100399X0160Y    R180 S0      
327m7514            U26   -BB58       A01X+036606Y+100504X0177Y    R180 S1      
317m7514            VIA   -    MD0100PA01X+014487Y+099443X0190Y         S0      
327m7514            J30   -72         A01X+014487Y+099443X0205Y0590R090 S1      
317m7515            VIA   -    MD0080PA01X+035682Y+100399X0160Y    R180 S0      
327m7515            U26   -BB60       A01X+035865Y+100504X0177Y    R180 S1      
327m7515            J30   -215        A01X+012872Y+099108X0205Y0590R090 S1      
317m7515            VIA   -    MD0100PA01X+012872Y+099108X0190Y         S0      
317m7516            VIA   -    MD0080PA01X+035866Y+100080X0160Y    R180 S0      
327m7516            U26   -BA60       A01X+036050Y+100185X0177Y    R180 S1      
327m7516            J30   -70         A01X+014487Y+098774X0205Y0590R090 S1      
317m7516            VIA   -    MD0100PA01X+014487Y+098774X0190Y         S0      
317m7517            VIA   -    MD0080PA01X+036237Y+100080X0160Y    R180 S0      
327m7517            U26   -BA59       A01X+036420Y+100185X0177Y    R180 S1      
327m7517            J30   -213        A01X+012872Y+098439X0205Y0590R090 S1      
317m7517            VIA   -    MD0100PA01X+012872Y+098439X0190Y         S0      
317m7518            VIA   -    MD0080PA01X+036422Y+099762X0160Y    R180 S0      
327m7518            U26   -AY58       A01X+036606Y+099866X0177Y    R180 S1      
327m7518            J30   -68         A01X+014487Y+098104X0205Y0590R090 S1      
317m7518            VIA   -    MD0100PA01X+014487Y+098104X0190Y         S0      
317m7519            VIA   -    MD0080PA01X+035682Y+099762X0160Y    R180 S0      
327m7519            U26   -AY60       A01X+035865Y+099866X0177Y    R180 S1      
327m7519            J30   -211        A01X+012872Y+097770X0205Y0590R090 S1      
317m7519            VIA   -    MD0100PA01X+012872Y+097770X0190Y         S0      
317m7520            VIA   -    MD0080PA01X+035866Y+099443X0160Y    R180 S0      
327m7520            U26   -AW60       A01X+036050Y+099547X0177Y    R180 S1      
327m7520            J30   -66         A01X+014487Y+097435X0205Y0590R090 S1      
317m7520            VIA   -    MD0100PA01X+014487Y+097435X0190Y         S0      
317m7521            VIA   -    MD0080PA01X+036237Y+098805X0160Y    R180 S0      
327m7521            U26   -AU59       A01X+036420Y+098910X0177Y    R180 S1      
327m7521            J30   -207        A01X+012872Y+096431X0205Y0590R090 S1      
317m7521            VIA   -    MD0100PA01X+012872Y+096431X0190Y         S0      
317m7522            VIA   -    MD0080PA01X+035866Y+100718X0160Y    R180 S0      
317m7522            VIA   -    MD0100PA01X+012872Y+099778X0190Y         S0      
327m7522            J30   -217        A01X+012872Y+099778X0205Y0590R090 S1      
327m7522            U26   -BC60       A01X+036050Y+100823X0177Y    R180 S1      
317m7523            VIA   -    MD0080PA01X+035682Y+101037X0160Y    R180 S0      
317m7523            VIA   -    MD0100PA01X+012872Y+100112X0190Y         S0      
327m7523            J30   -218        A01X+012872Y+100112X0205Y0590R090 S1      
327m7523            U26   -BD60       A01X+035865Y+101142X0177Y    R180 S1      
317m7524            VIA   -    MD0080PA01X+036422Y+098486X0160Y    R180 S0      
327m7524            U26   -AT58       A01X+036606Y+098591X0177Y    R180 S1      
327m7524            R503  -2          A18X+015037Y+096097X0198Y0197R180 S2      
317m7524            VIA   -    MD0100PA18X+015037Y+096097X0190Y    R180 S0      
327m7525            J30   -62         A01X+014487Y+096097X0205Y0590R090 S1      
317m7525            VIA   -    MD0100PA00X+014487Y+096097X0190Y         S0      
327m7525            R503  -1          A18X+014722Y+096097X0198Y0197R180 S2      
317m7526            VIA   -    MD0080PA01X+133414Y+105357X0160Y         S0      
327m7526            U25   -BP60       A01X+133598Y+105252X0177Y    R180 S1      
317m7526            VIA   -    MD0100PA01X+112101Y+106470X0190Y         S0      
327m7526            J19   -87         A01X+112101Y+106470X0205Y0590R090 S1      
317m7527            VIA   -    MD0080PA01X+133599Y+104400X0160Y         S0      
327m7527            U25   -BL60       A01X+133783Y+104295X0177Y    R180 S1      
317m7527            VIA   -    MD0100PA01X+110487Y+105132X0190Y         S0      
327m7527            J19   -227        A01X+110487Y+105132X0205Y0590R090 S1      
317m7528            VIA   -    MD0080PA01X+133414Y+106632X0160Y         S0      
327m7528            U25   -BV60       A01X+133598Y+106528X0177Y    R180 S1      
317m7528            VIA   -    MD0100PA01X+112101Y+108478X0190Y         S0      
327m7528            J19   -93         A01X+112101Y+108478X0205Y0590R090 S1      
317m7529            VIA   -    MD0080PA01X+134154Y+114924X0160Y         S0      
327m7529            U25   -DD58       A01X+134338Y+114819X0177Y    R180 S1      
317m7529            VIA   -    MD0100PA01X+110487Y+123872X0190Y         S0      
327m7529            J19   -283        A01X+110487Y+123872X0205Y0590R090 S1      
317m7530            VIA   -    MD0080PA01X+134154Y+113010X0160Y         S0      
327m7530            U25   -CV58       A01X+134338Y+112906X0177Y    R180 S1      
317m7530            VIA   -    MD0100PA01X+110487Y+120191X0190Y         S0      
327m7530            J19   -272        A01X+110487Y+120191X0205Y0590R090 S1      
317m7531            VIA   -    MD0080PA01X+134154Y+111097X0160Y         S0      
327m7531            U25   -CM58       A01X+134338Y+110992X0177Y    R180 S1      
317m7531            VIA   -    MD0100PA01X+110487Y+116510X0190Y         S0      
327m7531            J19   -261        A01X+110487Y+116510X0205Y0590R090 S1      
317m7532            VIA   -    MD0080PA01X+134154Y+109184X0160Y         S0      
327m7532            U25   -CF58       A01X+134338Y+109079X0177Y    R180 S1      
317m7532            VIA   -    MD0100PA01X+110487Y+112829X0190Y         S0      
327m7532            J19   -250        A01X+110487Y+112829X0205Y0590R090 S1      
317m7533            VIA   -    MD0080PA01X+134154Y+107270X0160Y         S0      
327m7533            U25   -BY58       A01X+134338Y+107165X0177Y    R180 S1      
317m7533            VIA   -    MD0100PA01X+110487Y+109148X0190Y         S0      
327m7533            J19   -239        A01X+110487Y+109148X0205Y0590R090 S1      
317m7534            VIA   -    MD0080PA01X+133414Y+114286X0160Y         S0      
327m7534            U25   -DB60       A01X+133598Y+114181X0177Y    R180 S1      
317m7534            VIA   -    MD0100PA01X+112101Y+123203X0190Y         S0      
327m7534            J19   -137        A01X+112101Y+123203X0205Y0590R090 S1      
317m7535            VIA   -    MD0080PA01X+133414Y+112372X0160Y         S0      
327m7535            U25   -CT60       A01X+133598Y+112268X0177Y    R180 S1      
317m7535            VIA   -    MD0100PA01X+112101Y+119522X0190Y         S0      
327m7535            J19   -126        A01X+112101Y+119522X0205Y0590R090 S1      
317m7536            VIA   -    MD0080PA01X+133414Y+110459X0160Y         S0      
327m7536            U25   -CK60       A01X+133598Y+110354X0177Y    R180 S1      
317m7536            VIA   -    MD0100PA01X+112101Y+115841X0190Y         S0      
327m7536            J19   -115        A01X+112101Y+115841X0205Y0590R090 S1      
317m7537            VIA   -    MD0080PA01X+133414Y+108546X0160Y         S0      
327m7537            U25   -CD60       A01X+133598Y+108441X0177Y    R180 S1      
317m7537            VIA   -    MD0100PA01X+112101Y+112160X0190Y         S0      
327m7537            J19   -104        A01X+112101Y+112160X0205Y0590R090 S1      
317m7538            VIA   -    MD0080PA01X+133599Y+106951X0160Y         S0      
327m7538            U25   -BW60       A01X+133783Y+106846X0177Y    R180 S1      
317m7538            VIA   -    MD0100PA01X+112101Y+108813X0190Y         S0      
327m7538            J19   -94         A01X+112101Y+108813X0205Y0590R090 S1      
317m7539            VIA   -    MD0080PA01X+133969Y+114605X0160Y         S0      
327m7539            U25   -DC59       A01X+134153Y+114500X0177Y    R180 S1      
317m7539            VIA   -    MD0100PA01X+110487Y+123537X0190Y         S0      
327m7539            J19   -282        A01X+110487Y+123537X0205Y0590R090 S1      
317m7540            VIA   -    MD0080PA01X+133969Y+112691X0160Y         S0      
327m7540            U25   -CU59       A01X+134153Y+112587X0177Y    R180 S1      
317m7540            VIA   -    MD0100PA01X+110487Y+119856X0190Y         S0      
327m7540            J19   -271        A01X+110487Y+119856X0205Y0590R090 S1      
317m7541            VIA   -    MD0080PA01X+133969Y+110778X0160Y         S0      
327m7541            U25   -CL59       A01X+134153Y+110673X0177Y    R180 S1      
317m7541            VIA   -    MD0100PA01X+110487Y+116175X0190Y         S0      
327m7541            J19   -260        A01X+110487Y+116175X0205Y0590R090 S1      
317m7542            VIA   -    MD0080PA01X+133969Y+108865X0160Y         S0      
327m7542            U25   -CE59       A01X+134153Y+108760X0177Y    R180 S1      
317m7542            VIA   -    MD0100PA01X+110487Y+112494X0190Y         S0      
327m7542            J19   -249        A01X+110487Y+112494X0205Y0590R090 S1      
317m7543            VIA   -    MD0080PA01X+133969Y+106951X0160Y         S0      
327m7543            U25   -BW59       A01X+134153Y+106846X0177Y    R180 S1      
317m7543            VIA   -    MD0100PA01X+110487Y+108813X0190Y         S0      
327m7543            J19   -238        A01X+110487Y+108813X0205Y0590R090 S1      
317m7544            VIA   -    MD0080PA01X+133599Y+114605X0160Y         S0      
327m7544            U25   -DC60       A01X+133783Y+114500X0177Y    R180 S1      
317m7544            VIA   -    MD0100PA01X+112101Y+123537X0190Y         S0      
327m7544            J19   -138        A01X+112101Y+123537X0205Y0590R090 S1      
317m7545            VIA   -    MD0080PA01X+133599Y+112691X0160Y         S0      
327m7545            U25   -CU60       A01X+133783Y+112587X0177Y    R180 S1      
317m7545            VIA   -    MD0100PA01X+112101Y+119856X0190Y         S0      
327m7545            J19   -127        A01X+112101Y+119856X0205Y0590R090 S1      
317m7546            VIA   -    MD0080PA01X+133599Y+110778X0160Y         S0      
327m7546            U25   -CL60       A01X+133783Y+110673X0177Y    R180 S1      
317m7546            VIA   -    MD0100PA01X+112101Y+116175X0190Y         S0      
327m7546            J19   -116        A01X+112101Y+116175X0205Y0590R090 S1      
317m7547            VIA   -    MD0080PA01X+133599Y+108865X0160Y         S0      
327m7547            U25   -CE60       A01X+133783Y+108760X0177Y    R180 S1      
317m7547            VIA   -    MD0100PA01X+112101Y+112494X0190Y         S0      
327m7547            J19   -105        A01X+112101Y+112494X0205Y0590R090 S1      
317m7548            VIA   -    MD0080PA01X+133969Y+110140X0160Y         S0      
327m7548            U25   -CJ59       A01X+134153Y+110036X0177Y    R180 S1      
317m7548            VIA   -    MD0100PA01X+112101Y+115171X0190Y         S0      
327m7548            J19   -113        A01X+112101Y+115171X0205Y0590R090 S1      
317m7549            VIA   -    MD0080PA01X+133414Y+109821X0160Y         S0      
327m7549            U25   -CH60       A01X+133598Y+109717X0177Y    R180 S1      
317m7549            VIA   -    MD0100PA01X+112101Y+114502X0190Y         S0      
327m7549            J19   -111        A01X+112101Y+114502X0205Y0590R090 S1      
317m7550            VIA   -    MD0080PA01X+134154Y+109821X0160Y         S0      
327m7550            U25   -CH58       A01X+134338Y+109717X0177Y    R180 S1      
317m7550            VIA   -    MD0100PA01X+110487Y+114167X0190Y         S0      
327m7550            J19   -254        A01X+110487Y+114167X0205Y0590R090 S1      
317m7551            VIA   -    MD0080PA01X+133599Y+109502X0160Y         S0      
327m7551            U25   -CG60       A01X+133783Y+109398X0177Y    R180 S1      
317m7551            VIA   -    MD0100PA01X+110487Y+113498X0190Y         S0      
327m7551            J19   -252        A01X+110487Y+113498X0205Y0590R090 S1      
317m7552            VIA   -    MD0080PA01X+133969Y+109502X0160Y         S0      
327m7552            U25   -CG59       A01X+134153Y+109398X0177Y    R180 S1      
317m7552            VIA   -    MD0100PA01X+112101Y+113833X0190Y         S0      
327m7552            J19   -109        A01X+112101Y+113833X0205Y0590R090 S1      
317m7553            VIA   -    MD0080PA01X+133414Y+109184X0160Y         S0      
327m7553            U25   -CF60       A01X+133598Y+109079X0177Y    R180 S1      
317m7553            VIA   -    MD0100PA01X+112101Y+113163X0190Y         S0      
327m7553            J19   -107        A01X+112101Y+113163X0205Y0590R090 S1      
317m7554            VIA   -    MD0080PA01X+134154Y+108546X0160Y         S0      
327m7554            U25   -CD58       A01X+134338Y+108441X0177Y    R180 S1      
317m7554            VIA   -    MD0100PA01X+110487Y+111825X0190Y         S0      
327m7554            J19   -247        A01X+110487Y+111825X0205Y0590R090 S1      
317m7555            VIA   -    MD0080PA01X+133414Y+115561X0160Y         S0      
327m7555            U25   -DF60       A01X+133598Y+115457X0177Y    R180 S1      
317m7555            VIA   -    MD0100PA01X+110487Y+125211X0190Y         S0      
327m7555            J19   -287        A01X+110487Y+125211X0205Y0590R090 S1      
317m7556            VIA   -    MD0080PA01X+133599Y+115242X0160Y         S0      
327m7556            U25   -DE60       A01X+133783Y+115138X0177Y    R180 S1      
317m7556            VIA   -    MD0100PA01X+110487Y+124541X0190Y         S0      
327m7556            J19   -285        A01X+110487Y+124541X0205Y0590R090 S1      
317m7557            VIA   -    MD0080PA01X+133599Y+108227X0160Y         S0      
327m7557            U25   -CC60       A01X+133783Y+108122X0177Y    R180 S1      
317m7557            VIA   -    MD0100PA01X+110487Y+111156X0190Y         S0      
327m7557            J19   -245        A01X+110487Y+111156X0205Y0590R090 S1      
317m7558            VIA   -    MD0080PA01X+133969Y+115242X0160Y         S0      
327m7558            U25   -DE59       A01X+134153Y+115138X0177Y    R180 S1      
317m7558            VIA   -    MD0100PA01X+112101Y+124876X0190Y         S0      
327m7558            J19   -142        A01X+112101Y+124876X0205Y0590R090 S1      
317m7559            VIA   -    MD0080PA01X+133414Y+114924X0160Y         S0      
327m7559            U25   -DD60       A01X+133598Y+114819X0177Y    R180 S1      
317m7559            VIA   -    MD0100PA01X+112101Y+124207X0190Y         S0      
327m7559            J19   -140        A01X+112101Y+124207X0205Y0590R090 S1      
317m7560            VIA   -    MD0080PA01X+134154Y+114286X0160Y         S0      
327m7560            U25   -DB58       A01X+134338Y+114181X0177Y    R180 S1      
317m7560            VIA   -    MD0100PA01X+110487Y+122868X0190Y         S0      
327m7560            J19   -280        A01X+110487Y+122868X0205Y0590R090 S1      
317m7561            VIA   -    MD0080PA01X+133599Y+113967X0160Y         S0      
327m7561            U25   -DA60       A01X+133783Y+113862X0177Y    R180 S1      
317m7561            VIA   -    MD0100PA01X+110487Y+122199X0190Y         S0      
327m7561            J19   -278        A01X+110487Y+122199X0205Y0590R090 S1      
317m7562            VIA   -    MD0080PA01X+133969Y+113967X0160Y         S0      
327m7562            U25   -DA59       A01X+134153Y+113862X0177Y    R180 S1      
317m7562            VIA   -    MD0100PA01X+112101Y+122534X0190Y         S0      
327m7562            J19   -135        A01X+112101Y+122534X0205Y0590R090 S1      
317m7563            VIA   -    MD0080PA01X+133414Y+113648X0160Y         S0      
327m7563            U25   -CY60       A01X+133598Y+113543X0177Y    R180 S1      
317m7563            VIA   -    MD0100PA01X+112101Y+121864X0190Y         S0      
327m7563            J19   -133        A01X+112101Y+121864X0205Y0590R090 S1      
317m7564            VIA   -    MD0080PA01X+134154Y+113648X0160Y         S0      
327m7564            U25   -CY58       A01X+134338Y+113543X0177Y    R180 S1      
317m7564            VIA   -    MD0100PA01X+110487Y+121530X0190Y         S0      
327m7564            J19   -276        A01X+110487Y+121530X0205Y0590R090 S1      
317m7565            VIA   -    MD0080PA01X+133599Y+113329X0160Y         S0      
327m7565            U25   -CW60       A01X+133783Y+113224X0177Y    R180 S1      
317m7565            VIA   -    MD0100PA01X+110487Y+120860X0190Y         S0      
327m7565            J19   -274        A01X+110487Y+120860X0205Y0590R090 S1      
317m7566            VIA   -    MD0080PA01X+133969Y+113329X0160Y         S0      
327m7566            U25   -CW59       A01X+134153Y+113224X0177Y    R180 S1      
317m7566            VIA   -    MD0100PA01X+112101Y+121195X0190Y         S0      
327m7566            J19   -131        A01X+112101Y+121195X0205Y0590R090 S1      
317m7567            VIA   -    MD0080PA01X+133414Y+113010X0160Y         S0      
327m7567            U25   -CV60       A01X+133598Y+112906X0177Y    R180 S1      
317m7567            VIA   -    MD0100PA01X+112101Y+120526X0190Y         S0      
327m7567            J19   -129        A01X+112101Y+120526X0205Y0590R090 S1      
317m7568            VIA   -    MD0080PA01X+133969Y+108227X0160Y         S0      
327m7568            U25   -CC59       A01X+134153Y+108122X0177Y    R180 S1      
317m7568            VIA   -    MD0100PA01X+112101Y+111490X0190Y         S0      
327m7568            J19   -102        A01X+112101Y+111490X0205Y0590R090 S1      
317m7569            VIA   -    MD0080PA01X+134154Y+112372X0160Y         S0      
327m7569            U25   -CT58       A01X+134338Y+112268X0177Y    R180 S1      
317m7569            VIA   -    MD0100PA01X+110487Y+119187X0190Y         S0      
327m7569            J19   -269        A01X+110487Y+119187X0205Y0590R090 S1      
317m7570            VIA   -    MD0080PA01X+133599Y+112054X0160Y         S0      
327m7570            U25   -CR60       A01X+133783Y+111949X0177Y    R180 S1      
317m7570            VIA   -    MD0100PA01X+110487Y+118518X0190Y         S0      
327m7570            J19   -267        A01X+110487Y+118518X0205Y0590R090 S1      
317m7571            VIA   -    MD0080PA01X+133969Y+112054X0160Y         S0      
327m7571            U25   -CR59       A01X+134153Y+111949X0177Y    R180 S1      
317m7571            VIA   -    MD0100PA01X+112101Y+118852X0190Y         S0      
327m7571            J19   -124        A01X+112101Y+118852X0205Y0590R090 S1      
317m7572            VIA   -    MD0080PA01X+133414Y+111735X0160Y         S0      
327m7572            U25   -CP60       A01X+133598Y+111630X0177Y    R180 S1      
317m7572            VIA   -    MD0100PA01X+112101Y+118183X0190Y         S0      
327m7572            J19   -122        A01X+112101Y+118183X0205Y0590R090 S1      
317m7573            VIA   -    MD0080PA01X+134154Y+111735X0160Y         S0      
327m7573            U25   -CP58       A01X+134338Y+111630X0177Y    R180 S1      
317m7573            VIA   -    MD0100PA01X+110487Y+117848X0190Y         S0      
327m7573            J19   -265        A01X+110487Y+117848X0205Y0590R090 S1      
317m7574            VIA   -    MD0080PA01X+133599Y+111416X0160Y         S0      
327m7574            U25   -CN60       A01X+133783Y+111311X0177Y    R180 S1      
317m7574            VIA   -    MD0100PA01X+110487Y+117179X0190Y         S0      
327m7574            J19   -263        A01X+110487Y+117179X0205Y0590R090 S1      
317m7575            VIA   -    MD0080PA01X+133969Y+111416X0160Y         S0      
327m7575            U25   -CN59       A01X+134153Y+111311X0177Y    R180 S1      
317m7575            VIA   -    MD0100PA01X+112101Y+117514X0190Y         S0      
327m7575            J19   -120        A01X+112101Y+117514X0205Y0590R090 S1      
317m7576            VIA   -    MD0080PA01X+133414Y+111097X0160Y         S0      
327m7576            U25   -CM60       A01X+133598Y+110992X0177Y    R180 S1      
317m7576            VIA   -    MD0100PA01X+112101Y+116844X0190Y         S0      
327m7576            J19   -118        A01X+112101Y+116844X0205Y0590R090 S1      
317m7577            VIA   -    MD0080PA01X+134154Y+110459X0160Y         S0      
327m7577            U25   -CK58       A01X+134338Y+110354X0177Y    R180 S1      
317m7577            VIA   -    MD0100PA01X+110487Y+115506X0190Y         S0      
327m7577            J19   -258        A01X+110487Y+115506X0205Y0590R090 S1      
317m7578            VIA   -    MD0080PA01X+133599Y+110140X0160Y         S0      
327m7578            U25   -CJ60       A01X+133783Y+110036X0177Y    R180 S1      
317m7578            VIA   -    MD0100PA01X+110487Y+114837X0190Y         S0      
327m7578            J19   -256        A01X+110487Y+114837X0205Y0590R090 S1      
317m7579            VIA   -    MD0080PA01X+133414Y+107908X0160Y         S0      
327m7579            U25   -CB60       A01X+133598Y+107803X0177Y    R180 S1      
317m7579            VIA   -    MD0100PA01X+112101Y+110821X0190Y         S0      
327m7579            J19   -100        A01X+112101Y+110821X0205Y0590R090 S1      
317m7580            VIA   -    MD0080PA01X+133599Y+105038X0160Y         S0      
327m7580            U25   -BN60       A01X+133783Y+104933X0177Y    R180 S1      
317m7580            VIA   -    MD0100PA01X+110487Y+105801X0190Y         S0      
327m7580            J19   -229        A01X+110487Y+105801X0205Y0590R090 S1      
317m7581            VIA   -    MD0080PA01X+134154Y+104719X0160Y         S0      
327m7581            U25   -BM58       A01X+134338Y+104614X0177Y    R180 S1      
317m7581            VIA   -    MD0100PA01X+112101Y+105467X0190Y         S0      
327m7581            J19   -84         A01X+112101Y+105467X0205Y0590R090 S1      
317m7582            VIA   -    MD0080PA01X+134154Y+106632X0160Y         S0      
327m7582            U25   -BV58       A01X+134338Y+106528X0177Y    R180 S1      
317m7582            VIA   -    MD0100PA01X+110487Y+108144X0190Y         S0      
327m7582            J19   -236        A01X+110487Y+108144X0205Y0590R090 S1      
317m7583            VIA   -    MD0080PA01X+133599Y+106313X0160Y         S0      
327m7583            U25   -BU60       A01X+133783Y+106209X0177Y    R180 S1      
317m7583            VIA   -    MD0100PA01X+110487Y+107474X0190Y         S0      
327m7583            J19   -234        A01X+110487Y+107474X0205Y0590R090 S1      
317m7584            VIA   -    MD0080PA01X+133969Y+106313X0160Y         S0      
327m7584            U25   -BU59       A01X+134153Y+106209X0177Y    R180 S1      
317m7584            VIA   -    MD0100PA01X+112101Y+107809X0190Y         S0      
327m7584            J19   -91         A01X+112101Y+107809X0205Y0590R090 S1      
317m7585            VIA   -    MD0080PA01X+133414Y+105994X0160Y         S0      
327m7585            U25   -BT60       A01X+133598Y+105890X0177Y    R180 S1      
317m7585            VIA   -    MD0100PA01X+112101Y+107140X0190Y         S0      
327m7585            J19   -89         A01X+112101Y+107140X0205Y0590R090 S1      
317m7586            VIA   -    MD0080PA01X+134154Y+107908X0160Y         S0      
327m7586            U25   -CB58       A01X+134338Y+107803X0177Y    R180 S1      
317m7586            VIA   -    MD0100PA01X+110487Y+110486X0190Y         S0      
327m7586            J19   -243        A01X+110487Y+110486X0205Y0590R090 S1      
317m7587            VIA   -    MD0080PA01X+133599Y+107589X0160Y         S0      
327m7587            U25   -CA60       A01X+133783Y+107484X0177Y    R180 S1      
317m7587            VIA   -    MD0100PA01X+110487Y+109817X0190Y         S0      
327m7587            J19   -241        A01X+110487Y+109817X0205Y0590R090 S1      
317m7588            VIA   -    MD0080PA01X+133969Y+107589X0160Y         S0      
327m7588            U25   -CA59       A01X+134153Y+107484X0177Y    R180 S1      
317m7588            VIA   -    MD0100PA01X+112101Y+110152X0190Y         S0      
327m7588            J19   -98         A01X+112101Y+110152X0205Y0590R090 S1      
317m7589            VIA   -    MD0080PA01X+133414Y+107270X0160Y         S0      
327m7589            U25   -BY60       A01X+133598Y+107165X0177Y    R180 S1      
317m7589            VIA   -    MD0100PA01X+112101Y+109482X0190Y         S0      
327m7589            J19   -96         A01X+112101Y+109482X0205Y0590R090 S1      
317m7590            VIA   -    MD0080PA01X+133414Y+104081X0160Y         S0      
327m7590            U25   -BK60       A01X+133598Y+103976X0177Y    R180 S1      
317m7590            VIA   -    MD0100PA01X+112101Y+104797X0190Y         S0      
327m7590            J19   -82         A01X+112101Y+104797X0205Y0590R090 S1      
317m7591            VIA   -    MD0080PA01X+134154Y+104081X0160Y         S0      
327m7591            U25   -BK58       A01X+134338Y+103976X0177Y    R180 S1      
317m7591            VIA   -    MD0100PA01X+110487Y+104463X0190Y         S0      
327m7591            J19   -225        A01X+110487Y+104463X0205Y0590R090 S1      
317m7592            VIA   -    MD0080PA01X+133969Y+103762X0160Y         S0      
327m7592            U25   -BJ59       A01X+134153Y+103658X0177Y    R180 S1      
317m7592            VIA   -    MD0100PA01X+112101Y+104128X0190Y         S0      
327m7592            J19   -80         A01X+112101Y+104128X0205Y0590R090 S1      
317m7593            VIA   -    MD0080PA01X+133599Y+103762X0160Y         S0      
327m7593            U25   -BJ60       A01X+133783Y+103658X0177Y    R180 S1      
317m7593            VIA   -    MD0100PA01X+110487Y+103793X0190Y         S0      
327m7593            J19   -223        A01X+110487Y+103793X0205Y0590R090 S1      
317m7594            VIA   -    MD0080PA01X+133414Y+103443X0160Y         S0      
327m7594            U25   -BH60       A01X+133598Y+103339X0177Y    R180 S1      
317m7594            VIA   -    MD0100PA01X+112101Y+103459X0190Y         S0      
327m7594            J19   -78         A01X+112101Y+103459X0205Y0590R090 S1      
317m7595            VIA   -    MD0080PA01X+134154Y+103443X0160Y         S0      
327m7595            U25   -BH58       A01X+134338Y+103339X0177Y    R180 S1      
317m7595            VIA   -    MD0100PA01X+110487Y+103124X0190Y         S0      
327m7595            J19   -221        A01X+110487Y+103124X0205Y0590R090 S1      
317m7596            VIA   -    MD0080PA01X+133969Y+103124X0160Y         S0      
327m7596            U25   -BG59       A01X+134153Y+103020X0177Y    R180 S1      
317m7596            VIA   -    MD0100PA01X+112101Y+102789X0190Y         S0      
327m7596            J19   -76         A01X+112101Y+102789X0205Y0590R090 S1      
317m7597            VIA   -    MD0080PA01X+133969Y+105038X0160Y         S0      
327m7597            U25   -BN59       A01X+134153Y+104933X0177Y    R180 S1      
317m7597            VIA   -    MD0100PA01X+112101Y+106136X0190Y         S0      
327m7597            J19   -86         A01X+112101Y+106136X0205Y0590R090 S1      
317m7598            VIA   -    MD0080PA01X+133851Y+100718X0160Y    R180 S0      
327m7598            J19   -74         A01X+112101Y+100112X0205Y0590R090 S1      
317m7598            VIA   -    MD0100PA01X+112101Y+100112X0190Y         S0      
327m7598            U25   -BC59       A01X+134035Y+100823X0177Y    R180 S1      
317m7599            VIA   -    MD0080PA01X+133851Y+097529X0160Y    R180 S0      
327m7599            U25   -AN59       A01X+134035Y+097634X0177Y    R180 S1      
317m7599            VIA   -    MD0100PA01X+110487Y+094423X0190Y         S0      
327m7599            J19   -201        A01X+110487Y+094423X0205Y0590R090 S1      
317m7600            VIA   -    MD0080PA01X+133851Y+095616X0160Y    R180 S0      
327m7600            U25   -AG59       A01X+134035Y+095720X0177Y    R180 S1      
317m7600            VIA   -    MD0100PA01X+110487Y+090742X0190Y         S0      
327m7600            J19   -190        A01X+110487Y+090742X0205Y0590R090 S1      
317m7601            VIA   -    MD0080PA01X+133851Y+093702X0160Y    R180 S0      
327m7601            U25   -AA59       A01X+134035Y+093807X0177Y    R180 S1      
317m7601            VIA   -    MD0100PA01X+110487Y+087061X0190Y         S0      
327m7601            J19   -179        A01X+110487Y+087061X0205Y0590R090 S1      
317m7602            VIA   -    MD0080PA01X+133851Y+091789X0160Y    R180 S0      
327m7602            U25   -R59        A01X+134035Y+091894X0177Y    R180 S1      
317m7602            VIA   -    MD0100PA01X+110487Y+083380X0190Y         S0      
327m7602            J19   -168        A01X+110487Y+083380X0205Y0590R090 S1      
317m7603            VIA   -    MD0080PA01X+133851Y+089876X0160Y    R180 S0      
327m7603            U25   -J59        A01X+134035Y+089980X0177Y    R180 S1      
317m7603            VIA   -    MD0100PA01X+110487Y+079699X0190Y         S0      
327m7603            J19   -157        A01X+110487Y+079699X0205Y0590R090 S1      
317m7604            VIA   -    MD0080PA01X+133481Y+096891X0160Y    R180 S0      
327m7604            U25   -AL60       A01X+133665Y+096996X0177Y    R180 S1      
317m7604            VIA   -    MD0100PA01X+112101Y+093754X0190Y         S0      
327m7604            J19   -55         A01X+112101Y+093754X0205Y0590R090 S1      
317m7605            VIA   -    MD0080PA01X+133481Y+094978X0160Y    R180 S0      
327m7605            U25   -AE60       A01X+133665Y+095083X0177Y    R180 S1      
317m7605            VIA   -    MD0100PA01X+112101Y+090073X0190Y         S0      
327m7605            J19   -44         A01X+112101Y+090073X0205Y0590R090 S1      
317m7606            VIA   -    MD0080PA01X+133481Y+093065X0160Y    R180 S0      
327m7606            U25   -W60        A01X+133665Y+093169X0177Y    R180 S1      
317m7606            VIA   -    MD0100PA01X+112101Y+086392X0190Y         S0      
327m7606            J19   -33         A01X+112101Y+086392X0205Y0590R090 S1      
317m7607            VIA   -    MD0080PA01X+133481Y+091151X0160Y    R180 S0      
327m7607            U25   -N60        A01X+133665Y+091256X0177Y    R180 S1      
317m7607            VIA   -    MD0100PA01X+112101Y+082711X0190Y         S0      
327m7607            J19   -22         A01X+112101Y+082711X0205Y0590R090 S1      
317m7608            VIA   -    MD0080PA01X+133481Y+089238X0160Y    R180 S0      
327m7608            U25   -G60        A01X+133665Y+089343X0177Y    R180 S1      
317m7608            VIA   -    MD0100PA01X+112101Y+079030X0190Y         S0      
327m7608            J19   -11         A01X+112101Y+079030X0205Y0590R090 S1      
317m7609            VIA   -    MD0080PA01X+134036Y+097210X0160Y    R180 S0      
327m7609            U25   -AM58       A01X+134220Y+097315X0177Y    R180 S1      
317m7609            VIA   -    MD0100PA01X+110487Y+094089X0190Y         S0      
327m7609            J19   -200        A01X+110487Y+094089X0205Y0590R090 S1      
317m7610            VIA   -    MD0080PA01X+134036Y+095297X0160Y    R180 S0      
327m7610            U25   -AF58       A01X+134220Y+095402X0177Y    R180 S1      
317m7610            VIA   -    MD0100PA01X+110487Y+090408X0190Y         S0      
327m7610            J19   -189        A01X+110487Y+090408X0205Y0590R090 S1      
317m7611            VIA   -    MD0080PA01X+134036Y+093384X0160Y    R180 S0      
327m7611            U25   -Y58        A01X+134220Y+093488X0177Y    R180 S1      
317m7611            VIA   -    MD0100PA01X+110487Y+086726X0190Y         S0      
327m7611            J19   -178        A01X+110487Y+086726X0205Y0590R090 S1      
317m7612            VIA   -    MD0080PA01X+134036Y+091470X0160Y    R180 S0      
327m7612            U25   -P58        A01X+134220Y+091575X0177Y    R180 S1      
317m7612            VIA   -    MD0100PA01X+110487Y+083045X0190Y         S0      
327m7612            J19   -167        A01X+110487Y+083045X0205Y0590R090 S1      
317m7613            VIA   -    MD0080PA01X+134036Y+089557X0160Y    R180 S0      
327m7613            U25   -H58        A01X+134220Y+089662X0177Y    R180 S1      
317m7613            VIA   -    MD0100PA01X+110487Y+079364X0190Y         S0      
327m7613            J19   -156        A01X+110487Y+079364X0205Y0590R090 S1      
317m7614            VIA   -    MD0080PA01X+133296Y+097210X0160Y    R180 S0      
327m7614            U25   -AM60       A01X+133480Y+097315X0177Y    R180 S1      
317m7614            VIA   -    MD0100PA01X+112101Y+094089X0190Y         S0      
327m7614            J19   -56         A01X+112101Y+094089X0205Y0590R090 S1      
317m7615            VIA   -    MD0080PA01X+133296Y+095297X0160Y    R180 S0      
327m7615            U25   -AF60       A01X+133480Y+095402X0177Y    R180 S1      
317m7615            VIA   -    MD0100PA01X+112101Y+090408X0190Y         S0      
327m7615            J19   -45         A01X+112101Y+090408X0205Y0590R090 S1      
317m7616            VIA   -    MD0080PA01X+133296Y+093384X0160Y    R180 S0      
327m7616            U25   -Y60        A01X+133480Y+093488X0177Y    R180 S1      
317m7616            VIA   -    MD0100PA01X+112101Y+086726X0190Y         S0      
327m7616            J19   -34         A01X+112101Y+086726X0205Y0590R090 S1      
317m7617            VIA   -    MD0080PA01X+133296Y+091470X0160Y    R180 S0      
327m7617            U25   -P60        A01X+133480Y+091575X0177Y    R180 S1      
317m7617            VIA   -    MD0100PA01X+112101Y+083045X0190Y         S0      
327m7617            J19   -23         A01X+112101Y+083045X0205Y0590R090 S1      
317m7618            VIA   -    MD0080PA01X+133296Y+089557X0160Y    R180 S0      
327m7618            U25   -H60        A01X+133480Y+089662X0177Y    R180 S1      
317m7618            VIA   -    MD0100PA01X+112101Y+079364X0190Y         S0      
327m7618            J19   -12         A01X+112101Y+079364X0205Y0590R090 S1      
317m7619            VIA   -    MD0080PA01X+134036Y+090832X0160Y    R180 S0      
327m7619            U25   -M58        A01X+134220Y+090937X0177Y    R180 S1      
317m7619            VIA   -    MD0100PA01X+112101Y+082041X0190Y         S0      
327m7619            J19   -20         A01X+112101Y+082041X0205Y0590R090 S1      
317m7620            VIA   -    MD0080PA01X+133481Y+090513X0160Y    R180 S0      
327m7620            U25   -L60        A01X+133665Y+090618X0177Y    R180 S1      
317m7620            VIA   -    MD0100PA01X+112101Y+081372X0190Y         S0      
327m7620            J19   -18         A01X+112101Y+081372X0205Y0590R090 S1      
317m7621            VIA   -    MD0080PA01X+133851Y+090513X0160Y    R180 S0      
327m7621            U25   -L59        A01X+134035Y+090618X0177Y    R180 S1      
317m7621            VIA   -    MD0100PA01X+110487Y+081037X0190Y         S0      
327m7621            J19   -161        A01X+110487Y+081037X0205Y0590R090 S1      
317m7622            VIA   -    MD0080PA01X+133296Y+090195X0160Y    R180 S0      
327m7622            U25   -K60        A01X+133480Y+090299X0177Y    R180 S1      
317m7622            VIA   -    MD0100PA01X+110487Y+080368X0190Y         S0      
327m7622            J19   -159        A01X+110487Y+080368X0205Y0590R090 S1      
317m7623            VIA   -    MD0080PA01X+134036Y+090195X0160Y    R180 S0      
327m7623            U25   -K58        A01X+134220Y+090299X0177Y    R180 S1      
317m7623            VIA   -    MD0100PA01X+112101Y+080703X0190Y         S0      
327m7623            J19   -16         A01X+112101Y+080703X0205Y0590R090 S1      
317m7624            VIA   -    MD0080PA01X+133481Y+089876X0160Y    R180 S0      
327m7624            U25   -J60        A01X+133665Y+089980X0177Y    R180 S1      
317m7624            VIA   -    MD0100PA01X+112101Y+080034X0190Y         S0      
327m7624            J19   -14         A01X+112101Y+080034X0205Y0590R090 S1      
317m7625            VIA   -    MD0080PA01X+133851Y+089238X0160Y    R180 S0      
327m7625            U25   -G59        A01X+134035Y+089343X0177Y    R180 S1      
317m7625            VIA   -    MD0100PA01X+110487Y+078695X0190Y         S0      
327m7625            J19   -154        A01X+110487Y+078695X0205Y0590R090 S1      
317m7626            VIA   -    MD0080PA01X+133851Y+096254X0160Y    R180 S0      
327m7626            U25   -AJ59       A01X+134035Y+096358X0177Y    R180 S1      
317m7626            VIA   -    MD0100PA01X+110487Y+092081X0190Y         S0      
327m7626            J19   -194        A01X+110487Y+092081X0205Y0590R090 S1      
317m7627            VIA   -    MD0080PA01X+133296Y+095935X0160Y    R180 S0      
327m7627            U25   -AH60       A01X+133480Y+096039X0177Y    R180 S1      
317m7627            VIA   -    MD0100PA01X+110487Y+091411X0190Y         S0      
327m7627            J19   -192        A01X+110487Y+091411X0205Y0590R090 S1      
317m7628            VIA   -    MD0080PA01X+133296Y+088919X0160Y    R180 S0      
327m7628            U25   -F60        A01X+133480Y+089024X0177Y    R180 S1      
317m7628            VIA   -    MD0100PA01X+110487Y+078026X0190Y         S0      
327m7628            J19   -152        A01X+110487Y+078026X0205Y0590R090 S1      
317m7629            VIA   -    MD0080PA01X+134036Y+095935X0160Y    R180 S0      
327m7629            U25   -AH58       A01X+134220Y+096039X0177Y    R180 S1      
317m7629            VIA   -    MD0100PA01X+112101Y+091746X0190Y         S0      
327m7629            J19   -49         A01X+112101Y+091746X0205Y0590R090 S1      
317m7630            VIA   -    MD0080PA01X+133481Y+095616X0160Y    R180 S0      
327m7630            U25   -AG60       A01X+133665Y+095720X0177Y    R180 S1      
317m7630            VIA   -    MD0100PA01X+112101Y+091077X0190Y         S0      
327m7630            J19   -47         A01X+112101Y+091077X0205Y0590R090 S1      
317m7631            VIA   -    MD0080PA01X+133851Y+094978X0160Y    R180 S0      
327m7631            U25   -AE59       A01X+134035Y+095083X0177Y    R180 S1      
317m7631            VIA   -    MD0100PA01X+110487Y+089738X0190Y         S0      
327m7631            J19   -187        A01X+110487Y+089738X0205Y0590R090 S1      
317m7632            VIA   -    MD0080PA01X+133296Y+094659X0160Y    R180 S0      
327m7632            U25   -AD60       A01X+133480Y+094764X0177Y    R180 S1      
317m7632            VIA   -    MD0100PA01X+110487Y+089069X0190Y         S0      
327m7632            J19   -185        A01X+110487Y+089069X0205Y0590R090 S1      
317m7633            VIA   -    MD0080PA01X+134036Y+094659X0160Y    R180 S0      
327m7633            U25   -AD58       A01X+134220Y+094764X0177Y    R180 S1      
317m7633            VIA   -    MD0100PA01X+112101Y+089404X0190Y         S0      
327m7633            J19   -42         A01X+112101Y+089404X0205Y0590R090 S1      
317m7634            VIA   -    MD0080PA01X+133481Y+094340X0160Y    R180 S0      
327m7634            U25   -AC60       A01X+133665Y+094445X0177Y    R180 S1      
317m7634            VIA   -    MD0100PA01X+112101Y+088734X0190Y         S0      
327m7634            J19   -40         A01X+112101Y+088734X0205Y0590R090 S1      
317m7635            VIA   -    MD0080PA01X+133851Y+094340X0160Y    R180 S0      
317m7635            VIA   -    MD0100PA01X+110487Y+088400X0190Y         S0      
327m7635            J19   -183        A01X+110487Y+088400X0205Y0590R090 S1      
327m7635            U25   -AC59       A01X+134035Y+094445X0177Y    R180 S1      
317m7636            VIA   -    MD0080PA01X+133296Y+094021X0160Y    R180 S0      
327m7636            U25   -AB60       A01X+133480Y+094126X0177Y    R180 S1      
317m7636            VIA   -    MD0100PA01X+110487Y+087730X0190Y         S0      
327m7636            J19   -181        A01X+110487Y+087730X0205Y0590R090 S1      
317m7637            VIA   -    MD0080PA01X+134036Y+094021X0160Y    R180 S0      
327m7637            U25   -AB58       A01X+134220Y+094126X0177Y    R180 S1      
317m7637            VIA   -    MD0100PA01X+112101Y+088065X0190Y         S0      
327m7637            J19   -38         A01X+112101Y+088065X0205Y0590R090 S1      
317m7638            VIA   -    MD0080PA01X+133481Y+093702X0160Y    R180 S0      
327m7638            U25   -AA60       A01X+133665Y+093807X0177Y    R180 S1      
317m7638            VIA   -    MD0100PA01X+112101Y+087396X0190Y         S0      
327m7638            J19   -36         A01X+112101Y+087396X0205Y0590R090 S1      
317m7639            VIA   -    MD0080PA01X+134036Y+088919X0160Y    R180 S0      
327m7639            U25   -F58        A01X+134220Y+089024X0177Y    R180 S1      
317m7639            VIA   -    MD0100PA01X+112101Y+078360X0190Y         S0      
327m7639            J19   -9          A01X+112101Y+078360X0205Y0590R090 S1      
317m7640            VIA   -    MD0080PA01X+133851Y+093065X0160Y    R180 S0      
327m7640            U25   -W59        A01X+134035Y+093169X0177Y    R180 S1      
317m7640            VIA   -    MD0100PA01X+110487Y+086057X0190Y         S0      
327m7640            J19   -176        A01X+110487Y+086057X0205Y0590R090 S1      
317m7641            VIA   -    MD0080PA01X+133296Y+092746X0160Y    R180 S0      
327m7641            U25   -V60        A01X+133480Y+092850X0177Y    R180 S1      
317m7641            VIA   -    MD0100PA01X+110487Y+085388X0190Y         S0      
327m7641            J19   -174        A01X+110487Y+085388X0205Y0590R090 S1      
317m7642            VIA   -    MD0080PA01X+134036Y+092746X0160Y    R180 S0      
327m7642            U25   -V58        A01X+134220Y+092850X0177Y    R180 S1      
317m7642            VIA   -    MD0100PA01X+112101Y+085722X0190Y         S0      
327m7642            J19   -31         A01X+112101Y+085722X0205Y0590R090 S1      
317m7643            VIA   -    MD0080PA01X+133481Y+092427X0160Y    R180 S0      
327m7643            U25   -U60        A01X+133665Y+092532X0177Y    R180 S1      
317m7643            VIA   -    MD0100PA01X+112101Y+085053X0190Y         S0      
327m7643            J19   -29         A01X+112101Y+085053X0205Y0590R090 S1      
317m7644            VIA   -    MD0080PA01X+133851Y+092427X0160Y    R180 S0      
327m7644            U25   -U59        A01X+134035Y+092532X0177Y    R180 S1      
317m7644            VIA   -    MD0100PA01X+110487Y+084718X0190Y         S0      
327m7644            J19   -172        A01X+110487Y+084718X0205Y0590R090 S1      
317m7645            VIA   -    MD0080PA01X+133296Y+092108X0160Y    R180 S0      
327m7645            U25   -T60        A01X+133480Y+092213X0177Y    R180 S1      
317m7645            VIA   -    MD0100PA01X+110487Y+084049X0190Y         S0      
327m7645            J19   -170        A01X+110487Y+084049X0205Y0590R090 S1      
317m7646            VIA   -    MD0080PA01X+134036Y+092108X0160Y    R180 S0      
327m7646            U25   -T58        A01X+134220Y+092213X0177Y    R180 S1      
317m7646            VIA   -    MD0100PA01X+112101Y+084384X0190Y         S0      
327m7646            J19   -27         A01X+112101Y+084384X0205Y0590R090 S1      
317m7647            VIA   -    MD0080PA01X+133481Y+091789X0160Y    R180 S0      
327m7647            U25   -R60        A01X+133665Y+091894X0177Y    R180 S1      
317m7647            VIA   -    MD0100PA01X+112101Y+083715X0190Y         S0      
327m7647            J19   -25         A01X+112101Y+083715X0205Y0590R090 S1      
317m7648            VIA   -    MD0080PA01X+133851Y+091151X0160Y    R180 S0      
327m7648            U25   -N59        A01X+134035Y+091256X0177Y    R180 S1      
317m7648            VIA   -    MD0100PA01X+110487Y+082376X0190Y         S0      
327m7648            J19   -165        A01X+110487Y+082376X0205Y0590R090 S1      
317m7649            VIA   -    MD0080PA01X+133296Y+090832X0160Y    R180 S0      
327m7649            U25   -M60        A01X+133480Y+090937X0177Y    R180 S1      
317m7649            VIA   -    MD0100PA01X+110487Y+081707X0190Y         S0      
327m7649            J19   -163        A01X+110487Y+081707X0205Y0590R090 S1      
317m7650            VIA   -    MD0080PA01X+133481Y+088600X0160Y    R180 S0      
327m7650            U25   -E60        A01X+133665Y+088705X0177Y    R180 S1      
317m7650            VIA   -    MD0100PA01X+112101Y+077691X0190Y         S0      
327m7650            J19   -7          A01X+112101Y+077691X0205Y0590R090 S1      
317m7651            VIA   -    MD0080PA01X+133851Y+099443X0160Y    R180 S0      
327m7651            U25   -AW59       A01X+134035Y+099547X0177Y    R180 S1      
317m7651            VIA   -    MD0100PA01X+110487Y+097100X0190Y         S0      
327m7651            J19   -209        A01X+110487Y+097100X0205Y0590R090 S1      
317m7652            VIA   -    MD0080PA01X+133296Y+099124X0160Y    R180 S0      
327m7652            U25   -AV60       A01X+133480Y+099228X0177Y    R180 S1      
317m7652            VIA   -    MD0100PA01X+112101Y+096766X0190Y         S0      
327m7652            J19   -64         A01X+112101Y+096766X0205Y0590R090 S1      
317m7653            VIA   -    MD0080PA01X+133851Y+098167X0160Y    R180 S0      
327m7653            U25   -AR59       A01X+134035Y+098272X0177Y    R180 S1      
317m7653            VIA   -    MD0100PA01X+110487Y+095762X0190Y         S0      
327m7653            J19   -205        A01X+110487Y+095762X0205Y0590R090 S1      
317m7654            VIA   -    MD0080PA01X+133296Y+097848X0160Y    R180 S0      
327m7654            U25   -AP60       A01X+133480Y+097953X0177Y    R180 S1      
317m7654            VIA   -    MD0100PA01X+110487Y+095092X0190Y         S0      
327m7654            J19   -203        A01X+110487Y+095092X0205Y0590R090 S1      
317m7655            VIA   -    MD0080PA01X+134036Y+097848X0160Y    R180 S0      
327m7655            U25   -AP58       A01X+134220Y+097953X0177Y    R180 S1      
317m7655            VIA   -    MD0100PA01X+112101Y+095427X0190Y         S0      
327m7655            J19   -60         A01X+112101Y+095427X0205Y0590R090 S1      
317m7656            VIA   -    MD0080PA01X+133481Y+097529X0160Y    R180 S0      
327m7656            U25   -AN60       A01X+133665Y+097634X0177Y    R180 S1      
317m7656            VIA   -    MD0100PA01X+112101Y+094758X0190Y         S0      
327m7656            J19   -58         A01X+112101Y+094758X0205Y0590R090 S1      
317m7657            VIA   -    MD0080PA01X+133851Y+096891X0160Y    R180 S0      
327m7657            U25   -AL59       A01X+134035Y+096996X0177Y    R180 S1      
317m7657            VIA   -    MD0100PA01X+110487Y+093419X0190Y         S0      
327m7657            J19   -198        A01X+110487Y+093419X0205Y0590R090 S1      
317m7658            VIA   -    MD0080PA01X+133296Y+096572X0160Y    R180 S0      
327m7658            U25   -AK60       A01X+133480Y+096677X0177Y    R180 S1      
317m7658            VIA   -    MD0100PA01X+110487Y+092750X0190Y         S0      
327m7658            J19   -196        A01X+110487Y+092750X0205Y0590R090 S1      
317m7659            VIA   -    MD0080PA01X+134036Y+096572X0160Y    R180 S0      
327m7659            U25   -AK58       A01X+134220Y+096677X0177Y    R180 S1      
317m7659            VIA   -    MD0100PA01X+112101Y+093085X0190Y         S0      
327m7659            J19   -53         A01X+112101Y+093085X0205Y0590R090 S1      
317m7660            VIA   -    MD0080PA01X+133481Y+096254X0160Y    R180 S0      
327m7660            U25   -AJ60       A01X+133665Y+096358X0177Y    R180 S1      
317m7660            VIA   -    MD0100PA01X+112101Y+092415X0190Y         S0      
327m7660            J19   -51         A01X+112101Y+092415X0205Y0590R090 S1      
317m7661            VIA   -    MD0080PA01X+134036Y+100399X0160Y    R180 S0      
327m7661            J19   -72         A01X+112101Y+099443X0205Y0590R090 S1      
317m7661            VIA   -    MD0100PA01X+112101Y+099443X0190Y         S0      
327m7661            U25   -BB58       A01X+134220Y+100504X0177Y    R180 S1      
317m7662            VIA   -    MD0080PA01X+133296Y+100399X0160Y    R180 S0      
327m7662            U25   -BB60       A01X+133480Y+100504X0177Y    R180 S1      
317m7662            VIA   -    MD0100PA01X+110487Y+099108X0190Y         S0      
327m7662            J19   -215        A01X+110487Y+099108X0205Y0590R090 S1      
317m7663            VIA   -    MD0080PA01X+133481Y+100080X0160Y    R180 S0      
327m7663            U25   -BA60       A01X+133665Y+100185X0177Y    R180 S1      
317m7663            VIA   -    MD0100PA01X+112101Y+098774X0190Y         S0      
327m7663            J19   -70         A01X+112101Y+098774X0205Y0590R090 S1      
317m7664            VIA   -    MD0080PA01X+133851Y+100080X0160Y    R180 S0      
327m7664            U25   -BA59       A01X+134035Y+100185X0177Y    R180 S1      
317m7664            VIA   -    MD0100PA01X+110487Y+098439X0190Y         S0      
327m7664            J19   -213        A01X+110487Y+098439X0205Y0590R090 S1      
317m7665            VIA   -    MD0080PA01X+134036Y+099762X0160Y    R180 S0      
327m7665            U25   -AY58       A01X+134220Y+099866X0177Y    R180 S1      
317m7665            VIA   -    MD0100PA01X+112101Y+098104X0190Y         S0      
327m7665            J19   -68         A01X+112101Y+098104X0205Y0590R090 S1      
317m7666            VIA   -    MD0080PA01X+133296Y+099762X0160Y    R180 S0      
327m7666            U25   -AY60       A01X+133480Y+099866X0177Y    R180 S1      
317m7666            VIA   -    MD0100PA01X+110487Y+097770X0190Y         S0      
327m7666            J19   -211        A01X+110487Y+097770X0205Y0590R090 S1      
317m7667            VIA   -    MD0080PA01X+133481Y+099443X0160Y    R180 S0      
327m7667            U25   -AW60       A01X+133665Y+099547X0177Y    R180 S1      
317m7667            VIA   -    MD0100PA01X+112101Y+097435X0190Y         S0      
327m7667            J19   -66         A01X+112101Y+097435X0205Y0590R090 S1      
317m7668            VIA   -    MD0080PA01X+133851Y+098805X0160Y    R180 S0      
327m7668            U25   -AU59       A01X+134035Y+098910X0177Y    R180 S1      
317m7668            VIA   -    MD0100PA01X+110487Y+096431X0190Y         S0      
327m7668            J19   -207        A01X+110487Y+096431X0205Y0590R090 S1      
317m7669            VIA   -    MD0080PA01X+133481Y+100718X0160Y    R180 S0      
327m7669            J19   -217        A01X+110487Y+099778X0205Y0590R090 S1      
317m7669            VIA   -    MD0100PA01X+110487Y+099778X0190Y         S0      
327m7669            U25   -BC60       A01X+133665Y+100823X0177Y    R180 S1      
317m7670            VIA   -    MD0080PA01X+133296Y+101037X0160Y    R180 S0      
327m7670            J19   -218        A01X+110487Y+100112X0205Y0590R090 S1      
317m7670            VIA   -    MD0100PA01X+110487Y+100112X0190Y         S0      
327m7670            U25   -BD60       A01X+133480Y+101142X0177Y    R180 S1      
317m7671            VIA   -    MD0080PA01X+134036Y+098486X0160Y    R180 S0      
327m7671            U25   -AT58       A01X+134220Y+098591X0177Y    R180 S1      
317m7671            VIA   -    MD0100PA18X+112651Y+096096X0190Y         S0      
327m7671            R378  -2          A18X+112651Y+096096X0198Y0197R180 S2      
327m7672            J19   -62         A01X+112101Y+096096X0205Y0590R090 S1      
317m7672            VIA   -    MD0100PA00X+112101Y+096096X0190Y         S0      
327m7672            R378  -1          A18X+112336Y+096096X0198Y0197R180 S2      
317m7673            VIA   -    MD0080PA01X+037280Y+105357X0160Y         S0      
327m7673            U26   -BP56       A01X+037464Y+105252X0177Y    R180 S1      
317m7673            VIA   -    MD0100PA01X+017457Y+106471X0190Y         S0      
327m7673            J28   -87         A01X+017457Y+106471X0205Y0590R090 S1      
317m7674            VIA   -    MD0080PA01X+037095Y+104400X0160Y         S0      
327m7674            U26   -BL57       A01X+037279Y+104295X0177Y    R180 S1      
317m7674            VIA   -    MD0100PA01X+015842Y+105132X0190Y         S0      
327m7674            J28   -227        A01X+015842Y+105132X0205Y0590R090 S1      
317m7675            VIA   -    MD0080PA01X+037280Y+106632X0160Y         S0      
327m7675            U26   -BV56       A01X+037464Y+106528X0177Y    R180 S1      
317m7675            VIA   -    MD0100PA01X+017457Y+108478X0190Y         S0      
327m7675            J28   -93         A01X+017457Y+108478X0205Y0590R090 S1      
317m7676            VIA   -    MD0080PA01X+037650Y+114924X0160Y         S0      
327m7676            U26   -DD55       A01X+037834Y+114819X0177Y    R180 S1      
317m7676            VIA   -    MD0100PA01X+015842Y+123872X0190Y         S0      
327m7676            J28   -283        A01X+015842Y+123872X0205Y0590R090 S1      
317m7677            VIA   -    MD0080PA01X+037650Y+113010X0160Y         S0      
327m7677            U26   -CV55       A01X+037834Y+112906X0177Y    R180 S1      
317m7677            VIA   -    MD0100PA01X+015842Y+120191X0190Y         S0      
327m7677            J28   -272        A01X+015842Y+120191X0205Y0590R090 S1      
317m7678            VIA   -    MD0080PA01X+037650Y+111097X0160Y         S0      
327m7678            U26   -CM55       A01X+037834Y+110992X0177Y    R180 S1      
317m7678            VIA   -    MD0100PA01X+015842Y+116510X0190Y         S0      
327m7678            J28   -261        A01X+015842Y+116510X0205Y0590R090 S1      
317m7679            VIA   -    MD0080PA01X+037650Y+109184X0160Y         S0      
327m7679            U26   -CF55       A01X+037834Y+109079X0177Y    R180 S1      
317m7679            VIA   -    MD0100PA01X+015842Y+112829X0190Y         S0      
327m7679            J28   -250        A01X+015842Y+112829X0205Y0590R090 S1      
317m7680            VIA   -    MD0080PA01X+037650Y+107270X0160Y         S0      
327m7680            U26   -BY55       A01X+037834Y+107166X0177Y    R180 S1      
317m7680            VIA   -    MD0100PA01X+015842Y+109148X0190Y         S0      
327m7680            J28   -239        A01X+015842Y+109148X0205Y0590R090 S1      
317m7681            VIA   -    MD0080PA01X+037280Y+114286X0160Y         S0      
327m7681            U26   -DB56       A01X+037464Y+114181X0177Y    R180 S1      
317m7681            VIA   -    MD0100PA01X+017457Y+123203X0190Y         S0      
327m7681            J28   -137        A01X+017457Y+123203X0205Y0590R090 S1      
317m7682            VIA   -    MD0080PA01X+037280Y+112373X0160Y         S0      
327m7682            U26   -CT56       A01X+037464Y+112268X0177Y    R180 S1      
317m7682            VIA   -    MD0100PA01X+017457Y+119522X0190Y         S0      
327m7682            J28   -126        A01X+017457Y+119522X0205Y0590R090 S1      
317m7683            VIA   -    MD0080PA01X+037280Y+110459X0160Y         S0      
327m7683            U26   -CK56       A01X+037464Y+110354X0177Y    R180 S1      
317m7683            VIA   -    MD0100PA01X+017457Y+115841X0190Y         S0      
327m7683            J28   -115        A01X+017457Y+115841X0205Y0590R090 S1      
317m7684            VIA   -    MD0080PA01X+037280Y+108546X0160Y         S0      
327m7684            U26   -CD56       A01X+037464Y+108441X0177Y    R180 S1      
317m7684            VIA   -    MD0100PA01X+017457Y+112160X0190Y         S0      
327m7684            J28   -104        A01X+017457Y+112160X0205Y0590R090 S1      
317m7685            VIA   -    MD0080PA01X+037095Y+106951X0160Y         S0      
327m7685            U26   -BW57       A01X+037279Y+106847X0177Y    R180 S1      
317m7685            VIA   -    MD0100PA01X+017457Y+108813X0190Y         S0      
327m7685            J28   -94         A01X+017457Y+108813X0205Y0590R090 S1      
317m7686            VIA   -    MD0080PA01X+037835Y+114605X0160Y         S0      
327m7686            U26   -DC55       A01X+038019Y+114500X0177Y    R180 S1      
317m7686            VIA   -    MD0100PA01X+015842Y+123538X0190Y         S0      
327m7686            J28   -282        A01X+015842Y+123538X0205Y0590R090 S1      
317m7687            VIA   -    MD0080PA01X+037835Y+112692X0160Y         S0      
327m7687            U26   -CU55       A01X+038019Y+112587X0177Y    R180 S1      
317m7687            VIA   -    MD0100PA01X+015842Y+119856X0190Y         S0      
327m7687            J28   -271        A01X+015842Y+119856X0205Y0590R090 S1      
317m7688            VIA   -    MD0080PA01X+037835Y+110778X0160Y         S0      
327m7688            U26   -CL55       A01X+038019Y+110673X0177Y    R180 S1      
317m7688            VIA   -    MD0100PA01X+015842Y+116175X0190Y         S0      
327m7688            J28   -260        A01X+015842Y+116175X0205Y0590R090 S1      
317m7689            VIA   -    MD0080PA01X+037835Y+108865X0160Y         S0      
327m7689            U26   -CE55       A01X+038019Y+108760X0177Y    R180 S1      
317m7689            VIA   -    MD0100PA01X+015842Y+112494X0190Y         S0      
327m7689            J28   -249        A01X+015842Y+112494X0205Y0590R090 S1      
317m7690            VIA   -    MD0080PA01X+037835Y+106951X0160Y         S0      
327m7690            U26   -BW55       A01X+038019Y+106847X0177Y    R180 S1      
317m7690            VIA   -    MD0100PA01X+015842Y+108813X0190Y         S0      
327m7690            J28   -238        A01X+015842Y+108813X0205Y0590R090 S1      
317m7691            VIA   -    MD0080PA01X+037095Y+114605X0160Y         S0      
327m7691            U26   -DC57       A01X+037279Y+114500X0177Y    R180 S1      
317m7691            VIA   -    MD0100PA01X+017457Y+123538X0190Y         S0      
327m7691            J28   -138        A01X+017457Y+123538X0205Y0590R090 S1      
317m7692            VIA   -    MD0080PA01X+037095Y+112692X0160Y         S0      
327m7692            U26   -CU57       A01X+037279Y+112587X0177Y    R180 S1      
317m7692            VIA   -    MD0100PA01X+017457Y+119856X0190Y         S0      
327m7692            J28   -127        A01X+017457Y+119856X0205Y0590R090 S1      
317m7693            VIA   -    MD0080PA01X+037095Y+110778X0160Y         S0      
327m7693            U26   -CL57       A01X+037279Y+110673X0177Y    R180 S1      
317m7693            VIA   -    MD0100PA01X+017457Y+116175X0190Y         S0      
327m7693            J28   -116        A01X+017457Y+116175X0205Y0590R090 S1      
317m7694            VIA   -    MD0080PA01X+037095Y+108865X0160Y         S0      
327m7694            U26   -CE57       A01X+037279Y+108760X0177Y    R180 S1      
317m7694            VIA   -    MD0100PA01X+017457Y+112494X0190Y         S0      
327m7694            J28   -105        A01X+017457Y+112494X0205Y0590R090 S1      
317m7695            VIA   -    MD0080PA01X+037835Y+110140X0160Y         S0      
327m7695            U26   -CJ55       A01X+038019Y+110036X0177Y    R180 S1      
317m7695            VIA   -    MD0100PA01X+017457Y+115171X0190Y         S0      
327m7695            J28   -113        A01X+017457Y+115171X0205Y0590R090 S1      
317m7696            VIA   -    MD0080PA01X+037280Y+109821X0160Y         S0      
327m7696            U26   -CH56       A01X+037464Y+109717X0177Y    R180 S1      
317m7696            VIA   -    MD0100PA01X+017457Y+114502X0190Y         S0      
327m7696            J28   -111        A01X+017457Y+114502X0205Y0590R090 S1      
317m7697            VIA   -    MD0080PA01X+037650Y+109821X0160Y         S0      
327m7697            U26   -CH55       A01X+037834Y+109717X0177Y    R180 S1      
317m7697            VIA   -    MD0100PA01X+015842Y+114168X0190Y         S0      
327m7697            J28   -254        A01X+015842Y+114168X0205Y0590R090 S1      
317m7698            VIA   -    MD0080PA01X+037095Y+109502X0160Y         S0      
327m7698            U26   -CG57       A01X+037279Y+109398X0177Y    R180 S1      
317m7698            VIA   -    MD0100PA01X+015842Y+113498X0190Y         S0      
327m7698            J28   -252        A01X+015842Y+113498X0205Y0590R090 S1      
317m7699            VIA   -    MD0080PA01X+037835Y+109502X0160Y         S0      
327m7699            U26   -CG55       A01X+038019Y+109398X0177Y    R180 S1      
317m7699            VIA   -    MD0100PA01X+017457Y+113833X0190Y         S0      
327m7699            J28   -109        A01X+017457Y+113833X0205Y0590R090 S1      
317m7700            VIA   -    MD0080PA01X+037280Y+109184X0160Y         S0      
327m7700            U26   -CF56       A01X+037464Y+109079X0177Y    R180 S1      
317m7700            VIA   -    MD0100PA01X+017457Y+113164X0190Y         S0      
327m7700            J28   -107        A01X+017457Y+113164X0205Y0590R090 S1      
317m7701            VIA   -    MD0080PA01X+037650Y+108546X0160Y         S0      
327m7701            U26   -CD55       A01X+037834Y+108441X0177Y    R180 S1      
317m7701            VIA   -    MD0100PA01X+015842Y+111825X0190Y         S0      
327m7701            J28   -247        A01X+015842Y+111825X0205Y0590R090 S1      
317m7702            VIA   -    MD0080PA01X+037650Y+115562X0160Y         S0      
327m7702            U26   -DF55       A01X+037834Y+115457X0177Y    R180 S1      
317m7702            VIA   -    MD0100PA01X+015842Y+125211X0190Y         S0      
327m7702            J28   -287        A01X+015842Y+125211X0205Y0590R090 S1      
317m7703            VIA   -    MD0080PA01X+037095Y+115243X0160Y         S0      
327m7703            U26   -DE57       A01X+037279Y+115138X0177Y    R180 S1      
317m7703            VIA   -    MD0100PA01X+015842Y+124542X0190Y         S0      
327m7703            J28   -285        A01X+015842Y+124542X0205Y0590R090 S1      
317m7704            VIA   -    MD0080PA01X+037095Y+108227X0160Y         S0      
327m7704            U26   -CC57       A01X+037279Y+108122X0177Y    R180 S1      
317m7704            VIA   -    MD0100PA01X+015842Y+111156X0190Y         S0      
327m7704            J28   -245        A01X+015842Y+111156X0205Y0590R090 S1      
317m7705            VIA   -    MD0080PA01X+037835Y+115243X0160Y         S0      
327m7705            U26   -DE55       A01X+038019Y+115138X0177Y    R180 S1      
317m7705            VIA   -    MD0100PA01X+017457Y+124876X0190Y         S0      
327m7705            J28   -142        A01X+017457Y+124876X0205Y0590R090 S1      
317m7706            VIA   -    MD0080PA01X+037280Y+114924X0160Y         S0      
327m7706            U26   -DD56       A01X+037464Y+114819X0177Y    R180 S1      
317m7706            VIA   -    MD0100PA01X+017457Y+124207X0190Y         S0      
327m7706            J28   -140        A01X+017457Y+124207X0205Y0590R090 S1      
317m7707            VIA   -    MD0080PA01X+037650Y+114286X0160Y         S0      
327m7707            U26   -DB55       A01X+037834Y+114181X0177Y    R180 S1      
317m7707            VIA   -    MD0100PA01X+015842Y+122868X0190Y         S0      
327m7707            J28   -280        A01X+015842Y+122868X0205Y0590R090 S1      
317m7708            VIA   -    MD0080PA01X+037095Y+113967X0160Y         S0      
327m7708            U26   -DA57       A01X+037279Y+113862X0177Y    R180 S1      
317m7708            VIA   -    MD0100PA01X+015842Y+122199X0190Y         S0      
327m7708            J28   -278        A01X+015842Y+122199X0205Y0590R090 S1      
317m7709            VIA   -    MD0080PA01X+037835Y+113967X0160Y         S0      
327m7709            U26   -DA55       A01X+038019Y+113862X0177Y    R180 S1      
317m7709            VIA   -    MD0100PA01X+017457Y+122534X0190Y         S0      
327m7709            J28   -135        A01X+017457Y+122534X0205Y0590R090 S1      
317m7710            VIA   -    MD0080PA01X+037280Y+113648X0160Y         S0      
327m7710            U26   -CY56       A01X+037464Y+113543X0177Y    R180 S1      
317m7710            VIA   -    MD0100PA01X+017457Y+121864X0190Y         S0      
327m7710            J28   -133        A01X+017457Y+121864X0205Y0590R090 S1      
317m7711            VIA   -    MD0080PA01X+037650Y+113648X0160Y         S0      
327m7711            U26   -CY55       A01X+037834Y+113543X0177Y    R180 S1      
317m7711            VIA   -    MD0100PA01X+015842Y+121530X0190Y         S0      
327m7711            J28   -276        A01X+015842Y+121530X0205Y0590R090 S1      
317m7712            VIA   -    MD0080PA01X+037095Y+113329X0160Y         S0      
327m7712            U26   -CW57       A01X+037279Y+113225X0177Y    R180 S1      
317m7712            VIA   -    MD0100PA01X+015842Y+120860X0190Y         S0      
327m7712            J28   -274        A01X+015842Y+120860X0205Y0590R090 S1      
317m7713            VIA   -    MD0080PA01X+037835Y+113329X0160Y         S0      
327m7713            U26   -CW55       A01X+038019Y+113225X0177Y    R180 S1      
317m7713            VIA   -    MD0100PA01X+017457Y+121195X0190Y         S0      
327m7713            J28   -131        A01X+017457Y+121195X0205Y0590R090 S1      
317m7714            VIA   -    MD0080PA01X+037280Y+113010X0160Y         S0      
327m7714            U26   -CV56       A01X+037464Y+112906X0177Y    R180 S1      
327m7714            J28   -129        A01X+017457Y+120526X0205Y0590R090 S1      
317m7714            VIA   -    MD0100PA01X+017457Y+120526X0190Y         S0      
317m7715            VIA   -    MD0080PA01X+037835Y+108227X0160Y         S0      
327m7715            U26   -CC55       A01X+038019Y+108122X0177Y    R180 S1      
317m7715            VIA   -    MD0100PA01X+017457Y+111490X0190Y         S0      
327m7715            J28   -102        A01X+017457Y+111490X0205Y0590R090 S1      
317m7716            VIA   -    MD0080PA01X+037650Y+112373X0160Y         S0      
327m7716            U26   -CT55       A01X+037834Y+112268X0177Y    R180 S1      
317m7716            VIA   -    MD0100PA01X+015842Y+119187X0190Y         S0      
327m7716            J28   -269        A01X+015842Y+119187X0205Y0590R090 S1      
317m7717            VIA   -    MD0080PA01X+037095Y+112054X0160Y         S0      
327m7717            U26   -CR57       A01X+037279Y+111949X0177Y    R180 S1      
317m7717            VIA   -    MD0100PA01X+015842Y+118518X0190Y         S0      
327m7717            J28   -267        A01X+015842Y+118518X0205Y0590R090 S1      
317m7718            VIA   -    MD0080PA01X+037835Y+112054X0160Y         S0      
327m7718            U26   -CR55       A01X+038019Y+111949X0177Y    R180 S1      
317m7718            VIA   -    MD0100PA01X+017457Y+118852X0190Y         S0      
327m7718            J28   -124        A01X+017457Y+118852X0205Y0590R090 S1      
317m7719            VIA   -    MD0080PA01X+037280Y+111735X0160Y         S0      
327m7719            U26   -CP56       A01X+037464Y+111630X0177Y    R180 S1      
317m7719            VIA   -    MD0100PA01X+017457Y+118183X0190Y         S0      
327m7719            J28   -122        A01X+017457Y+118183X0205Y0590R090 S1      
317m7720            VIA   -    MD0080PA01X+037650Y+111735X0160Y         S0      
327m7720            U26   -CP55       A01X+037834Y+111630X0177Y    R180 S1      
317m7720            VIA   -    MD0100PA01X+015842Y+117849X0190Y         S0      
327m7720            J28   -265        A01X+015842Y+117849X0205Y0590R090 S1      
317m7721            VIA   -    MD0080PA01X+037095Y+111416X0160Y         S0      
327m7721            U26   -CN57       A01X+037279Y+111311X0177Y    R180 S1      
317m7721            VIA   -    MD0100PA01X+015842Y+117179X0190Y         S0      
327m7721            J28   -263        A01X+015842Y+117179X0205Y0590R090 S1      
317m7722            VIA   -    MD0080PA01X+037835Y+111416X0160Y         S0      
327m7722            U26   -CN55       A01X+038019Y+111311X0177Y    R180 S1      
317m7722            VIA   -    MD0100PA01X+017457Y+117514X0190Y         S0      
327m7722            J28   -120        A01X+017457Y+117514X0205Y0590R090 S1      
317m7723            VIA   -    MD0080PA01X+037280Y+111097X0160Y         S0      
327m7723            U26   -CM56       A01X+037464Y+110992X0177Y    R180 S1      
317m7723            VIA   -    MD0100PA01X+017457Y+116845X0190Y         S0      
327m7723            J28   -118        A01X+017457Y+116845X0205Y0590R090 S1      
317m7724            VIA   -    MD0080PA01X+037650Y+110459X0160Y         S0      
327m7724            U26   -CK55       A01X+037834Y+110354X0177Y    R180 S1      
317m7724            VIA   -    MD0100PA01X+015842Y+115506X0190Y         S0      
327m7724            J28   -258        A01X+015842Y+115506X0205Y0590R090 S1      
317m7725            VIA   -    MD0080PA01X+037095Y+110140X0160Y         S0      
327m7725            U26   -CJ57       A01X+037279Y+110036X0177Y    R180 S1      
317m7725            VIA   -    MD0100PA01X+015842Y+114837X0190Y         S0      
327m7725            J28   -256        A01X+015842Y+114837X0205Y0590R090 S1      
317m7726            VIA   -    MD0080PA01X+037280Y+107908X0160Y         S0      
327m7726            U26   -CB56       A01X+037464Y+107803X0177Y    R180 S1      
317m7726            VIA   -    MD0100PA01X+017457Y+110821X0190Y         S0      
327m7726            J28   -100        A01X+017457Y+110821X0205Y0590R090 S1      
317m7727            VIA   -    MD0080PA01X+037095Y+105038X0160Y         S0      
327m7727            U26   -BN57       A01X+037279Y+104933X0177Y    R180 S1      
317m7727            VIA   -    MD0100PA01X+015842Y+105801X0190Y         S0      
327m7727            J28   -229        A01X+015842Y+105801X0205Y0590R090 S1      
317m7728            VIA   -    MD0080PA01X+037650Y+104719X0160Y         S0      
327m7728            U26   -BM55       A01X+037834Y+104614X0177Y    R180 S1      
317m7728            VIA   -    MD0100PA01X+017457Y+105467X0190Y         S0      
327m7728            J28   -84         A01X+017457Y+105467X0205Y0590R090 S1      
317m7729            VIA   -    MD0080PA01X+037650Y+106632X0160Y         S0      
327m7729            U26   -BV55       A01X+037834Y+106528X0177Y    R180 S1      
317m7729            VIA   -    MD0100PA01X+015842Y+108144X0190Y         S0      
327m7729            J28   -236        A01X+015842Y+108144X0205Y0590R090 S1      
317m7730            VIA   -    MD0080PA01X+037095Y+106314X0160Y         S0      
327m7730            U26   -BU57       A01X+037279Y+106209X0177Y    R180 S1      
317m7730            VIA   -    MD0100PA01X+015842Y+107474X0190Y         S0      
327m7730            J28   -234        A01X+015842Y+107474X0205Y0590R090 S1      
317m7731            VIA   -    MD0080PA01X+037835Y+106314X0160Y         S0      
327m7731            U26   -BU55       A01X+038019Y+106209X0177Y    R180 S1      
317m7731            VIA   -    MD0100PA01X+017457Y+107809X0190Y         S0      
327m7731            J28   -91         A01X+017457Y+107809X0205Y0590R090 S1      
317m7732            VIA   -    MD0080PA01X+037280Y+105995X0160Y         S0      
327m7732            U26   -BT56       A01X+037464Y+105890X0177Y    R180 S1      
317m7732            VIA   -    MD0100PA01X+017457Y+107140X0190Y         S0      
327m7732            J28   -89         A01X+017457Y+107140X0205Y0590R090 S1      
317m7733            VIA   -    MD0080PA01X+037650Y+107908X0160Y         S0      
327m7733            U26   -CB55       A01X+037834Y+107803X0177Y    R180 S1      
317m7733            VIA   -    MD0100PA01X+015842Y+110486X0190Y         S0      
327m7733            J28   -243        A01X+015842Y+110486X0205Y0590R090 S1      
317m7734            VIA   -    MD0080PA01X+037095Y+107589X0160Y         S0      
327m7734            U26   -CA57       A01X+037279Y+107484X0177Y    R180 S1      
317m7734            VIA   -    MD0100PA01X+015842Y+109817X0190Y         S0      
327m7734            J28   -241        A01X+015842Y+109817X0205Y0590R090 S1      
317m7735            VIA   -    MD0080PA01X+037835Y+107589X0160Y         S0      
327m7735            U26   -CA55       A01X+038019Y+107484X0177Y    R180 S1      
317m7735            VIA   -    MD0100PA01X+017457Y+110152X0190Y         S0      
327m7735            J28   -98         A01X+017457Y+110152X0205Y0590R090 S1      
317m7736            VIA   -    MD0080PA01X+037280Y+107270X0160Y         S0      
327m7736            U26   -BY56       A01X+037464Y+107166X0177Y    R180 S1      
317m7736            VIA   -    MD0100PA01X+017457Y+109482X0190Y         S0      
327m7736            J28   -96         A01X+017457Y+109482X0205Y0590R090 S1      
317m7737            VIA   -    MD0080PA01X+037280Y+104081X0160Y         S0      
327m7737            U26   -BK56       A01X+037464Y+103976X0177Y    R180 S1      
317m7737            VIA   -    MD0100PA01X+017457Y+104797X0190Y         S0      
327m7737            J28   -82         A01X+017457Y+104797X0205Y0590R090 S1      
317m7738            VIA   -    MD0080PA01X+037650Y+104081X0160Y         S0      
327m7738            U26   -BK55       A01X+037834Y+103976X0177Y    R180 S1      
317m7738            VIA   -    MD0100PA01X+015842Y+104463X0190Y         S0      
327m7738            J28   -225        A01X+015842Y+104463X0205Y0590R090 S1      
317m7739            VIA   -    MD0080PA01X+037835Y+103762X0160Y         S0      
327m7739            U26   -BJ55       A01X+038019Y+103658X0177Y    R180 S1      
317m7739            VIA   -    MD0100PA01X+017457Y+104128X0190Y         S0      
327m7739            J28   -80         A01X+017457Y+104128X0205Y0590R090 S1      
317m7740            VIA   -    MD0080PA01X+037095Y+103762X0160Y         S0      
327m7740            U26   -BJ57       A01X+037279Y+103658X0177Y    R180 S1      
317m7740            VIA   -    MD0100PA01X+015842Y+103793X0190Y         S0      
327m7740            J28   -223        A01X+015842Y+103793X0205Y0590R090 S1      
317m7741            VIA   -    MD0080PA01X+037280Y+103443X0160Y         S0      
327m7741            U26   -BH56       A01X+037464Y+103339X0177Y    R180 S1      
317m7741            VIA   -    MD0100PA01X+017457Y+103459X0190Y         S0      
327m7741            J28   -78         A01X+017457Y+103459X0205Y0590R090 S1      
317m7742            VIA   -    MD0080PA01X+037650Y+103443X0160Y         S0      
327m7742            U26   -BH55       A01X+037834Y+103339X0177Y    R180 S1      
317m7742            VIA   -    MD0100PA01X+015842Y+103124X0190Y         S0      
327m7742            J28   -221        A01X+015842Y+103124X0205Y0590R090 S1      
317m7743            VIA   -    MD0080PA01X+037835Y+103124X0160Y         S0      
327m7743            U26   -BG55       A01X+038019Y+103020X0177Y    R180 S1      
317m7743            VIA   -    MD0100PA01X+017457Y+102790X0190Y         S0      
327m7743            J28   -76         A01X+017457Y+102790X0205Y0590R090 S1      
317m7744            VIA   -    MD0080PA01X+037835Y+105038X0160Y         S0      
327m7744            U26   -BN55       A01X+038019Y+104933X0177Y    R180 S1      
317m7744            VIA   -    MD0100PA01X+017457Y+106136X0190Y         S0      
327m7744            J28   -86         A01X+017457Y+106136X0205Y0590R090 S1      
317m7745            VIA   -    MD0080PA01X+037717Y+100718X0160Y    R180 S0      
327m7745            U26   -BC55       A01X+037901Y+100823X0177Y    R180 S1      
317m7745            VIA   -    MD0100PA01X+017457Y+100112X0190Y         S0      
327m7745            J28   -74         A01X+017457Y+100112X0205Y0590R090 S1      
317m7746            VIA   -    MD0080PA01X+037717Y+097529X0160Y    R180 S0      
327m7746            U26   -AN55       A01X+037901Y+097634X0177Y    R180 S1      
317m7746            VIA   -    MD0100PA01X+015842Y+094423X0190Y         S0      
327m7746            J28   -201        A01X+015842Y+094423X0205Y0590R090 S1      
317m7747            VIA   -    MD0080PA01X+037717Y+095616X0160Y    R180 S0      
327m7747            U26   -AG55       A01X+037901Y+095721X0177Y    R180 S1      
317m7747            VIA   -    MD0100PA01X+015842Y+090742X0190Y         S0      
327m7747            J28   -190        A01X+015842Y+090742X0205Y0590R090 S1      
317m7748            VIA   -    MD0080PA01X+037717Y+093702X0160Y    R180 S0      
327m7748            U26   -AA55       A01X+037901Y+093807X0177Y    R180 S1      
317m7748            VIA   -    MD0100PA01X+015842Y+087061X0190Y         S0      
327m7748            J28   -179        A01X+015842Y+087061X0205Y0590R090 S1      
317m7749            VIA   -    MD0080PA01X+037717Y+091789X0160Y    R180 S0      
327m7749            U26   -R55        A01X+037901Y+091894X0177Y    R180 S1      
317m7749            VIA   -    MD0100PA01X+015842Y+083380X0190Y         S0      
327m7749            J28   -168        A01X+015842Y+083380X0205Y0590R090 S1      
317m7750            VIA   -    MD0080PA01X+037717Y+089876X0160Y    R180 S0      
327m7750            U26   -J55        A01X+037901Y+089980X0177Y    R180 S1      
317m7750            VIA   -    MD0100PA01X+015842Y+079699X0190Y         S0      
327m7750            J28   -157        A01X+015842Y+079699X0205Y0590R090 S1      
317m7751            VIA   -    MD0080PA01X+036977Y+096892X0160Y    R180 S0      
327m7751            U26   -AL57       A01X+037161Y+096996X0177Y    R180 S1      
317m7751            VIA   -    MD0100PA01X+017457Y+093754X0190Y         S0      
327m7751            J28   -55         A01X+017457Y+093754X0205Y0590R090 S1      
317m7752            VIA   -    MD0080PA01X+036977Y+094978X0160Y    R180 S0      
327m7752            U26   -AE57       A01X+037161Y+095083X0177Y    R180 S1      
317m7752            VIA   -    MD0100PA01X+017457Y+090073X0190Y         S0      
327m7752            J28   -44         A01X+017457Y+090073X0205Y0590R090 S1      
317m7753            VIA   -    MD0080PA01X+036977Y+093065X0160Y    R180 S0      
327m7753            U26   -W57        A01X+037161Y+093169X0177Y    R180 S1      
317m7753            VIA   -    MD0100PA01X+017457Y+086392X0190Y         S0      
327m7753            J28   -33         A01X+017457Y+086392X0205Y0590R090 S1      
317m7754            VIA   -    MD0080PA01X+036977Y+091151X0160Y    R180 S0      
327m7754            U26   -N57        A01X+037161Y+091256X0177Y    R180 S1      
317m7754            VIA   -    MD0100PA01X+017457Y+082711X0190Y         S0      
327m7754            J28   -22         A01X+017457Y+082711X0205Y0590R090 S1      
317m7755            VIA   -    MD0080PA01X+036977Y+089238X0160Y    R180 S0      
327m7755            U26   -G57        A01X+037161Y+089343X0177Y    R180 S1      
317m7755            VIA   -    MD0100PA01X+017457Y+079030X0190Y         S0      
327m7755            J28   -11         A01X+017457Y+079030X0205Y0590R090 S1      
317m7756            VIA   -    MD0080PA01X+037532Y+097210X0160Y    R180 S0      
327m7756            U26   -AM55       A01X+037716Y+097315X0177Y    R180 S1      
317m7756            VIA   -    MD0100PA01X+015842Y+094089X0190Y         S0      
327m7756            J28   -200        A01X+015842Y+094089X0205Y0590R090 S1      
317m7757            VIA   -    MD0080PA01X+037532Y+095297X0160Y    R180 S0      
327m7757            U26   -AF55       A01X+037716Y+095402X0177Y    R180 S1      
317m7757            VIA   -    MD0100PA01X+015842Y+090408X0190Y         S0      
327m7757            J28   -189        A01X+015842Y+090408X0205Y0590R090 S1      
317m7758            VIA   -    MD0080PA01X+037532Y+093384X0160Y    R180 S0      
327m7758            U26   -Y55        A01X+037716Y+093488X0177Y    R180 S1      
317m7758            VIA   -    MD0100PA01X+015842Y+086726X0190Y         S0      
327m7758            J28   -178        A01X+015842Y+086726X0205Y0590R090 S1      
317m7759            VIA   -    MD0080PA01X+037532Y+091470X0160Y    R180 S0      
327m7759            U26   -P55        A01X+037716Y+091575X0177Y    R180 S1      
317m7759            VIA   -    MD0100PA01X+015842Y+083045X0190Y         S0      
327m7759            J28   -167        A01X+015842Y+083045X0205Y0590R090 S1      
317m7760            VIA   -    MD0080PA01X+037532Y+089557X0160Y    R180 S0      
327m7760            U26   -H55        A01X+037716Y+089662X0177Y    R180 S1      
317m7760            VIA   -    MD0100PA01X+015842Y+079364X0190Y         S0      
327m7760            J28   -156        A01X+015842Y+079364X0205Y0590R090 S1      
317m7761            VIA   -    MD0080PA01X+037162Y+097210X0160Y    R180 S0      
327m7761            U26   -AM56       A01X+037346Y+097315X0177Y    R180 S1      
317m7761            VIA   -    MD0100PA01X+017457Y+094089X0190Y         S0      
327m7761            J28   -56         A01X+017457Y+094089X0205Y0590R090 S1      
317m7762            VIA   -    MD0080PA01X+037162Y+095297X0160Y    R180 S0      
327m7762            U26   -AF56       A01X+037346Y+095402X0177Y    R180 S1      
317m7762            VIA   -    MD0100PA01X+017457Y+090408X0190Y         S0      
327m7762            J28   -45         A01X+017457Y+090408X0205Y0590R090 S1      
317m7763            VIA   -    MD0080PA01X+037162Y+093384X0160Y    R180 S0      
327m7763            U26   -Y56        A01X+037346Y+093488X0177Y    R180 S1      
317m7763            VIA   -    MD0100PA01X+017457Y+086726X0190Y         S0      
327m7763            J28   -34         A01X+017457Y+086726X0205Y0590R090 S1      
317m7764            VIA   -    MD0080PA01X+037162Y+091470X0160Y    R180 S0      
327m7764            U26   -P56        A01X+037346Y+091575X0177Y    R180 S1      
317m7764            VIA   -    MD0100PA01X+017457Y+083045X0190Y         S0      
327m7764            J28   -23         A01X+017457Y+083045X0205Y0590R090 S1      
317m7765            VIA   -    MD0080PA01X+037162Y+089557X0160Y    R180 S0      
327m7765            U26   -H56        A01X+037346Y+089662X0177Y    R180 S1      
317m7765            VIA   -    MD0100PA01X+017457Y+079364X0190Y         S0      
327m7765            J28   -12         A01X+017457Y+079364X0205Y0590R090 S1      
317m7766            VIA   -    MD0080PA01X+037532Y+090832X0160Y    R180 S0      
327m7766            U26   -M55        A01X+037716Y+090937X0177Y    R180 S1      
317m7766            VIA   -    MD0100PA01X+017457Y+082042X0190Y         S0      
327m7766            J28   -20         A01X+017457Y+082042X0205Y0590R090 S1      
317m7767            VIA   -    MD0080PA01X+036977Y+090514X0160Y    R180 S0      
327m7767            U26   -L57        A01X+037161Y+090618X0177Y    R180 S1      
317m7767            VIA   -    MD0100PA01X+017457Y+081372X0190Y         S0      
327m7767            J28   -18         A01X+017457Y+081372X0205Y0590R090 S1      
317m7768            VIA   -    MD0080PA01X+037717Y+090514X0160Y    R180 S0      
327m7768            U26   -L55        A01X+037901Y+090618X0177Y    R180 S1      
317m7768            VIA   -    MD0100PA01X+015842Y+081038X0190Y         S0      
327m7768            J28   -161        A01X+015842Y+081038X0205Y0590R090 S1      
317m7769            VIA   -    MD0080PA01X+037162Y+090195X0160Y    R180 S0      
327m7769            U26   -K56        A01X+037346Y+090299X0177Y    R180 S1      
317m7769            VIA   -    MD0100PA01X+015842Y+080368X0190Y         S0      
327m7769            J28   -159        A01X+015842Y+080368X0205Y0590R090 S1      
317m7770            VIA   -    MD0080PA01X+037532Y+090195X0160Y    R180 S0      
327m7770            U26   -K55        A01X+037716Y+090299X0177Y    R180 S1      
317m7770            VIA   -    MD0100PA01X+017457Y+080703X0190Y         S0      
327m7770            J28   -16         A01X+017457Y+080703X0205Y0590R090 S1      
317m7771            VIA   -    MD0080PA01X+036977Y+089876X0160Y    R180 S0      
327m7771            U26   -J57        A01X+037161Y+089980X0177Y    R180 S1      
317m7771            VIA   -    MD0100PA01X+017457Y+080034X0190Y         S0      
327m7771            J28   -14         A01X+017457Y+080034X0205Y0590R090 S1      
317m7772            VIA   -    MD0080PA01X+037717Y+089238X0160Y    R180 S0      
327m7772            U26   -G55        A01X+037901Y+089343X0177Y    R180 S1      
317m7772            VIA   -    MD0100PA01X+015842Y+078695X0190Y         S0      
327m7772            J28   -154        A01X+015842Y+078695X0205Y0590R090 S1      
317m7773            VIA   -    MD0080PA01X+037717Y+096254X0160Y    R180 S0      
327m7773            U26   -AJ55       A01X+037901Y+096358X0177Y    R180 S1      
317m7773            VIA   -    MD0100PA01X+015842Y+092081X0190Y         S0      
327m7773            J28   -194        A01X+015842Y+092081X0205Y0590R090 S1      
317m7774            VIA   -    MD0080PA01X+037162Y+095935X0160Y    R180 S0      
327m7774            U26   -AH56       A01X+037346Y+096040X0177Y    R180 S1      
317m7774            VIA   -    MD0100PA01X+015842Y+091412X0190Y         S0      
327m7774            J28   -192        A01X+015842Y+091412X0205Y0590R090 S1      
317m7775            VIA   -    MD0080PA01X+037162Y+088919X0160Y    R180 S0      
327m7775            U26   -F56        A01X+037346Y+089024X0177Y    R180 S1      
317m7775            VIA   -    MD0100PA01X+015842Y+078026X0190Y         S0      
327m7775            J28   -152        A01X+015842Y+078026X0205Y0590R090 S1      
317m7776            VIA   -    MD0080PA01X+037532Y+095935X0160Y    R180 S0      
327m7776            U26   -AH55       A01X+037716Y+096040X0177Y    R180 S1      
317m7776            VIA   -    MD0100PA01X+017457Y+091746X0190Y         S0      
327m7776            J28   -49         A01X+017457Y+091746X0205Y0590R090 S1      
317m7777            VIA   -    MD0080PA01X+036977Y+095616X0160Y    R180 S0      
327m7777            U26   -AG57       A01X+037161Y+095721X0177Y    R180 S1      
317m7777            VIA   -    MD0100PA01X+017457Y+091077X0190Y         S0      
327m7777            J28   -47         A01X+017457Y+091077X0205Y0590R090 S1      
317m7778            VIA   -    MD0080PA01X+037717Y+094978X0160Y    R180 S0      
327m7778            U26   -AE55       A01X+037901Y+095083X0177Y    R180 S1      
317m7778            VIA   -    MD0100PA01X+015842Y+089738X0190Y         S0      
327m7778            J28   -187        A01X+015842Y+089738X0205Y0590R090 S1      
317m7779            VIA   -    MD0080PA01X+037162Y+094659X0160Y    R180 S0      
327m7779            U26   -AD56       A01X+037346Y+094764X0177Y    R180 S1      
317m7779            VIA   -    MD0100PA01X+015842Y+089069X0190Y         S0      
327m7779            J28   -185        A01X+015842Y+089069X0205Y0590R090 S1      
317m7780            VIA   -    MD0080PA01X+037532Y+094659X0160Y    R180 S0      
327m7780            U26   -AD55       A01X+037716Y+094764X0177Y    R180 S1      
317m7780            VIA   -    MD0100PA01X+017457Y+089404X0190Y         S0      
327m7780            J28   -42         A01X+017457Y+089404X0205Y0590R090 S1      
317m7781            VIA   -    MD0080PA01X+036977Y+094340X0160Y    R180 S0      
327m7781            U26   -AC57       A01X+037161Y+094445X0177Y    R180 S1      
317m7781            VIA   -    MD0100PA01X+017457Y+088734X0190Y         S0      
327m7781            J28   -40         A01X+017457Y+088734X0205Y0590R090 S1      
317m7782            VIA   -    MD0080PA01X+037717Y+094340X0160Y    R180 S0      
327m7782            U26   -AC55       A01X+037901Y+094445X0177Y    R180 S1      
317m7782            VIA   -    MD0100PA01X+015842Y+088400X0190Y         S0      
327m7782            J28   -183        A01X+015842Y+088400X0205Y0590R090 S1      
317m7783            VIA   -    MD0080PA01X+037162Y+094021X0160Y    R180 S0      
327m7783            U26   -AB56       A01X+037346Y+094126X0177Y    R180 S1      
317m7783            VIA   -    MD0100PA01X+015842Y+087730X0190Y         S0      
327m7783            J28   -181        A01X+015842Y+087730X0205Y0590R090 S1      
317m7784            VIA   -    MD0080PA01X+037532Y+094021X0160Y    R180 S0      
327m7784            U26   -AB55       A01X+037716Y+094126X0177Y    R180 S1      
317m7784            VIA   -    MD0100PA01X+017457Y+088065X0190Y         S0      
327m7784            J28   -38         A01X+017457Y+088065X0205Y0590R090 S1      
317m7785            VIA   -    MD0080PA01X+036977Y+093702X0160Y    R180 S0      
327m7785            U26   -AA57       A01X+037161Y+093807X0177Y    R180 S1      
317m7785            VIA   -    MD0100PA01X+017457Y+087396X0190Y         S0      
327m7785            J28   -36         A01X+017457Y+087396X0205Y0590R090 S1      
317m7786            VIA   -    MD0080PA01X+037532Y+088919X0160Y    R180 S0      
327m7786            U26   -F55        A01X+037716Y+089024X0177Y    R180 S1      
317m7786            VIA   -    MD0100PA01X+017457Y+078360X0190Y         S0      
327m7786            J28   -9          A01X+017457Y+078360X0205Y0590R090 S1      
317m7787            VIA   -    MD0080PA01X+037717Y+093065X0160Y    R180 S0      
327m7787            U26   -W55        A01X+037901Y+093169X0177Y    R180 S1      
317m7787            VIA   -    MD0100PA01X+015842Y+086057X0190Y         S0      
327m7787            J28   -176        A01X+015842Y+086057X0205Y0590R090 S1      
317m7788            VIA   -    MD0080PA01X+037162Y+092746X0160Y    R180 S0      
327m7788            U26   -V56        A01X+037346Y+092850X0177Y    R180 S1      
317m7788            VIA   -    MD0100PA01X+015842Y+085388X0190Y         S0      
327m7788            J28   -174        A01X+015842Y+085388X0205Y0590R090 S1      
317m7789            VIA   -    MD0080PA01X+037532Y+092746X0160Y    R180 S0      
327m7789            U26   -V55        A01X+037716Y+092850X0177Y    R180 S1      
317m7789            VIA   -    MD0100PA01X+017457Y+085723X0190Y         S0      
327m7789            J28   -31         A01X+017457Y+085723X0205Y0590R090 S1      
317m7790            VIA   -    MD0080PA01X+036977Y+092427X0160Y    R180 S0      
327m7790            U26   -U57        A01X+037161Y+092532X0177Y    R180 S1      
317m7790            VIA   -    MD0100PA01X+017457Y+085053X0190Y         S0      
327m7790            J28   -29         A01X+017457Y+085053X0205Y0590R090 S1      
317m7791            VIA   -    MD0080PA01X+037717Y+092427X0160Y    R180 S0      
327m7791            U26   -U55        A01X+037901Y+092532X0177Y    R180 S1      
317m7791            VIA   -    MD0100PA01X+015842Y+084719X0190Y         S0      
327m7791            J28   -172        A01X+015842Y+084719X0205Y0590R090 S1      
317m7792            VIA   -    MD0080PA01X+037162Y+092108X0160Y    R180 S0      
327m7792            U26   -T56        A01X+037346Y+092213X0177Y    R180 S1      
317m7792            VIA   -    MD0100PA01X+015842Y+084049X0190Y         S0      
327m7792            J28   -170        A01X+015842Y+084049X0205Y0590R090 S1      
317m7793            VIA   -    MD0080PA01X+037532Y+092108X0160Y    R180 S0      
327m7793            U26   -T55        A01X+037716Y+092213X0177Y    R180 S1      
317m7793            VIA   -    MD0100PA01X+017457Y+084384X0190Y         S0      
327m7793            J28   -27         A01X+017457Y+084384X0205Y0590R090 S1      
317m7794            VIA   -    MD0080PA01X+036977Y+091789X0160Y    R180 S0      
327m7794            U26   -R57        A01X+037161Y+091894X0177Y    R180 S1      
317m7794            VIA   -    MD0100PA01X+017457Y+083715X0190Y         S0      
327m7794            J28   -25         A01X+017457Y+083715X0205Y0590R090 S1      
317m7795            VIA   -    MD0080PA01X+037717Y+091151X0160Y    R180 S0      
327m7795            U26   -N55        A01X+037901Y+091256X0177Y    R180 S1      
317m7795            VIA   -    MD0100PA01X+015842Y+082376X0190Y         S0      
327m7795            J28   -165        A01X+015842Y+082376X0205Y0590R090 S1      
317m7796            VIA   -    MD0080PA01X+037162Y+090832X0160Y    R180 S0      
327m7796            U26   -M56        A01X+037346Y+090937X0177Y    R180 S1      
317m7796            VIA   -    MD0100PA01X+015842Y+081707X0190Y         S0      
327m7796            J28   -163        A01X+015842Y+081707X0205Y0590R090 S1      
317m7797            VIA   -    MD0080PA01X+036977Y+088600X0160Y    R180 S0      
327m7797            U26   -E57        A01X+037161Y+088705X0177Y    R180 S1      
317m7797            VIA   -    MD0100PA01X+017457Y+077691X0190Y         S0      
327m7797            J28   -7          A01X+017457Y+077691X0205Y0590R090 S1      
317m7798            VIA   -    MD0080PA01X+037717Y+099443X0160Y    R180 S0      
327m7798            U26   -AW55       A01X+037901Y+099547X0177Y    R180 S1      
317m7798            VIA   -    MD0100PA01X+015842Y+097100X0190Y         S0      
327m7798            J28   -209        A01X+015842Y+097100X0205Y0590R090 S1      
317m7799            VIA   -    MD0080PA01X+037162Y+099124X0160Y    R180 S0      
327m7799            U26   -AV56       A01X+037346Y+099228X0177Y    R180 S1      
317m7799            VIA   -    MD0100PA01X+017457Y+096766X0190Y         S0      
327m7799            J28   -64         A01X+017457Y+096766X0205Y0590R090 S1      
317m7800            VIA   -    MD0080PA01X+037717Y+098167X0160Y    R180 S0      
327m7800            U26   -AR55       A01X+037901Y+098272X0177Y    R180 S1      
317m7800            VIA   -    MD0100PA01X+015842Y+095762X0190Y         S0      
327m7800            J28   -205        A01X+015842Y+095762X0205Y0590R090 S1      
317m7801            VIA   -    MD0080PA01X+037162Y+097848X0160Y    R180 S0      
327m7801            U26   -AP56       A01X+037346Y+097953X0177Y    R180 S1      
317m7801            VIA   -    MD0100PA01X+015842Y+095093X0190Y         S0      
327m7801            J28   -203        A01X+015842Y+095093X0205Y0590R090 S1      
317m7802            VIA   -    MD0080PA01X+037532Y+097848X0160Y    R180 S0      
327m7802            U26   -AP55       A01X+037716Y+097953X0177Y    R180 S1      
317m7802            VIA   -    MD0100PA01X+017457Y+095427X0190Y         S0      
327m7802            J28   -60         A01X+017457Y+095427X0205Y0590R090 S1      
317m7803            VIA   -    MD0080PA01X+036977Y+097529X0160Y    R180 S0      
327m7803            U26   -AN57       A01X+037161Y+097634X0177Y    R180 S1      
317m7803            VIA   -    MD0100PA01X+017457Y+094758X0190Y         S0      
327m7803            J28   -58         A01X+017457Y+094758X0205Y0590R090 S1      
317m7804            VIA   -    MD0080PA01X+037717Y+096892X0160Y    R180 S0      
327m7804            U26   -AL55       A01X+037901Y+096996X0177Y    R180 S1      
317m7804            VIA   -    MD0100PA01X+015842Y+093419X0190Y         S0      
327m7804            J28   -198        A01X+015842Y+093419X0205Y0590R090 S1      
317m7805            VIA   -    MD0080PA01X+037162Y+096573X0160Y    R180 S0      
327m7805            U26   -AK56       A01X+037346Y+096677X0177Y    R180 S1      
317m7805            VIA   -    MD0100PA01X+015842Y+092750X0190Y         S0      
327m7805            J28   -196        A01X+015842Y+092750X0205Y0590R090 S1      
317m7806            VIA   -    MD0080PA01X+037532Y+096573X0160Y    R180 S0      
327m7806            U26   -AK55       A01X+037716Y+096677X0177Y    R180 S1      
317m7806            VIA   -    MD0100PA01X+017457Y+093085X0190Y         S0      
327m7806            J28   -53         A01X+017457Y+093085X0205Y0590R090 S1      
317m7807            VIA   -    MD0080PA01X+036977Y+096254X0160Y    R180 S0      
327m7807            U26   -AJ57       A01X+037161Y+096358X0177Y    R180 S1      
317m7807            VIA   -    MD0100PA01X+017457Y+092416X0190Y         S0      
327m7807            J28   -51         A01X+017457Y+092416X0205Y0590R090 S1      
317m7808            VIA   -    MD0080PA01X+037532Y+100399X0160Y    R180 S0      
327m7808            U26   -BB55       A01X+037716Y+100504X0177Y    R180 S1      
317m7808            VIA   -    MD0100PA01X+017457Y+099443X0190Y         S0      
327m7808            J28   -72         A01X+017457Y+099443X0205Y0590R090 S1      
317m7809            VIA   -    MD0080PA01X+037162Y+100399X0160Y    R180 S0      
327m7809            U26   -BB56       A01X+037346Y+100504X0177Y    R180 S1      
317m7809            VIA   -    MD0100PA01X+015842Y+099108X0190Y         S0      
327m7809            J28   -215        A01X+015842Y+099108X0205Y0590R090 S1      
317m7810            VIA   -    MD0080PA01X+036977Y+100080X0160Y    R180 S0      
327m7810            U26   -BA57       A01X+037161Y+100185X0177Y    R180 S1      
317m7810            VIA   -    MD0100PA01X+017457Y+098774X0190Y         S0      
327m7810            J28   -70         A01X+017457Y+098774X0205Y0590R090 S1      
317m7811            VIA   -    MD0080PA01X+037717Y+100080X0160Y    R180 S0      
327m7811            U26   -BA55       A01X+037901Y+100185X0177Y    R180 S1      
317m7811            VIA   -    MD0100PA01X+015842Y+098439X0190Y         S0      
327m7811            J28   -213        A01X+015842Y+098439X0205Y0590R090 S1      
317m7812            VIA   -    MD0080PA01X+037532Y+099762X0160Y    R180 S0      
327m7812            U26   -AY55       A01X+037716Y+099866X0177Y    R180 S1      
317m7812            VIA   -    MD0100PA01X+017457Y+098104X0190Y         S0      
327m7812            J28   -68         A01X+017457Y+098104X0205Y0590R090 S1      
317m7813            VIA   -    MD0080PA01X+037162Y+099762X0160Y    R180 S0      
327m7813            U26   -AY56       A01X+037346Y+099866X0177Y    R180 S1      
317m7813            VIA   -    MD0100PA01X+015842Y+097770X0190Y         S0      
327m7813            J28   -211        A01X+015842Y+097770X0205Y0590R090 S1      
317m7814            VIA   -    MD0080PA01X+036977Y+099443X0160Y    R180 S0      
327m7814            U26   -AW57       A01X+037161Y+099547X0177Y    R180 S1      
317m7814            VIA   -    MD0100PA01X+017457Y+097435X0190Y         S0      
327m7814            J28   -66         A01X+017457Y+097435X0205Y0590R090 S1      
317m7815            VIA   -    MD0080PA01X+037717Y+098805X0160Y    R180 S0      
327m7815            U26   -AU55       A01X+037901Y+098910X0177Y    R180 S1      
327m7815            J28   -207        A01X+015842Y+096431X0205Y0590R090 S1      
317m7815            VIA   -    MD0100PA01X+015842Y+096431X0190Y         S0      
317m7816            VIA   -    MD0080PA01X+036977Y+100718X0160Y    R180 S0      
327m7816            U26   -BC57       A01X+037161Y+100823X0177Y    R180 S1      
317m7816            VIA   -    MD0100PA01X+015842Y+099778X0190Y         S0      
327m7816            J28   -217        A01X+015842Y+099778X0205Y0590R090 S1      
317m7817            VIA   -    MD0080PA01X+037162Y+101037X0160Y    R180 S0      
327m7817            U26   -BD56       A01X+037346Y+101142X0177Y    R180 S1      
317m7817            VIA   -    MD0100PA01X+015842Y+100112X0190Y         S0      
327m7817            J28   -218        A01X+015842Y+100112X0205Y0590R090 S1      
317m7818            VIA   -    MD0080PA01X+037532Y+098486X0160Y    R180 S0      
327m7818            U26   -AT55       A01X+037716Y+098591X0177Y    R180 S1      
317m7818            VIA   -    MD0100PA18X+018007Y+096097X0190Y    R180 S0      
327m7818            R502  -2          A18X+018007Y+096097X0198Y0197R180 S2      
327m7819            J28   -62         A01X+017457Y+096097X0205Y0590R090 S1      
317m7819            VIA   -    MD0100PA00X+017457Y+096097X0190Y         S0      
327m7819            R502  -1          A18X+017692Y+096097X0198Y0197R180 S2      
317m7820            VIA   -    MD0080PA01X+134894Y+105357X0160Y         S0      
327m7820            U25   -BP56       A01X+135078Y+105252X0177Y    R180 S1      
317m7820            VIA   -    MD0100PA01X+115071Y+106470X0190Y         S0      
327m7820            J17   -87         A01X+115071Y+106470X0205Y0590R090 S1      
317m7821            VIA   -    MD0080PA01X+134709Y+104400X0160Y         S0      
327m7821            U25   -BL57       A01X+134893Y+104295X0177Y    R180 S1      
317m7821            VIA   -    MD0100PA01X+113457Y+105132X0190Y         S0      
327m7821            J17   -227        A01X+113457Y+105132X0205Y0590R090 S1      
317m7822            VIA   -    MD0080PA01X+134894Y+106632X0160Y         S0      
327m7822            U25   -BV56       A01X+135078Y+106528X0177Y    R180 S1      
317m7822            VIA   -    MD0100PA01X+115071Y+108478X0190Y         S0      
327m7822            J17   -93         A01X+115071Y+108478X0205Y0590R090 S1      
317m7823            VIA   -    MD0080PA01X+135264Y+114924X0160Y         S0      
327m7823            U25   -DD55       A01X+135448Y+114819X0177Y    R180 S1      
317m7823            VIA   -    MD0100PA01X+113457Y+123872X0190Y         S0      
327m7823            J17   -283        A01X+113457Y+123872X0205Y0590R090 S1      
317m7824            VIA   -    MD0080PA01X+135264Y+113010X0160Y         S0      
327m7824            U25   -CV55       A01X+135448Y+112906X0177Y    R180 S1      
317m7824            VIA   -    MD0100PA01X+113457Y+120191X0190Y         S0      
327m7824            J17   -272        A01X+113457Y+120191X0205Y0590R090 S1      
317m7825            VIA   -    MD0080PA01X+135264Y+111097X0160Y         S0      
327m7825            U25   -CM55       A01X+135448Y+110992X0177Y    R180 S1      
317m7825            VIA   -    MD0100PA01X+113457Y+116510X0190Y         S0      
327m7825            J17   -261        A01X+113457Y+116510X0205Y0590R090 S1      
317m7826            VIA   -    MD0080PA01X+135264Y+109184X0160Y         S0      
327m7826            U25   -CF55       A01X+135448Y+109079X0177Y    R180 S1      
317m7826            VIA   -    MD0100PA01X+113457Y+112829X0190Y         S0      
327m7826            J17   -250        A01X+113457Y+112829X0205Y0590R090 S1      
317m7827            VIA   -    MD0080PA01X+135264Y+107270X0160Y         S0      
327m7827            U25   -BY55       A01X+135448Y+107165X0177Y    R180 S1      
317m7827            VIA   -    MD0100PA01X+113457Y+109148X0190Y         S0      
327m7827            J17   -239        A01X+113457Y+109148X0205Y0590R090 S1      
317m7828            VIA   -    MD0080PA01X+134894Y+114286X0160Y         S0      
327m7828            U25   -DB56       A01X+135078Y+114181X0177Y    R180 S1      
317m7828            VIA   -    MD0100PA01X+115071Y+123203X0190Y         S0      
327m7828            J17   -137        A01X+115071Y+123203X0205Y0590R090 S1      
317m7829            VIA   -    MD0080PA01X+134894Y+112372X0160Y         S0      
327m7829            U25   -CT56       A01X+135078Y+112268X0177Y    R180 S1      
317m7829            VIA   -    MD0100PA01X+115071Y+119522X0190Y         S0      
327m7829            J17   -126        A01X+115071Y+119522X0205Y0590R090 S1      
317m7830            VIA   -    MD0080PA01X+134894Y+110459X0160Y         S0      
327m7830            U25   -CK56       A01X+135078Y+110354X0177Y    R180 S1      
317m7830            VIA   -    MD0100PA01X+115071Y+115841X0190Y         S0      
327m7830            J17   -115        A01X+115071Y+115841X0205Y0590R090 S1      
317m7831            VIA   -    MD0080PA01X+134894Y+108546X0160Y         S0      
327m7831            U25   -CD56       A01X+135078Y+108441X0177Y    R180 S1      
317m7831            VIA   -    MD0100PA01X+115071Y+112160X0190Y         S0      
327m7831            J17   -104        A01X+115071Y+112160X0205Y0590R090 S1      
317m7832            VIA   -    MD0080PA01X+134709Y+106951X0160Y         S0      
327m7832            U25   -BW57       A01X+134893Y+106846X0177Y    R180 S1      
317m7832            VIA   -    MD0100PA01X+115071Y+108813X0190Y         S0      
327m7832            J17   -94         A01X+115071Y+108813X0205Y0590R090 S1      
317m7833            VIA   -    MD0080PA01X+135449Y+114605X0160Y         S0      
327m7833            U25   -DC55       A01X+135633Y+114500X0177Y    R180 S1      
317m7833            VIA   -    MD0100PA01X+113457Y+123537X0190Y         S0      
327m7833            J17   -282        A01X+113457Y+123537X0205Y0590R090 S1      
317m7834            VIA   -    MD0080PA01X+135449Y+112691X0160Y         S0      
327m7834            U25   -CU55       A01X+135633Y+112587X0177Y    R180 S1      
317m7834            VIA   -    MD0100PA01X+113457Y+119856X0190Y         S0      
327m7834            J17   -271        A01X+113457Y+119856X0205Y0590R090 S1      
317m7835            VIA   -    MD0080PA01X+135449Y+110778X0160Y         S0      
327m7835            U25   -CL55       A01X+135633Y+110673X0177Y    R180 S1      
317m7835            VIA   -    MD0100PA01X+113457Y+116175X0190Y         S0      
327m7835            J17   -260        A01X+113457Y+116175X0205Y0590R090 S1      
317m7836            VIA   -    MD0080PA01X+135449Y+108865X0160Y         S0      
327m7836            U25   -CE55       A01X+135633Y+108760X0177Y    R180 S1      
317m7836            VIA   -    MD0100PA01X+113457Y+112494X0190Y         S0      
327m7836            J17   -249        A01X+113457Y+112494X0205Y0590R090 S1      
317m7837            VIA   -    MD0080PA01X+135449Y+106951X0160Y         S0      
327m7837            U25   -BW55       A01X+135633Y+106846X0177Y    R180 S1      
317m7837            VIA   -    MD0100PA01X+113457Y+108813X0190Y         S0      
327m7837            J17   -238        A01X+113457Y+108813X0205Y0590R090 S1      
317m7838            VIA   -    MD0080PA01X+134709Y+114605X0160Y         S0      
327m7838            U25   -DC57       A01X+134893Y+114500X0177Y    R180 S1      
317m7838            VIA   -    MD0100PA01X+115071Y+123537X0190Y         S0      
327m7838            J17   -138        A01X+115071Y+123537X0205Y0590R090 S1      
317m7839            VIA   -    MD0080PA01X+134709Y+112691X0160Y         S0      
327m7839            U25   -CU57       A01X+134893Y+112587X0177Y    R180 S1      
317m7839            VIA   -    MD0100PA01X+115071Y+119856X0190Y         S0      
327m7839            J17   -127        A01X+115071Y+119856X0205Y0590R090 S1      
317m7840            VIA   -    MD0080PA01X+134709Y+110778X0160Y         S0      
327m7840            U25   -CL57       A01X+134893Y+110673X0177Y    R180 S1      
317m7840            VIA   -    MD0100PA01X+115071Y+116175X0190Y         S0      
327m7840            J17   -116        A01X+115071Y+116175X0205Y0590R090 S1      
317m7841            VIA   -    MD0080PA01X+134709Y+108865X0160Y         S0      
327m7841            U25   -CE57       A01X+134893Y+108760X0177Y    R180 S1      
317m7841            VIA   -    MD0100PA01X+115071Y+112494X0190Y         S0      
327m7841            J17   -105        A01X+115071Y+112494X0205Y0590R090 S1      
317m7842            VIA   -    MD0080PA01X+135449Y+110140X0160Y         S0      
327m7842            U25   -CJ55       A01X+135633Y+110036X0177Y    R180 S1      
317m7842            VIA   -    MD0100PA01X+115071Y+115171X0190Y         S0      
327m7842            J17   -113        A01X+115071Y+115171X0205Y0590R090 S1      
317m7843            VIA   -    MD0080PA01X+134894Y+109821X0160Y         S0      
327m7843            U25   -CH56       A01X+135078Y+109717X0177Y    R180 S1      
317m7843            VIA   -    MD0100PA01X+115071Y+114502X0190Y         S0      
327m7843            J17   -111        A01X+115071Y+114502X0205Y0590R090 S1      
317m7844            VIA   -    MD0080PA01X+135264Y+109821X0160Y         S0      
327m7844            U25   -CH55       A01X+135448Y+109717X0177Y    R180 S1      
317m7844            VIA   -    MD0100PA01X+113457Y+114167X0190Y         S0      
327m7844            J17   -254        A01X+113457Y+114167X0205Y0590R090 S1      
317m7845            VIA   -    MD0080PA01X+134709Y+109502X0160Y         S0      
327m7845            U25   -CG57       A01X+134893Y+109398X0177Y    R180 S1      
317m7845            VIA   -    MD0100PA01X+113457Y+113498X0190Y         S0      
327m7845            J17   -252        A01X+113457Y+113498X0205Y0590R090 S1      
317m7846            VIA   -    MD0080PA01X+135449Y+109502X0160Y         S0      
327m7846            U25   -CG55       A01X+135633Y+109398X0177Y    R180 S1      
317m7846            VIA   -    MD0100PA01X+115071Y+113833X0190Y         S0      
327m7846            J17   -109        A01X+115071Y+113833X0205Y0590R090 S1      
317m7847            VIA   -    MD0080PA01X+134894Y+109184X0160Y         S0      
327m7847            U25   -CF56       A01X+135078Y+109079X0177Y    R180 S1      
317m7847            VIA   -    MD0100PA01X+115071Y+113163X0190Y         S0      
327m7847            J17   -107        A01X+115071Y+113163X0205Y0590R090 S1      
317m7848            VIA   -    MD0080PA01X+135264Y+108546X0160Y         S0      
327m7848            U25   -CD55       A01X+135448Y+108441X0177Y    R180 S1      
317m7848            VIA   -    MD0100PA01X+113457Y+111825X0190Y         S0      
327m7848            J17   -247        A01X+113457Y+111825X0205Y0590R090 S1      
317m7849            VIA   -    MD0080PA01X+135264Y+115561X0160Y         S0      
317m7849            VIA   -    MD0100PA01X+113457Y+125211X0190Y         S0      
327m7849            J17   -287        A01X+113457Y+125211X0205Y0590R090 S1      
327m7849            U25   -DF55       A01X+135448Y+115457X0177Y    R180 S1      
317m7850            VIA   -    MD0080PA01X+134709Y+115242X0160Y         S0      
327m7850            U25   -DE57       A01X+134893Y+115138X0177Y    R180 S1      
317m7850            VIA   -    MD0100PA01X+113457Y+124541X0190Y         S0      
327m7850            J17   -285        A01X+113457Y+124541X0205Y0590R090 S1      
317m7851            VIA   -    MD0080PA01X+134709Y+108227X0160Y         S0      
327m7851            U25   -CC57       A01X+134893Y+108122X0177Y    R180 S1      
317m7851            VIA   -    MD0100PA01X+113457Y+111156X0190Y         S0      
327m7851            J17   -245        A01X+113457Y+111156X0205Y0590R090 S1      
317m7852            VIA   -    MD0080PA01X+135449Y+115242X0160Y         S0      
327m7852            U25   -DE55       A01X+135633Y+115138X0177Y    R180 S1      
317m7852            VIA   -    MD0100PA01X+115071Y+124876X0190Y         S0      
327m7852            J17   -142        A01X+115071Y+124876X0205Y0590R090 S1      
317m7853            VIA   -    MD0080PA01X+134894Y+114924X0160Y         S0      
327m7853            U25   -DD56       A01X+135078Y+114819X0177Y    R180 S1      
317m7853            VIA   -    MD0100PA01X+115071Y+124207X0190Y         S0      
327m7853            J17   -140        A01X+115071Y+124207X0205Y0590R090 S1      
317m7854            VIA   -    MD0080PA01X+135264Y+114286X0160Y         S0      
327m7854            U25   -DB55       A01X+135448Y+114181X0177Y    R180 S1      
317m7854            VIA   -    MD0100PA01X+113457Y+122868X0190Y         S0      
327m7854            J17   -280        A01X+113457Y+122868X0205Y0590R090 S1      
317m7855            VIA   -    MD0080PA01X+134709Y+113967X0160Y         S0      
327m7855            U25   -DA57       A01X+134893Y+113862X0177Y    R180 S1      
317m7855            VIA   -    MD0100PA01X+113457Y+122199X0190Y         S0      
327m7855            J17   -278        A01X+113457Y+122199X0205Y0590R090 S1      
317m7856            VIA   -    MD0080PA01X+135449Y+113967X0160Y         S0      
327m7856            U25   -DA55       A01X+135633Y+113862X0177Y    R180 S1      
317m7856            VIA   -    MD0100PA01X+115071Y+122534X0190Y         S0      
327m7856            J17   -135        A01X+115071Y+122534X0205Y0590R090 S1      
317m7857            VIA   -    MD0080PA01X+134894Y+113648X0160Y         S0      
327m7857            U25   -CY56       A01X+135078Y+113543X0177Y    R180 S1      
317m7857            VIA   -    MD0100PA01X+115071Y+121864X0190Y         S0      
327m7857            J17   -133        A01X+115071Y+121864X0205Y0590R090 S1      
317m7858            VIA   -    MD0080PA01X+135264Y+113648X0160Y         S0      
327m7858            U25   -CY55       A01X+135448Y+113543X0177Y    R180 S1      
317m7858            VIA   -    MD0100PA01X+113457Y+121530X0190Y         S0      
327m7858            J17   -276        A01X+113457Y+121530X0205Y0590R090 S1      
317m7859            VIA   -    MD0080PA01X+134709Y+113329X0160Y         S0      
327m7859            U25   -CW57       A01X+134893Y+113224X0177Y    R180 S1      
317m7859            VIA   -    MD0100PA01X+113457Y+120860X0190Y         S0      
327m7859            J17   -274        A01X+113457Y+120860X0205Y0590R090 S1      
317m7860            VIA   -    MD0080PA01X+135449Y+113329X0160Y         S0      
327m7860            U25   -CW55       A01X+135633Y+113224X0177Y    R180 S1      
317m7860            VIA   -    MD0100PA01X+115071Y+121195X0190Y         S0      
327m7860            J17   -131        A01X+115071Y+121195X0205Y0590R090 S1      
317m7861            VIA   -    MD0080PA01X+134894Y+113010X0160Y         S0      
327m7861            U25   -CV56       A01X+135078Y+112906X0177Y    R180 S1      
327m7861            J17   -129        A01X+115071Y+120526X0205Y0590R090 S1      
317m7861            VIA   -    MD0100PA01X+115071Y+120526X0190Y         S0      
317m7862            VIA   -    MD0080PA01X+135449Y+108227X0160Y         S0      
327m7862            U25   -CC55       A01X+135633Y+108122X0177Y    R180 S1      
317m7862            VIA   -    MD0100PA01X+115071Y+111490X0190Y         S0      
327m7862            J17   -102        A01X+115071Y+111490X0205Y0590R090 S1      
317m7863            VIA   -    MD0080PA01X+135264Y+112372X0160Y         S0      
327m7863            U25   -CT55       A01X+135448Y+112268X0177Y    R180 S1      
317m7863            VIA   -    MD0100PA01X+113457Y+119187X0190Y         S0      
327m7863            J17   -269        A01X+113457Y+119187X0205Y0590R090 S1      
317m7864            VIA   -    MD0080PA01X+134709Y+112054X0160Y         S0      
327m7864            U25   -CR57       A01X+134893Y+111949X0177Y    R180 S1      
317m7864            VIA   -    MD0100PA01X+113457Y+118518X0190Y         S0      
327m7864            J17   -267        A01X+113457Y+118518X0205Y0590R090 S1      
317m7865            VIA   -    MD0080PA01X+135449Y+112054X0160Y         S0      
327m7865            U25   -CR55       A01X+135633Y+111949X0177Y    R180 S1      
317m7865            VIA   -    MD0100PA01X+115071Y+118852X0190Y         S0      
327m7865            J17   -124        A01X+115071Y+118852X0205Y0590R090 S1      
317m7866            VIA   -    MD0080PA01X+134894Y+111735X0160Y         S0      
327m7866            U25   -CP56       A01X+135078Y+111630X0177Y    R180 S1      
317m7866            VIA   -    MD0100PA01X+115071Y+118183X0190Y         S0      
327m7866            J17   -122        A01X+115071Y+118183X0205Y0590R090 S1      
317m7867            VIA   -    MD0080PA01X+135264Y+111735X0160Y         S0      
327m7867            U25   -CP55       A01X+135448Y+111630X0177Y    R180 S1      
317m7867            VIA   -    MD0100PA01X+113457Y+117848X0190Y         S0      
327m7867            J17   -265        A01X+113457Y+117848X0205Y0590R090 S1      
317m7868            VIA   -    MD0080PA01X+134709Y+111416X0160Y         S0      
327m7868            U25   -CN57       A01X+134893Y+111311X0177Y    R180 S1      
317m7868            VIA   -    MD0100PA01X+113457Y+117179X0190Y         S0      
327m7868            J17   -263        A01X+113457Y+117179X0205Y0590R090 S1      
317m7869            VIA   -    MD0080PA01X+135449Y+111416X0160Y         S0      
327m7869            U25   -CN55       A01X+135633Y+111311X0177Y    R180 S1      
317m7869            VIA   -    MD0100PA01X+115071Y+117514X0190Y         S0      
327m7869            J17   -120        A01X+115071Y+117514X0205Y0590R090 S1      
317m7870            VIA   -    MD0080PA01X+134894Y+111097X0160Y         S0      
327m7870            U25   -CM56       A01X+135078Y+110992X0177Y    R180 S1      
317m7870            VIA   -    MD0100PA01X+115071Y+116844X0190Y         S0      
327m7870            J17   -118        A01X+115071Y+116844X0205Y0590R090 S1      
317m7871            VIA   -    MD0080PA01X+135264Y+110459X0160Y         S0      
327m7871            U25   -CK55       A01X+135448Y+110354X0177Y    R180 S1      
317m7871            VIA   -    MD0100PA01X+113457Y+115506X0190Y         S0      
327m7871            J17   -258        A01X+113457Y+115506X0205Y0590R090 S1      
317m7872            VIA   -    MD0080PA01X+134709Y+110140X0160Y         S0      
327m7872            U25   -CJ57       A01X+134893Y+110036X0177Y    R180 S1      
317m7872            VIA   -    MD0100PA01X+113457Y+114837X0190Y         S0      
327m7872            J17   -256        A01X+113457Y+114837X0205Y0590R090 S1      
317m7873            VIA   -    MD0080PA01X+134894Y+107908X0160Y         S0      
327m7873            U25   -CB56       A01X+135078Y+107803X0177Y    R180 S1      
317m7873            VIA   -    MD0100PA01X+115071Y+110821X0190Y         S0      
327m7873            J17   -100        A01X+115071Y+110821X0205Y0590R090 S1      
317m7874            VIA   -    MD0080PA01X+134709Y+105038X0160Y         S0      
327m7874            U25   -BN57       A01X+134893Y+104933X0177Y    R180 S1      
317m7874            VIA   -    MD0100PA01X+113457Y+105801X0190Y         S0      
327m7874            J17   -229        A01X+113457Y+105801X0205Y0590R090 S1      
317m7875            VIA   -    MD0080PA01X+135264Y+104719X0160Y         S0      
327m7875            U25   -BM55       A01X+135448Y+104614X0177Y    R180 S1      
317m7875            VIA   -    MD0100PA01X+115071Y+105467X0190Y         S0      
327m7875            J17   -84         A01X+115071Y+105467X0205Y0590R090 S1      
317m7876            VIA   -    MD0080PA01X+135264Y+106632X0160Y         S0      
327m7876            U25   -BV55       A01X+135448Y+106528X0177Y    R180 S1      
317m7876            VIA   -    MD0100PA01X+113457Y+108144X0190Y         S0      
327m7876            J17   -236        A01X+113457Y+108144X0205Y0590R090 S1      
317m7877            VIA   -    MD0080PA01X+134709Y+106313X0160Y         S0      
327m7877            U25   -BU57       A01X+134893Y+106209X0177Y    R180 S1      
317m7877            VIA   -    MD0100PA01X+113457Y+107474X0190Y         S0      
327m7877            J17   -234        A01X+113457Y+107474X0205Y0590R090 S1      
317m7878            VIA   -    MD0080PA01X+135449Y+106313X0160Y         S0      
327m7878            U25   -BU55       A01X+135633Y+106209X0177Y    R180 S1      
317m7878            VIA   -    MD0100PA01X+115071Y+107809X0190Y         S0      
327m7878            J17   -91         A01X+115071Y+107809X0205Y0590R090 S1      
317m7879            VIA   -    MD0080PA01X+134894Y+105994X0160Y         S0      
327m7879            U25   -BT56       A01X+135078Y+105890X0177Y    R180 S1      
317m7879            VIA   -    MD0100PA01X+115071Y+107140X0190Y         S0      
327m7879            J17   -89         A01X+115071Y+107140X0205Y0590R090 S1      
317m7880            VIA   -    MD0080PA01X+135264Y+107908X0160Y         S0      
327m7880            U25   -CB55       A01X+135448Y+107803X0177Y    R180 S1      
317m7880            VIA   -    MD0100PA01X+113457Y+110486X0190Y         S0      
327m7880            J17   -243        A01X+113457Y+110486X0205Y0590R090 S1      
317m7881            VIA   -    MD0080PA01X+134709Y+107589X0160Y         S0      
327m7881            U25   -CA57       A01X+134893Y+107484X0177Y    R180 S1      
317m7881            VIA   -    MD0100PA01X+113457Y+109817X0190Y         S0      
327m7881            J17   -241        A01X+113457Y+109817X0205Y0590R090 S1      
317m7882            VIA   -    MD0080PA01X+135449Y+107589X0160Y         S0      
327m7882            U25   -CA55       A01X+135633Y+107484X0177Y    R180 S1      
317m7882            VIA   -    MD0100PA01X+115071Y+110152X0190Y         S0      
327m7882            J17   -98         A01X+115071Y+110152X0205Y0590R090 S1      
317m7883            VIA   -    MD0080PA01X+134894Y+107270X0160Y         S0      
327m7883            U25   -BY56       A01X+135078Y+107165X0177Y    R180 S1      
317m7883            VIA   -    MD0100PA01X+115071Y+109482X0190Y         S0      
327m7883            J17   -96         A01X+115071Y+109482X0205Y0590R090 S1      
317m7884            VIA   -    MD0080PA01X+134894Y+104081X0160Y         S0      
327m7884            U25   -BK56       A01X+135078Y+103976X0177Y    R180 S1      
317m7884            VIA   -    MD0100PA01X+115071Y+104797X0190Y         S0      
327m7884            J17   -82         A01X+115071Y+104797X0205Y0590R090 S1      
317m7885            VIA   -    MD0080PA01X+135264Y+104081X0160Y         S0      
327m7885            U25   -BK55       A01X+135448Y+103976X0177Y    R180 S1      
317m7885            VIA   -    MD0100PA01X+113457Y+104463X0190Y         S0      
327m7885            J17   -225        A01X+113457Y+104463X0205Y0590R090 S1      
317m7886            VIA   -    MD0080PA01X+135449Y+103762X0160Y         S0      
327m7886            U25   -BJ55       A01X+135633Y+103658X0177Y    R180 S1      
317m7886            VIA   -    MD0100PA01X+115071Y+104128X0190Y         S0      
327m7886            J17   -80         A01X+115071Y+104128X0205Y0590R090 S1      
317m7887            VIA   -    MD0080PA01X+134709Y+103762X0160Y         S0      
327m7887            U25   -BJ57       A01X+134893Y+103658X0177Y    R180 S1      
317m7887            VIA   -    MD0100PA01X+113457Y+103793X0190Y         S0      
327m7887            J17   -223        A01X+113457Y+103793X0205Y0590R090 S1      
317m7888            VIA   -    MD0080PA01X+134894Y+103443X0160Y         S0      
327m7888            U25   -BH56       A01X+135078Y+103339X0177Y    R180 S1      
317m7888            VIA   -    MD0100PA01X+115071Y+103459X0190Y         S0      
327m7888            J17   -78         A01X+115071Y+103459X0205Y0590R090 S1      
317m7889            VIA   -    MD0080PA01X+135264Y+103443X0160Y         S0      
327m7889            U25   -BH55       A01X+135448Y+103339X0177Y    R180 S1      
317m7889            VIA   -    MD0100PA01X+113457Y+103124X0190Y         S0      
327m7889            J17   -221        A01X+113457Y+103124X0205Y0590R090 S1      
317m7890            VIA   -    MD0080PA01X+135449Y+103124X0160Y         S0      
327m7890            U25   -BG55       A01X+135633Y+103020X0177Y    R180 S1      
317m7890            VIA   -    MD0100PA01X+115071Y+102789X0190Y         S0      
327m7890            J17   -76         A01X+115071Y+102789X0205Y0590R090 S1      
317m7891            VIA   -    MD0080PA01X+135449Y+105038X0160Y         S0      
327m7891            U25   -BN55       A01X+135633Y+104933X0177Y    R180 S1      
317m7891            VIA   -    MD0100PA01X+115071Y+106136X0190Y         S0      
327m7891            J17   -86         A01X+115071Y+106136X0205Y0590R090 S1      
317m7892            VIA   -    MD0080PA01X+135331Y+100718X0160Y    R180 S0      
327m7892            U25   -BC55       A01X+135515Y+100823X0177Y    R180 S1      
317m7892            VIA   -    MD0100PA01X+115071Y+100112X0190Y         S0      
327m7892            J17   -74         A01X+115071Y+100112X0205Y0590R090 S1      
317m7893            VIA   -    MD0080PA01X+135331Y+097529X0160Y    R180 S0      
327m7893            U25   -AN55       A01X+135515Y+097634X0177Y    R180 S1      
317m7893            VIA   -    MD0100PA01X+113457Y+094423X0190Y         S0      
327m7893            J17   -201        A01X+113457Y+094423X0205Y0590R090 S1      
317m7894            VIA   -    MD0080PA01X+135331Y+095616X0160Y    R180 S0      
327m7894            U25   -AG55       A01X+135515Y+095720X0177Y    R180 S1      
317m7894            VIA   -    MD0100PA01X+113457Y+090742X0190Y         S0      
327m7894            J17   -190        A01X+113457Y+090742X0205Y0590R090 S1      
317m7895            VIA   -    MD0080PA01X+135331Y+093702X0160Y    R180 S0      
327m7895            U25   -AA55       A01X+135515Y+093807X0177Y    R180 S1      
317m7895            VIA   -    MD0100PA01X+113457Y+087061X0190Y         S0      
327m7895            J17   -179        A01X+113457Y+087061X0205Y0590R090 S1      
317m7896            VIA   -    MD0080PA01X+135331Y+091789X0160Y    R180 S0      
327m7896            U25   -R55        A01X+135515Y+091894X0177Y    R180 S1      
317m7896            VIA   -    MD0100PA01X+113457Y+083380X0190Y         S0      
327m7896            J17   -168        A01X+113457Y+083380X0205Y0590R090 S1      
317m7897            VIA   -    MD0080PA01X+135331Y+089876X0160Y    R180 S0      
327m7897            U25   -J55        A01X+135515Y+089980X0177Y    R180 S1      
317m7897            VIA   -    MD0100PA01X+113457Y+079699X0190Y         S0      
327m7897            J17   -157        A01X+113457Y+079699X0205Y0590R090 S1      
317m7898            VIA   -    MD0080PA01X+134591Y+096891X0160Y    R180 S0      
327m7898            U25   -AL57       A01X+134775Y+096996X0177Y    R180 S1      
317m7898            VIA   -    MD0100PA01X+115071Y+093754X0190Y         S0      
327m7898            J17   -55         A01X+115071Y+093754X0205Y0590R090 S1      
317m7899            VIA   -    MD0080PA01X+134591Y+094978X0160Y    R180 S0      
327m7899            U25   -AE57       A01X+134775Y+095083X0177Y    R180 S1      
317m7899            VIA   -    MD0100PA01X+115071Y+090073X0190Y         S0      
327m7899            J17   -44         A01X+115071Y+090073X0205Y0590R090 S1      
317m7900            VIA   -    MD0080PA01X+134591Y+093065X0160Y    R180 S0      
327m7900            U25   -W57        A01X+134775Y+093169X0177Y    R180 S1      
317m7900            VIA   -    MD0100PA01X+115071Y+086392X0190Y         S0      
327m7900            J17   -33         A01X+115071Y+086392X0205Y0590R090 S1      
317m7901            VIA   -    MD0080PA01X+134591Y+091151X0160Y    R180 S0      
327m7901            U25   -N57        A01X+134775Y+091256X0177Y    R180 S1      
317m7901            VIA   -    MD0100PA01X+115071Y+082711X0190Y         S0      
327m7901            J17   -22         A01X+115071Y+082711X0205Y0590R090 S1      
317m7902            VIA   -    MD0080PA01X+134591Y+089238X0160Y    R180 S0      
327m7902            U25   -G57        A01X+134775Y+089343X0177Y    R180 S1      
317m7902            VIA   -    MD0100PA01X+115071Y+079030X0190Y         S0      
327m7902            J17   -11         A01X+115071Y+079030X0205Y0590R090 S1      
317m7903            VIA   -    MD0080PA01X+135146Y+097210X0160Y    R180 S0      
327m7903            U25   -AM55       A01X+135330Y+097315X0177Y    R180 S1      
317m7903            VIA   -    MD0100PA01X+113457Y+094089X0190Y         S0      
327m7903            J17   -200        A01X+113457Y+094089X0205Y0590R090 S1      
317m7904            VIA   -    MD0080PA01X+135146Y+095297X0160Y    R180 S0      
327m7904            U25   -AF55       A01X+135330Y+095402X0177Y    R180 S1      
317m7904            VIA   -    MD0100PA01X+113457Y+090408X0190Y         S0      
327m7904            J17   -189        A01X+113457Y+090408X0205Y0590R090 S1      
317m7905            VIA   -    MD0080PA01X+135146Y+093384X0160Y    R180 S0      
327m7905            U25   -Y55        A01X+135330Y+093488X0177Y    R180 S1      
317m7905            VIA   -    MD0100PA01X+113457Y+086726X0190Y         S0      
327m7905            J17   -178        A01X+113457Y+086726X0205Y0590R090 S1      
317m7906            VIA   -    MD0080PA01X+135146Y+091470X0160Y    R180 S0      
327m7906            U25   -P55        A01X+135330Y+091575X0177Y    R180 S1      
317m7906            VIA   -    MD0100PA01X+113457Y+083045X0190Y         S0      
327m7906            J17   -167        A01X+113457Y+083045X0205Y0590R090 S1      
317m7907            VIA   -    MD0080PA01X+135146Y+089557X0160Y    R180 S0      
327m7907            U25   -H55        A01X+135330Y+089662X0177Y    R180 S1      
317m7907            VIA   -    MD0100PA01X+113457Y+079364X0190Y         S0      
327m7907            J17   -156        A01X+113457Y+079364X0205Y0590R090 S1      
317m7908            VIA   -    MD0080PA01X+134776Y+097210X0160Y    R180 S0      
327m7908            U25   -AM56       A01X+134960Y+097315X0177Y    R180 S1      
317m7908            VIA   -    MD0100PA01X+115071Y+094089X0190Y         S0      
327m7908            J17   -56         A01X+115071Y+094089X0205Y0590R090 S1      
317m7909            VIA   -    MD0080PA01X+134776Y+095297X0160Y    R180 S0      
327m7909            U25   -AF56       A01X+134960Y+095402X0177Y    R180 S1      
317m7909            VIA   -    MD0100PA01X+115071Y+090408X0190Y         S0      
327m7909            J17   -45         A01X+115071Y+090408X0205Y0590R090 S1      
317m7910            VIA   -    MD0080PA01X+134776Y+093384X0160Y    R180 S0      
327m7910            U25   -Y56        A01X+134960Y+093488X0177Y    R180 S1      
317m7910            VIA   -    MD0100PA01X+115071Y+086726X0190Y         S0      
327m7910            J17   -34         A01X+115071Y+086726X0205Y0590R090 S1      
317m7911            VIA   -    MD0080PA01X+134776Y+091470X0160Y    R180 S0      
327m7911            U25   -P56        A01X+134960Y+091575X0177Y    R180 S1      
317m7911            VIA   -    MD0100PA01X+115071Y+083045X0190Y         S0      
327m7911            J17   -23         A01X+115071Y+083045X0205Y0590R090 S1      
317m7912            VIA   -    MD0080PA01X+134776Y+089557X0160Y    R180 S0      
327m7912            U25   -H56        A01X+134960Y+089662X0177Y    R180 S1      
317m7912            VIA   -    MD0100PA01X+115071Y+079364X0190Y         S0      
327m7912            J17   -12         A01X+115071Y+079364X0205Y0590R090 S1      
317m7913            VIA   -    MD0080PA01X+135146Y+090832X0160Y    R180 S0      
327m7913            U25   -M55        A01X+135330Y+090937X0177Y    R180 S1      
317m7913            VIA   -    MD0100PA01X+115071Y+082041X0190Y         S0      
327m7913            J17   -20         A01X+115071Y+082041X0205Y0590R090 S1      
317m7914            VIA   -    MD0080PA01X+134591Y+090513X0160Y    R180 S0      
327m7914            U25   -L57        A01X+134775Y+090618X0177Y    R180 S1      
317m7914            VIA   -    MD0100PA01X+115071Y+081372X0190Y         S0      
327m7914            J17   -18         A01X+115071Y+081372X0205Y0590R090 S1      
317m7915            VIA   -    MD0080PA01X+135331Y+090513X0160Y    R180 S0      
327m7915            U25   -L55        A01X+135515Y+090618X0177Y    R180 S1      
317m7915            VIA   -    MD0100PA01X+113457Y+081037X0190Y         S0      
327m7915            J17   -161        A01X+113457Y+081037X0205Y0590R090 S1      
317m7916            VIA   -    MD0080PA01X+134776Y+090195X0160Y    R180 S0      
327m7916            U25   -K56        A01X+134960Y+090299X0177Y    R180 S1      
317m7916            VIA   -    MD0100PA01X+113457Y+080368X0190Y         S0      
327m7916            J17   -159        A01X+113457Y+080368X0205Y0590R090 S1      
317m7917            VIA   -    MD0080PA01X+135146Y+090195X0160Y    R180 S0      
327m7917            U25   -K55        A01X+135330Y+090299X0177Y    R180 S1      
317m7917            VIA   -    MD0100PA01X+115071Y+080703X0190Y         S0      
327m7917            J17   -16         A01X+115071Y+080703X0205Y0590R090 S1      
317m7918            VIA   -    MD0080PA01X+134591Y+089876X0160Y    R180 S0      
327m7918            U25   -J57        A01X+134775Y+089980X0177Y    R180 S1      
317m7918            VIA   -    MD0100PA01X+115071Y+080034X0190Y         S0      
327m7918            J17   -14         A01X+115071Y+080034X0205Y0590R090 S1      
317m7919            VIA   -    MD0080PA01X+135331Y+089238X0160Y    R180 S0      
327m7919            U25   -G55        A01X+135515Y+089343X0177Y    R180 S1      
317m7919            VIA   -    MD0100PA01X+113457Y+078695X0190Y         S0      
327m7919            J17   -154        A01X+113457Y+078695X0205Y0590R090 S1      
317m7920            VIA   -    MD0080PA01X+135331Y+096254X0160Y    R180 S0      
327m7920            U25   -AJ55       A01X+135515Y+096358X0177Y    R180 S1      
317m7920            VIA   -    MD0100PA01X+113457Y+092081X0190Y         S0      
327m7920            J17   -194        A01X+113457Y+092081X0205Y0590R090 S1      
317m7921            VIA   -    MD0080PA01X+134776Y+095935X0160Y    R180 S0      
327m7921            U25   -AH56       A01X+134960Y+096039X0177Y    R180 S1      
317m7921            VIA   -    MD0100PA01X+113457Y+091411X0190Y         S0      
327m7921            J17   -192        A01X+113457Y+091411X0205Y0590R090 S1      
317m7922            VIA   -    MD0080PA01X+134776Y+088919X0160Y    R180 S0      
327m7922            U25   -F56        A01X+134960Y+089024X0177Y    R180 S1      
317m7922            VIA   -    MD0100PA01X+113457Y+078026X0190Y         S0      
327m7922            J17   -152        A01X+113457Y+078026X0205Y0590R090 S1      
317m7923            VIA   -    MD0080PA01X+135146Y+095935X0160Y    R180 S0      
327m7923            U25   -AH55       A01X+135330Y+096039X0177Y    R180 S1      
317m7923            VIA   -    MD0100PA01X+115071Y+091746X0190Y         S0      
327m7923            J17   -49         A01X+115071Y+091746X0205Y0590R090 S1      
317m7924            VIA   -    MD0080PA01X+134591Y+095616X0160Y    R180 S0      
327m7924            U25   -AG57       A01X+134775Y+095720X0177Y    R180 S1      
317m7924            VIA   -    MD0100PA01X+115071Y+091077X0190Y         S0      
327m7924            J17   -47         A01X+115071Y+091077X0205Y0590R090 S1      
317m7925            VIA   -    MD0080PA01X+135331Y+094978X0160Y    R180 S0      
327m7925            U25   -AE55       A01X+135515Y+095083X0177Y    R180 S1      
317m7925            VIA   -    MD0100PA01X+113457Y+089738X0190Y         S0      
327m7925            J17   -187        A01X+113457Y+089738X0205Y0590R090 S1      
317m7926            VIA   -    MD0080PA01X+134776Y+094659X0160Y    R180 S0      
327m7926            U25   -AD56       A01X+134960Y+094764X0177Y    R180 S1      
317m7926            VIA   -    MD0100PA01X+113457Y+089069X0190Y         S0      
327m7926            J17   -185        A01X+113457Y+089069X0205Y0590R090 S1      
317m7927            VIA   -    MD0080PA01X+135146Y+094659X0160Y    R180 S0      
327m7927            U25   -AD55       A01X+135330Y+094764X0177Y    R180 S1      
317m7927            VIA   -    MD0100PA01X+115071Y+089404X0190Y         S0      
327m7927            J17   -42         A01X+115071Y+089404X0205Y0590R090 S1      
317m7928            VIA   -    MD0080PA01X+134591Y+094340X0160Y    R180 S0      
327m7928            U25   -AC57       A01X+134775Y+094445X0177Y    R180 S1      
317m7928            VIA   -    MD0100PA01X+115071Y+088734X0190Y         S0      
327m7928            J17   -40         A01X+115071Y+088734X0205Y0590R090 S1      
317m7929            VIA   -    MD0080PA01X+135331Y+094340X0160Y    R180 S0      
327m7929            U25   -AC55       A01X+135515Y+094445X0177Y    R180 S1      
317m7929            VIA   -    MD0100PA01X+113457Y+088400X0190Y         S0      
327m7929            J17   -183        A01X+113457Y+088400X0205Y0590R090 S1      
317m7930            VIA   -    MD0080PA01X+134776Y+094021X0160Y    R180 S0      
327m7930            U25   -AB56       A01X+134960Y+094126X0177Y    R180 S1      
317m7930            VIA   -    MD0100PA01X+113457Y+087730X0190Y         S0      
327m7930            J17   -181        A01X+113457Y+087730X0205Y0590R090 S1      
317m7931            VIA   -    MD0080PA01X+135146Y+094021X0160Y    R180 S0      
327m7931            U25   -AB55       A01X+135330Y+094126X0177Y    R180 S1      
317m7931            VIA   -    MD0100PA01X+115071Y+088065X0190Y         S0      
327m7931            J17   -38         A01X+115071Y+088065X0205Y0590R090 S1      
317m7932            VIA   -    MD0080PA01X+134591Y+093702X0160Y    R180 S0      
327m7932            U25   -AA57       A01X+134775Y+093807X0177Y    R180 S1      
317m7932            VIA   -    MD0100PA01X+115071Y+087396X0190Y         S0      
327m7932            J17   -36         A01X+115071Y+087396X0205Y0590R090 S1      
317m7933            VIA   -    MD0080PA01X+135146Y+088919X0160Y    R180 S0      
327m7933            U25   -F55        A01X+135330Y+089024X0177Y    R180 S1      
317m7933            VIA   -    MD0100PA01X+115071Y+078360X0190Y         S0      
327m7933            J17   -9          A01X+115071Y+078360X0205Y0590R090 S1      
317m7934            VIA   -    MD0080PA01X+135331Y+093065X0160Y    R180 S0      
327m7934            U25   -W55        A01X+135515Y+093169X0177Y    R180 S1      
317m7934            VIA   -    MD0100PA01X+113457Y+086057X0190Y         S0      
327m7934            J17   -176        A01X+113457Y+086057X0205Y0590R090 S1      
317m7935            VIA   -    MD0080PA01X+134776Y+092746X0160Y    R180 S0      
327m7935            U25   -V56        A01X+134960Y+092850X0177Y    R180 S1      
317m7935            VIA   -    MD0100PA01X+113457Y+085388X0190Y         S0      
327m7935            J17   -174        A01X+113457Y+085388X0205Y0590R090 S1      
317m7936            VIA   -    MD0080PA01X+135146Y+092746X0160Y    R180 S0      
327m7936            U25   -V55        A01X+135330Y+092850X0177Y    R180 S1      
317m7936            VIA   -    MD0100PA01X+115071Y+085722X0190Y         S0      
327m7936            J17   -31         A01X+115071Y+085722X0205Y0590R090 S1      
317m7937            VIA   -    MD0080PA01X+134591Y+092427X0160Y    R180 S0      
327m7937            U25   -U57        A01X+134775Y+092532X0177Y    R180 S1      
317m7937            VIA   -    MD0100PA01X+115071Y+085053X0190Y         S0      
327m7937            J17   -29         A01X+115071Y+085053X0205Y0590R090 S1      
317m7938            VIA   -    MD0080PA01X+135331Y+092427X0160Y    R180 S0      
327m7938            U25   -U55        A01X+135515Y+092532X0177Y    R180 S1      
317m7938            VIA   -    MD0100PA01X+113457Y+084718X0190Y         S0      
327m7938            J17   -172        A01X+113457Y+084718X0205Y0590R090 S1      
317m7939            VIA   -    MD0080PA01X+134776Y+092108X0160Y    R180 S0      
327m7939            U25   -T56        A01X+134960Y+092213X0177Y    R180 S1      
317m7939            VIA   -    MD0100PA01X+113457Y+084049X0190Y         S0      
327m7939            J17   -170        A01X+113457Y+084049X0205Y0590R090 S1      
317m7940            VIA   -    MD0080PA01X+135146Y+092108X0160Y    R180 S0      
327m7940            U25   -T55        A01X+135330Y+092213X0177Y    R180 S1      
317m7940            VIA   -    MD0100PA01X+115071Y+084384X0190Y         S0      
327m7940            J17   -27         A01X+115071Y+084384X0205Y0590R090 S1      
317m7941            VIA   -    MD0080PA01X+134591Y+091789X0160Y    R180 S0      
327m7941            U25   -R57        A01X+134775Y+091894X0177Y    R180 S1      
317m7941            VIA   -    MD0100PA01X+115071Y+083715X0190Y         S0      
327m7941            J17   -25         A01X+115071Y+083715X0205Y0590R090 S1      
317m7942            VIA   -    MD0080PA01X+135331Y+091151X0160Y    R180 S0      
327m7942            U25   -N55        A01X+135515Y+091256X0177Y    R180 S1      
317m7942            VIA   -    MD0100PA01X+113457Y+082376X0190Y         S0      
327m7942            J17   -165        A01X+113457Y+082376X0205Y0590R090 S1      
317m7943            VIA   -    MD0080PA01X+134776Y+090832X0160Y    R180 S0      
327m7943            U25   -M56        A01X+134960Y+090937X0177Y    R180 S1      
317m7943            VIA   -    MD0100PA01X+113457Y+081707X0190Y         S0      
327m7943            J17   -163        A01X+113457Y+081707X0205Y0590R090 S1      
317m7944            VIA   -    MD0080PA01X+134591Y+088600X0160Y    R180 S0      
327m7944            U25   -E57        A01X+134775Y+088705X0177Y    R180 S1      
317m7944            VIA   -    MD0100PA01X+115071Y+077691X0190Y         S0      
327m7944            J17   -7          A01X+115071Y+077691X0205Y0590R090 S1      
317m7945            VIA   -    MD0080PA01X+135331Y+099443X0160Y    R180 S0      
327m7945            U25   -AW55       A01X+135515Y+099547X0177Y    R180 S1      
317m7945            VIA   -    MD0100PA01X+113457Y+097100X0190Y         S0      
327m7945            J17   -209        A01X+113457Y+097100X0205Y0590R090 S1      
317m7946            VIA   -    MD0080PA01X+134776Y+099124X0160Y    R180 S0      
327m7946            U25   -AV56       A01X+134960Y+099228X0177Y    R180 S1      
317m7946            VIA   -    MD0100PA01X+115071Y+096766X0190Y         S0      
327m7946            J17   -64         A01X+115071Y+096766X0205Y0590R090 S1      
317m7947            VIA   -    MD0080PA01X+135331Y+098167X0160Y    R180 S0      
327m7947            U25   -AR55       A01X+135515Y+098272X0177Y    R180 S1      
317m7947            VIA   -    MD0100PA01X+113457Y+095762X0190Y         S0      
327m7947            J17   -205        A01X+113457Y+095762X0205Y0590R090 S1      
317m7948            VIA   -    MD0080PA01X+134776Y+097848X0160Y    R180 S0      
327m7948            U25   -AP56       A01X+134960Y+097953X0177Y    R180 S1      
317m7948            VIA   -    MD0100PA01X+113457Y+095092X0190Y         S0      
327m7948            J17   -203        A01X+113457Y+095092X0205Y0590R090 S1      
317m7949            VIA   -    MD0080PA01X+135146Y+097848X0160Y    R180 S0      
327m7949            U25   -AP55       A01X+135330Y+097953X0177Y    R180 S1      
317m7949            VIA   -    MD0100PA01X+115071Y+095427X0190Y         S0      
327m7949            J17   -60         A01X+115071Y+095427X0205Y0590R090 S1      
317m7950            VIA   -    MD0080PA01X+134591Y+097529X0160Y    R180 S0      
327m7950            U25   -AN57       A01X+134775Y+097634X0177Y    R180 S1      
317m7950            VIA   -    MD0100PA01X+115071Y+094758X0190Y         S0      
327m7950            J17   -58         A01X+115071Y+094758X0205Y0590R090 S1      
317m7951            VIA   -    MD0080PA01X+135331Y+096891X0160Y    R180 S0      
327m7951            U25   -AL55       A01X+135515Y+096996X0177Y    R180 S1      
317m7951            VIA   -    MD0100PA01X+113457Y+093419X0190Y         S0      
327m7951            J17   -198        A01X+113457Y+093419X0205Y0590R090 S1      
317m7952            VIA   -    MD0080PA01X+134776Y+096572X0160Y    R180 S0      
327m7952            U25   -AK56       A01X+134960Y+096677X0177Y    R180 S1      
317m7952            VIA   -    MD0100PA01X+113457Y+092750X0190Y         S0      
327m7952            J17   -196        A01X+113457Y+092750X0205Y0590R090 S1      
317m7953            VIA   -    MD0080PA01X+135146Y+096572X0160Y    R180 S0      
327m7953            U25   -AK55       A01X+135330Y+096677X0177Y    R180 S1      
317m7953            VIA   -    MD0100PA01X+115071Y+093085X0190Y         S0      
327m7953            J17   -53         A01X+115071Y+093085X0205Y0590R090 S1      
317m7954            VIA   -    MD0080PA01X+134591Y+096254X0160Y    R180 S0      
327m7954            U25   -AJ57       A01X+134775Y+096358X0177Y    R180 S1      
317m7954            VIA   -    MD0100PA01X+115071Y+092415X0190Y         S0      
327m7954            J17   -51         A01X+115071Y+092415X0205Y0590R090 S1      
317m7955            VIA   -    MD0080PA01X+135146Y+100399X0160Y    R180 S0      
327m7955            U25   -BB55       A01X+135330Y+100504X0177Y    R180 S1      
317m7955            VIA   -    MD0100PA01X+115071Y+099443X0190Y         S0      
327m7955            J17   -72         A01X+115071Y+099443X0205Y0590R090 S1      
317m7956            VIA   -    MD0080PA01X+134776Y+100399X0160Y    R180 S0      
327m7956            U25   -BB56       A01X+134960Y+100504X0177Y    R180 S1      
317m7956            VIA   -    MD0100PA01X+113457Y+099108X0190Y         S0      
327m7956            J17   -215        A01X+113457Y+099108X0205Y0590R090 S1      
317m7957            VIA   -    MD0080PA01X+134591Y+100080X0160Y    R180 S0      
327m7957            U25   -BA57       A01X+134775Y+100185X0177Y    R180 S1      
317m7957            VIA   -    MD0100PA01X+115071Y+098774X0190Y         S0      
327m7957            J17   -70         A01X+115071Y+098774X0205Y0590R090 S1      
317m7958            VIA   -    MD0080PA01X+135331Y+100080X0160Y    R180 S0      
327m7958            U25   -BA55       A01X+135515Y+100185X0177Y    R180 S1      
317m7958            VIA   -    MD0100PA01X+113457Y+098439X0190Y         S0      
327m7958            J17   -213        A01X+113457Y+098439X0205Y0590R090 S1      
317m7959            VIA   -    MD0080PA01X+135146Y+099762X0160Y    R180 S0      
327m7959            U25   -AY55       A01X+135330Y+099866X0177Y    R180 S1      
317m7959            VIA   -    MD0100PA01X+115071Y+098104X0190Y         S0      
327m7959            J17   -68         A01X+115071Y+098104X0205Y0590R090 S1      
317m7960            VIA   -    MD0080PA01X+134776Y+099762X0160Y    R180 S0      
327m7960            U25   -AY56       A01X+134960Y+099866X0177Y    R180 S1      
317m7960            VIA   -    MD0100PA01X+113457Y+097770X0190Y         S0      
327m7960            J17   -211        A01X+113457Y+097770X0205Y0590R090 S1      
317m7961            VIA   -    MD0080PA01X+134591Y+099443X0160Y    R180 S0      
327m7961            U25   -AW57       A01X+134775Y+099547X0177Y    R180 S1      
317m7961            VIA   -    MD0100PA01X+115071Y+097435X0190Y         S0      
327m7961            J17   -66         A01X+115071Y+097435X0205Y0590R090 S1      
317m7962            VIA   -    MD0080PA01X+135331Y+098805X0160Y    R180 S0      
327m7962            U25   -AU55       A01X+135515Y+098910X0177Y    R180 S1      
317m7962            VIA   -    MD0100PA01X+113457Y+096431X0190Y         S0      
327m7962            J17   -207        A01X+113457Y+096431X0205Y0590R090 S1      
317m7963            VIA   -    MD0080PA01X+134591Y+100718X0160Y    R180 S0      
327m7963            U25   -BC57       A01X+134775Y+100823X0177Y    R180 S1      
317m7963            VIA   -    MD0100PA01X+113457Y+099778X0190Y         S0      
327m7963            J17   -217        A01X+113457Y+099778X0205Y0590R090 S1      
317m7964            VIA   -    MD0080PA01X+134776Y+101037X0160Y    R180 S0      
327m7964            U25   -BD56       A01X+134960Y+101142X0177Y    R180 S1      
317m7964            VIA   -    MD0100PA01X+113457Y+100112X0190Y         S0      
327m7964            J17   -218        A01X+113457Y+100112X0205Y0590R090 S1      
317m7965            VIA   -    MD0080PA01X+135146Y+098486X0160Y    R180 S0      
327m7965            U25   -AT55       A01X+135330Y+098591X0177Y    R180 S1      
317m7965            VIA   -    MD0100PA18X+115621Y+096096X0190Y         S0      
327m7965            R377  -2          A18X+115621Y+096096X0198Y0197R180 S2      
327m7966            J17   -62         A01X+115071Y+096096X0205Y0590R090 S1      
317m7966            VIA   -    MD0100PA00X+115071Y+096096X0190Y         S0      
327m7966            R377  -1          A18X+115306Y+096096X0198Y0197R180 S2      
317m7967            VIA   -    MD0080PA01X+034689Y+105357X0160Y         S0      
327m7967            U26   -BP63       A01X+034873Y+105252X0177Y    R180 S1      
317m7967            VIA   -    MD0100PA01X+020427Y+106471X0190Y         S0      
327m7967            J26   -87         A01X+020427Y+106471X0205Y0590R090 S1      
317m7968            VIA   -    MD0080PA01X+034504Y+104400X0160Y         S0      
327m7968            U26   -BL64       A01X+034688Y+104295X0177Y    R180 S1      
317m7968            VIA   -    MD0100PA01X+018813Y+105132X0190Y         S0      
327m7968            J26   -227        A01X+018813Y+105132X0205Y0590R090 S1      
317m7969            VIA   -    MD0080PA01X+034689Y+106632X0160Y         S0      
327m7969            U26   -BV63       A01X+034873Y+106528X0177Y    R180 S1      
317m7969            VIA   -    MD0100PA01X+020427Y+108478X0190Y         S0      
327m7969            J26   -93         A01X+020427Y+108478X0205Y0590R090 S1      
317m7970            VIA   -    MD0080PA01X+035060Y+114924X0160Y         S0      
327m7970            U26   -DD62       A01X+035243Y+114819X0177Y    R180 S1      
317m7970            VIA   -    MD0100PA01X+018813Y+123872X0190Y         S0      
327m7970            J26   -283        A01X+018813Y+123872X0205Y0590R090 S1      
317m7971            VIA   -    MD0080PA01X+035060Y+113010X0160Y         S0      
327m7971            U26   -CV62       A01X+035243Y+112906X0177Y    R180 S1      
317m7971            VIA   -    MD0100PA01X+018813Y+120191X0190Y         S0      
327m7971            J26   -272        A01X+018813Y+120191X0205Y0590R090 S1      
317m7972            VIA   -    MD0080PA01X+035060Y+111097X0160Y         S0      
327m7972            U26   -CM62       A01X+035243Y+110992X0177Y    R180 S1      
317m7972            VIA   -    MD0100PA01X+018813Y+116510X0190Y         S0      
327m7972            J26   -261        A01X+018813Y+116510X0205Y0590R090 S1      
317m7973            VIA   -    MD0080PA01X+035060Y+109184X0160Y         S0      
327m7973            U26   -CF62       A01X+035243Y+109079X0177Y    R180 S1      
317m7973            VIA   -    MD0100PA01X+018813Y+112829X0190Y         S0      
327m7973            J26   -250        A01X+018813Y+112829X0205Y0590R090 S1      
317m7974            VIA   -    MD0080PA01X+035060Y+107270X0160Y         S0      
327m7974            U26   -BY62       A01X+035243Y+107166X0177Y    R180 S1      
317m7974            VIA   -    MD0100PA01X+018813Y+109148X0190Y         S0      
327m7974            J26   -239        A01X+018813Y+109148X0205Y0590R090 S1      
317m7975            VIA   -    MD0080PA01X+034689Y+114286X0160Y         S0      
327m7975            U26   -DB63       A01X+034873Y+114181X0177Y    R180 S1      
317m7975            VIA   -    MD0100PA01X+020427Y+123203X0190Y         S0      
327m7975            J26   -137        A01X+020427Y+123203X0205Y0590R090 S1      
317m7976            VIA   -    MD0080PA01X+034689Y+112373X0160Y         S0      
327m7976            U26   -CT63       A01X+034873Y+112268X0177Y    R180 S1      
317m7976            VIA   -    MD0100PA01X+020427Y+119522X0190Y         S0      
327m7976            J26   -126        A01X+020427Y+119522X0205Y0590R090 S1      
317m7977            VIA   -    MD0080PA01X+034689Y+110459X0160Y         S0      
327m7977            U26   -CK63       A01X+034873Y+110354X0177Y    R180 S1      
317m7977            VIA   -    MD0100PA01X+020427Y+115841X0190Y         S0      
327m7977            J26   -115        A01X+020427Y+115841X0205Y0590R090 S1      
317m7978            VIA   -    MD0080PA01X+034689Y+108546X0160Y         S0      
327m7978            U26   -CD63       A01X+034873Y+108441X0177Y    R180 S1      
317m7978            VIA   -    MD0100PA01X+020427Y+112160X0190Y         S0      
327m7978            J26   -104        A01X+020427Y+112160X0205Y0590R090 S1      
317m7979            VIA   -    MD0080PA01X+034504Y+106951X0160Y         S0      
327m7979            U26   -BW64       A01X+034688Y+106847X0177Y    R180 S1      
317m7979            VIA   -    MD0100PA01X+020427Y+108813X0190Y         S0      
327m7979            J26   -94         A01X+020427Y+108813X0205Y0590R090 S1      
317m7980            VIA   -    MD0080PA01X+035244Y+114605X0160Y         S0      
327m7980            U26   -DC62       A01X+035428Y+114500X0177Y    R180 S1      
317m7980            VIA   -    MD0100PA01X+018813Y+123538X0190Y         S0      
327m7980            J26   -282        A01X+018813Y+123538X0205Y0590R090 S1      
317m7981            VIA   -    MD0080PA01X+035244Y+112692X0160Y         S0      
327m7981            U26   -CU62       A01X+035428Y+112587X0177Y    R180 S1      
317m7981            VIA   -    MD0100PA01X+018813Y+119856X0190Y         S0      
327m7981            J26   -271        A01X+018813Y+119856X0205Y0590R090 S1      
317m7982            VIA   -    MD0080PA01X+035244Y+110778X0160Y         S0      
327m7982            U26   -CL62       A01X+035428Y+110673X0177Y    R180 S1      
317m7982            VIA   -    MD0100PA01X+018813Y+116175X0190Y         S0      
327m7982            J26   -260        A01X+018813Y+116175X0205Y0590R090 S1      
317m7983            VIA   -    MD0080PA01X+035244Y+108865X0160Y         S0      
327m7983            U26   -CE62       A01X+035428Y+108760X0177Y    R180 S1      
317m7983            VIA   -    MD0100PA01X+018813Y+112494X0190Y         S0      
327m7983            J26   -249        A01X+018813Y+112494X0205Y0590R090 S1      
317m7984            VIA   -    MD0080PA01X+035244Y+106951X0160Y         S0      
327m7984            U26   -BW62       A01X+035428Y+106847X0177Y    R180 S1      
317m7984            VIA   -    MD0100PA01X+018813Y+108813X0190Y         S0      
327m7984            J26   -238        A01X+018813Y+108813X0205Y0590R090 S1      
317m7985            VIA   -    MD0080PA01X+034504Y+114605X0160Y         S0      
327m7985            U26   -DC64       A01X+034688Y+114500X0177Y    R180 S1      
317m7985            VIA   -    MD0100PA01X+020427Y+123538X0190Y         S0      
327m7985            J26   -138        A01X+020427Y+123538X0205Y0590R090 S1      
317m7986            VIA   -    MD0080PA01X+034504Y+112692X0160Y         S0      
327m7986            U26   -CU64       A01X+034688Y+112587X0177Y    R180 S1      
317m7986            VIA   -    MD0100PA01X+020427Y+119856X0190Y         S0      
327m7986            J26   -127        A01X+020427Y+119856X0205Y0590R090 S1      
317m7987            VIA   -    MD0080PA01X+034504Y+110778X0160Y         S0      
327m7987            U26   -CL64       A01X+034688Y+110673X0177Y    R180 S1      
317m7987            VIA   -    MD0100PA01X+020427Y+116175X0190Y         S0      
327m7987            J26   -116        A01X+020427Y+116175X0205Y0590R090 S1      
317m7988            VIA   -    MD0080PA01X+034504Y+108865X0160Y         S0      
327m7988            U26   -CE64       A01X+034688Y+108760X0177Y    R180 S1      
317m7988            VIA   -    MD0100PA01X+020427Y+112494X0190Y         S0      
327m7988            J26   -105        A01X+020427Y+112494X0205Y0590R090 S1      
317m7989            VIA   -    MD0080PA01X+035244Y+110140X0160Y         S0      
327m7989            U26   -CJ62       A01X+035428Y+110036X0177Y    R180 S1      
317m7989            VIA   -    MD0100PA01X+020427Y+115171X0190Y         S0      
327m7989            J26   -113        A01X+020427Y+115171X0205Y0590R090 S1      
317m7990            VIA   -    MD0080PA01X+034689Y+109821X0160Y         S0      
327m7990            U26   -CH63       A01X+034873Y+109717X0177Y    R180 S1      
317m7990            VIA   -    MD0100PA01X+020427Y+114502X0190Y         S0      
327m7990            J26   -111        A01X+020427Y+114502X0205Y0590R090 S1      
317m7991            VIA   -    MD0080PA01X+035060Y+109821X0160Y         S0      
327m7991            U26   -CH62       A01X+035243Y+109717X0177Y    R180 S1      
317m7991            VIA   -    MD0100PA01X+018813Y+114168X0190Y         S0      
327m7991            J26   -254        A01X+018813Y+114168X0205Y0590R090 S1      
317m7992            VIA   -    MD0080PA01X+034504Y+109502X0160Y         S0      
327m7992            U26   -CG64       A01X+034688Y+109398X0177Y    R180 S1      
317m7992            VIA   -    MD0100PA01X+018813Y+113498X0190Y         S0      
327m7992            J26   -252        A01X+018813Y+113498X0205Y0590R090 S1      
317m7993            VIA   -    MD0080PA01X+035244Y+109502X0160Y         S0      
327m7993            U26   -CG62       A01X+035428Y+109398X0177Y    R180 S1      
317m7993            VIA   -    MD0100PA01X+020427Y+113833X0190Y         S0      
327m7993            J26   -109        A01X+020427Y+113833X0205Y0590R090 S1      
317m7994            VIA   -    MD0080PA01X+034689Y+109184X0160Y         S0      
327m7994            U26   -CF63       A01X+034873Y+109079X0177Y    R180 S1      
317m7994            VIA   -    MD0100PA01X+020427Y+113164X0190Y         S0      
327m7994            J26   -107        A01X+020427Y+113164X0205Y0590R090 S1      
317m7995            VIA   -    MD0080PA01X+035060Y+108546X0160Y         S0      
327m7995            U26   -CD62       A01X+035243Y+108441X0177Y    R180 S1      
317m7995            VIA   -    MD0100PA01X+018813Y+111825X0190Y         S0      
327m7995            J26   -247        A01X+018813Y+111825X0205Y0590R090 S1      
317m7996            VIA   -    MD0080PA01X+035060Y+115562X0160Y         S0      
327m7996            U26   -DF62       A01X+035243Y+115457X0177Y    R180 S1      
317m7996            VIA   -    MD0100PA01X+018813Y+125211X0190Y         S0      
327m7996            J26   -287        A01X+018813Y+125211X0205Y0590R090 S1      
317m7997            VIA   -    MD0080PA01X+034504Y+115243X0160Y         S0      
327m7997            U26   -DE64       A01X+034688Y+115138X0177Y    R180 S1      
317m7997            VIA   -    MD0100PA01X+018813Y+124542X0190Y         S0      
327m7997            J26   -285        A01X+018813Y+124542X0205Y0590R090 S1      
317m7998            VIA   -    MD0080PA01X+034504Y+108227X0160Y         S0      
327m7998            U26   -CC64       A01X+034688Y+108122X0177Y    R180 S1      
317m7998            VIA   -    MD0100PA01X+018813Y+111156X0190Y         S0      
327m7998            J26   -245        A01X+018813Y+111156X0205Y0590R090 S1      
317m7999            VIA   -    MD0080PA01X+035244Y+115243X0160Y         S0      
327m7999            U26   -DE62       A01X+035428Y+115138X0177Y    R180 S1      
317m7999            VIA   -    MD0100PA01X+020427Y+124876X0190Y         S0      
327m7999            J26   -142        A01X+020427Y+124876X0205Y0590R090 S1      
317m8000            VIA   -    MD0080PA01X+034689Y+114924X0160Y         S0      
327m8000            U26   -DD63       A01X+034873Y+114819X0177Y    R180 S1      
317m8000            VIA   -    MD0100PA01X+020427Y+124207X0190Y         S0      
327m8000            J26   -140        A01X+020427Y+124207X0205Y0590R090 S1      
317m8001            VIA   -    MD0080PA01X+035060Y+114286X0160Y         S0      
327m8001            U26   -DB62       A01X+035243Y+114181X0177Y    R180 S1      
317m8001            VIA   -    MD0100PA01X+018813Y+122868X0190Y         S0      
327m8001            J26   -280        A01X+018813Y+122868X0205Y0590R090 S1      
317m8002            VIA   -    MD0080PA01X+034504Y+113967X0160Y         S0      
327m8002            U26   -DA64       A01X+034688Y+113862X0177Y    R180 S1      
317m8002            VIA   -    MD0100PA01X+018813Y+122199X0190Y         S0      
327m8002            J26   -278        A01X+018813Y+122199X0205Y0590R090 S1      
317m8003            VIA   -    MD0080PA01X+035244Y+113967X0160Y         S0      
327m8003            U26   -DA62       A01X+035428Y+113862X0177Y    R180 S1      
317m8003            VIA   -    MD0100PA01X+020427Y+122534X0190Y         S0      
327m8003            J26   -135        A01X+020427Y+122534X0205Y0590R090 S1      
317m8004            VIA   -    MD0080PA01X+034689Y+113648X0160Y         S0      
327m8004            U26   -CY63       A01X+034873Y+113543X0177Y    R180 S1      
317m8004            VIA   -    MD0100PA01X+020427Y+121864X0190Y         S0      
327m8004            J26   -133        A01X+020427Y+121864X0205Y0590R090 S1      
317m8005            VIA   -    MD0080PA01X+035060Y+113648X0160Y         S0      
327m8005            U26   -CY62       A01X+035243Y+113543X0177Y    R180 S1      
317m8005            VIA   -    MD0100PA01X+018813Y+121530X0190Y         S0      
327m8005            J26   -276        A01X+018813Y+121530X0205Y0590R090 S1      
317m8006            VIA   -    MD0080PA01X+034504Y+113329X0160Y         S0      
327m8006            U26   -CW64       A01X+034688Y+113225X0177Y    R180 S1      
317m8006            VIA   -    MD0100PA01X+018813Y+120860X0190Y         S0      
327m8006            J26   -274        A01X+018813Y+120860X0205Y0590R090 S1      
317m8007            VIA   -    MD0080PA01X+035244Y+113329X0160Y         S0      
327m8007            U26   -CW62       A01X+035428Y+113225X0177Y    R180 S1      
317m8007            VIA   -    MD0100PA01X+020427Y+121195X0190Y         S0      
327m8007            J26   -131        A01X+020427Y+121195X0205Y0590R090 S1      
317m8008            VIA   -    MD0080PA01X+034689Y+113010X0160Y         S0      
327m8008            U26   -CV63       A01X+034873Y+112906X0177Y    R180 S1      
317m8008            VIA   -    MD0100PA01X+020427Y+120526X0190Y         S0      
327m8008            J26   -129        A01X+020427Y+120526X0205Y0590R090 S1      
317m8009            VIA   -    MD0080PA01X+035244Y+108227X0160Y         S0      
327m8009            U26   -CC62       A01X+035428Y+108122X0177Y    R180 S1      
317m8009            VIA   -    MD0100PA01X+020427Y+111490X0190Y         S0      
327m8009            J26   -102        A01X+020427Y+111490X0205Y0590R090 S1      
317m8010            VIA   -    MD0080PA01X+035060Y+112373X0160Y         S0      
327m8010            U26   -CT62       A01X+035243Y+112268X0177Y    R180 S1      
317m8010            VIA   -    MD0100PA01X+018813Y+119187X0190Y         S0      
327m8010            J26   -269        A01X+018813Y+119187X0205Y0590R090 S1      
317m8011            VIA   -    MD0080PA01X+034504Y+112054X0160Y         S0      
327m8011            U26   -CR64       A01X+034688Y+111949X0177Y    R180 S1      
317m8011            VIA   -    MD0100PA01X+018813Y+118518X0190Y         S0      
327m8011            J26   -267        A01X+018813Y+118518X0205Y0590R090 S1      
317m8012            VIA   -    MD0080PA01X+035244Y+112054X0160Y         S0      
327m8012            U26   -CR62       A01X+035428Y+111949X0177Y    R180 S1      
317m8012            VIA   -    MD0100PA01X+020427Y+118852X0190Y         S0      
327m8012            J26   -124        A01X+020427Y+118852X0205Y0590R090 S1      
317m8013            VIA   -    MD0080PA01X+034689Y+111735X0160Y         S0      
327m8013            U26   -CP63       A01X+034873Y+111630X0177Y    R180 S1      
317m8013            VIA   -    MD0100PA01X+020427Y+118183X0190Y         S0      
327m8013            J26   -122        A01X+020427Y+118183X0205Y0590R090 S1      
317m8014            VIA   -    MD0080PA01X+035060Y+111735X0160Y         S0      
327m8014            U26   -CP62       A01X+035243Y+111630X0177Y    R180 S1      
317m8014            VIA   -    MD0100PA01X+018813Y+117849X0190Y         S0      
327m8014            J26   -265        A01X+018813Y+117849X0205Y0590R090 S1      
317m8015            VIA   -    MD0080PA01X+034504Y+111416X0160Y         S0      
327m8015            U26   -CN64       A01X+034688Y+111311X0177Y    R180 S1      
317m8015            VIA   -    MD0100PA01X+018813Y+117179X0190Y         S0      
327m8015            J26   -263        A01X+018813Y+117179X0205Y0590R090 S1      
317m8016            VIA   -    MD0080PA01X+035244Y+111416X0160Y         S0      
327m8016            U26   -CN62       A01X+035428Y+111311X0177Y    R180 S1      
317m8016            VIA   -    MD0100PA01X+020427Y+117514X0190Y         S0      
327m8016            J26   -120        A01X+020427Y+117514X0205Y0590R090 S1      
317m8017            VIA   -    MD0080PA01X+034689Y+111097X0160Y         S0      
327m8017            U26   -CM63       A01X+034873Y+110992X0177Y    R180 S1      
317m8017            VIA   -    MD0100PA01X+020427Y+116845X0190Y         S0      
327m8017            J26   -118        A01X+020427Y+116845X0205Y0590R090 S1      
317m8018            VIA   -    MD0080PA01X+035060Y+110459X0160Y         S0      
327m8018            U26   -CK62       A01X+035243Y+110354X0177Y    R180 S1      
317m8018            VIA   -    MD0100PA01X+018813Y+115506X0190Y         S0      
327m8018            J26   -258        A01X+018813Y+115506X0205Y0590R090 S1      
317m8019            VIA   -    MD0080PA01X+034504Y+110140X0160Y         S0      
327m8019            U26   -CJ64       A01X+034688Y+110036X0177Y    R180 S1      
317m8019            VIA   -    MD0100PA01X+018813Y+114837X0190Y         S0      
327m8019            J26   -256        A01X+018813Y+114837X0205Y0590R090 S1      
317m8020            VIA   -    MD0080PA01X+034689Y+107908X0160Y         S0      
327m8020            U26   -CB63       A01X+034873Y+107803X0177Y    R180 S1      
317m8020            VIA   -    MD0100PA01X+020427Y+110821X0190Y         S0      
327m8020            J26   -100        A01X+020427Y+110821X0205Y0590R090 S1      
317m8021            VIA   -    MD0080PA01X+034504Y+105038X0160Y         S0      
327m8021            U26   -BN64       A01X+034688Y+104933X0177Y    R180 S1      
317m8021            VIA   -    MD0100PA01X+018813Y+105801X0190Y         S0      
327m8021            J26   -229        A01X+018813Y+105801X0205Y0590R090 S1      
317m8022            VIA   -    MD0080PA01X+035060Y+104719X0160Y         S0      
327m8022            U26   -BM62       A01X+035243Y+104614X0177Y    R180 S1      
317m8022            VIA   -    MD0100PA01X+020427Y+105467X0190Y         S0      
327m8022            J26   -84         A01X+020427Y+105467X0205Y0590R090 S1      
317m8023            VIA   -    MD0080PA01X+035060Y+106632X0160Y         S0      
327m8023            U26   -BV62       A01X+035243Y+106528X0177Y    R180 S1      
317m8023            VIA   -    MD0100PA01X+018813Y+108144X0190Y         S0      
327m8023            J26   -236        A01X+018813Y+108144X0205Y0590R090 S1      
317m8024            VIA   -    MD0080PA01X+034504Y+106314X0160Y         S0      
327m8024            U26   -BU64       A01X+034688Y+106209X0177Y    R180 S1      
317m8024            VIA   -    MD0100PA01X+018813Y+107474X0190Y         S0      
327m8024            J26   -234        A01X+018813Y+107474X0205Y0590R090 S1      
317m8025            VIA   -    MD0080PA01X+035244Y+106314X0160Y         S0      
327m8025            U26   -BU62       A01X+035428Y+106209X0177Y    R180 S1      
317m8025            VIA   -    MD0100PA01X+020427Y+107809X0190Y         S0      
327m8025            J26   -91         A01X+020427Y+107809X0205Y0590R090 S1      
317m8026            VIA   -    MD0080PA01X+034689Y+105995X0160Y         S0      
327m8026            U26   -BT63       A01X+034873Y+105890X0177Y    R180 S1      
317m8026            VIA   -    MD0100PA01X+020427Y+107140X0190Y         S0      
327m8026            J26   -89         A01X+020427Y+107140X0205Y0590R090 S1      
317m8027            VIA   -    MD0080PA01X+035060Y+107908X0160Y         S0      
327m8027            U26   -CB62       A01X+035243Y+107803X0177Y    R180 S1      
317m8027            VIA   -    MD0100PA01X+018813Y+110486X0190Y         S0      
327m8027            J26   -243        A01X+018813Y+110486X0205Y0590R090 S1      
317m8028            VIA   -    MD0080PA01X+034504Y+107589X0160Y         S0      
327m8028            U26   -CA64       A01X+034688Y+107484X0177Y    R180 S1      
317m8028            VIA   -    MD0100PA01X+018813Y+109817X0190Y         S0      
327m8028            J26   -241        A01X+018813Y+109817X0205Y0590R090 S1      
317m8029            VIA   -    MD0080PA01X+035244Y+107589X0160Y         S0      
327m8029            U26   -CA62       A01X+035428Y+107484X0177Y    R180 S1      
317m8029            VIA   -    MD0100PA01X+020427Y+110152X0190Y         S0      
327m8029            J26   -98         A01X+020427Y+110152X0205Y0590R090 S1      
317m8030            VIA   -    MD0080PA01X+034689Y+107270X0160Y         S0      
327m8030            U26   -BY63       A01X+034873Y+107166X0177Y    R180 S1      
317m8030            VIA   -    MD0100PA01X+020427Y+109482X0190Y         S0      
327m8030            J26   -96         A01X+020427Y+109482X0205Y0590R090 S1      
317m8031            VIA   -    MD0080PA01X+034689Y+104081X0160Y         S0      
327m8031            U26   -BK63       A01X+034873Y+103976X0177Y    R180 S1      
317m8031            VIA   -    MD0100PA01X+020427Y+104797X0190Y         S0      
327m8031            J26   -82         A01X+020427Y+104797X0205Y0590R090 S1      
317m8032            VIA   -    MD0080PA01X+035060Y+104081X0160Y         S0      
327m8032            U26   -BK62       A01X+035243Y+103976X0177Y    R180 S1      
317m8032            VIA   -    MD0100PA01X+018813Y+104463X0190Y         S0      
327m8032            J26   -225        A01X+018813Y+104463X0205Y0590R090 S1      
317m8033            VIA   -    MD0080PA01X+035244Y+103762X0160Y         S0      
327m8033            U26   -BJ62       A01X+035428Y+103658X0177Y    R180 S1      
317m8033            VIA   -    MD0100PA01X+020427Y+104128X0190Y         S0      
327m8033            J26   -80         A01X+020427Y+104128X0205Y0590R090 S1      
317m8034            VIA   -    MD0080PA01X+034504Y+103762X0160Y         S0      
327m8034            U26   -BJ64       A01X+034688Y+103658X0177Y    R180 S1      
317m8034            VIA   -    MD0100PA01X+018813Y+103793X0190Y         S0      
327m8034            J26   -223        A01X+018813Y+103793X0205Y0590R090 S1      
317m8035            VIA   -    MD0080PA01X+034689Y+103443X0160Y         S0      
327m8035            U26   -BH63       A01X+034873Y+103339X0177Y    R180 S1      
317m8035            VIA   -    MD0100PA01X+020427Y+103459X0190Y         S0      
327m8035            J26   -78         A01X+020427Y+103459X0205Y0590R090 S1      
317m8036            VIA   -    MD0080PA01X+035060Y+103443X0160Y         S0      
327m8036            U26   -BH62       A01X+035243Y+103339X0177Y    R180 S1      
317m8036            VIA   -    MD0100PA01X+018813Y+103124X0190Y         S0      
327m8036            J26   -221        A01X+018813Y+103124X0205Y0590R090 S1      
317m8037            VIA   -    MD0080PA01X+035244Y+103124X0160Y         S0      
327m8037            U26   -BG62       A01X+035428Y+103020X0177Y    R180 S1      
317m8037            VIA   -    MD0100PA01X+020427Y+102790X0190Y         S0      
327m8037            J26   -76         A01X+020427Y+102790X0205Y0590R090 S1      
317m8038            VIA   -    MD0080PA01X+035244Y+105038X0160Y         S0      
327m8038            U26   -BN62       A01X+035428Y+104933X0177Y    R180 S1      
317m8038            VIA   -    MD0100PA01X+020427Y+106136X0190Y         S0      
327m8038            J26   -86         A01X+020427Y+106136X0205Y0590R090 S1      
317m8039            VIA   -    MD0080PA01X+035126Y+100718X0160Y    R180 S0      
327m8039            U26   -BC62       A01X+035310Y+100823X0177Y    R180 S1      
317m8039            VIA   -    MD0100PA01X+020427Y+100112X0190Y         S0      
327m8039            J26   -74         A01X+020427Y+100112X0205Y0590R090 S1      
317m8040            VIA   -    MD0080PA01X+035126Y+097529X0160Y    R180 S0      
327m8040            U26   -AN62       A01X+035310Y+097634X0177Y    R180 S1      
317m8040            VIA   -    MD0100PA01X+018813Y+094423X0190Y         S0      
327m8040            J26   -201        A01X+018813Y+094423X0205Y0590R090 S1      
317m8041            VIA   -    MD0080PA01X+035126Y+095616X0160Y    R180 S0      
327m8041            U26   -AG62       A01X+035310Y+095721X0177Y    R180 S1      
317m8041            VIA   -    MD0100PA01X+018813Y+090742X0190Y         S0      
327m8041            J26   -190        A01X+018813Y+090742X0205Y0590R090 S1      
317m8042            VIA   -    MD0080PA01X+035126Y+093702X0160Y    R180 S0      
327m8042            U26   -AA62       A01X+035310Y+093807X0177Y    R180 S1      
317m8042            VIA   -    MD0100PA01X+018813Y+087061X0190Y         S0      
327m8042            J26   -179        A01X+018813Y+087061X0205Y0590R090 S1      
317m8043            VIA   -    MD0080PA01X+035126Y+091789X0160Y    R180 S0      
327m8043            U26   -R62        A01X+035310Y+091894X0177Y    R180 S1      
317m8043            VIA   -    MD0100PA01X+018813Y+083380X0190Y         S0      
327m8043            J26   -168        A01X+018813Y+083380X0205Y0590R090 S1      
317m8044            VIA   -    MD0080PA01X+035126Y+089876X0160Y    R180 S0      
327m8044            U26   -J62        A01X+035310Y+089980X0177Y    R180 S1      
317m8044            VIA   -    MD0100PA01X+018813Y+079699X0190Y         S0      
327m8044            J26   -157        A01X+018813Y+079699X0205Y0590R090 S1      
317m8045            VIA   -    MD0080PA01X+034386Y+096892X0160Y    R180 S0      
327m8045            U26   -AL64       A01X+034570Y+096996X0177Y    R180 S1      
317m8045            VIA   -    MD0100PA01X+020427Y+093754X0190Y         S0      
327m8045            J26   -55         A01X+020427Y+093754X0205Y0590R090 S1      
317m8046            VIA   -    MD0080PA01X+034386Y+094978X0160Y    R180 S0      
327m8046            U26   -AE64       A01X+034570Y+095083X0177Y    R180 S1      
317m8046            VIA   -    MD0100PA01X+020427Y+090073X0190Y         S0      
327m8046            J26   -44         A01X+020427Y+090073X0205Y0590R090 S1      
317m8047            VIA   -    MD0080PA01X+034386Y+093065X0160Y    R180 S0      
327m8047            U26   -W64        A01X+034570Y+093169X0177Y    R180 S1      
317m8047            VIA   -    MD0100PA01X+020427Y+086392X0190Y         S0      
327m8047            J26   -33         A01X+020427Y+086392X0205Y0590R090 S1      
317m8048            VIA   -    MD0080PA01X+034386Y+091151X0160Y    R180 S0      
327m8048            U26   -N64        A01X+034570Y+091256X0177Y    R180 S1      
317m8048            VIA   -    MD0100PA01X+020427Y+082711X0190Y         S0      
327m8048            J26   -22         A01X+020427Y+082711X0205Y0590R090 S1      
317m8049            VIA   -    MD0080PA01X+034386Y+089238X0160Y    R180 S0      
327m8049            U26   -G64        A01X+034570Y+089343X0177Y    R180 S1      
317m8049            VIA   -    MD0100PA01X+020427Y+079030X0190Y         S0      
327m8049            J26   -11         A01X+020427Y+079030X0205Y0590R090 S1      
317m8050            VIA   -    MD0080PA01X+034941Y+097210X0160Y    R180 S0      
327m8050            U26   -AM62       A01X+035125Y+097315X0177Y    R180 S1      
317m8050            VIA   -    MD0100PA01X+018813Y+094089X0190Y         S0      
327m8050            J26   -200        A01X+018813Y+094089X0205Y0590R090 S1      
317m8051            VIA   -    MD0080PA01X+034941Y+095297X0160Y    R180 S0      
327m8051            U26   -AF62       A01X+035125Y+095402X0177Y    R180 S1      
317m8051            VIA   -    MD0100PA01X+018813Y+090408X0190Y         S0      
327m8051            J26   -189        A01X+018813Y+090408X0205Y0590R090 S1      
317m8052            VIA   -    MD0080PA01X+034941Y+093384X0160Y    R180 S0      
327m8052            U26   -Y62        A01X+035125Y+093488X0177Y    R180 S1      
317m8052            VIA   -    MD0100PA01X+018813Y+086726X0190Y         S0      
327m8052            J26   -178        A01X+018813Y+086726X0205Y0590R090 S1      
317m8053            VIA   -    MD0080PA01X+034941Y+091470X0160Y    R180 S0      
327m8053            U26   -P62        A01X+035125Y+091575X0177Y    R180 S1      
317m8053            VIA   -    MD0100PA01X+018813Y+083045X0190Y         S0      
327m8053            J26   -167        A01X+018813Y+083045X0205Y0590R090 S1      
317m8054            VIA   -    MD0080PA01X+034941Y+089557X0160Y    R180 S0      
327m8054            U26   -H62        A01X+035125Y+089662X0177Y    R180 S1      
317m8054            VIA   -    MD0100PA01X+018813Y+079364X0190Y         S0      
327m8054            J26   -156        A01X+018813Y+079364X0205Y0590R090 S1      
317m8055            VIA   -    MD0080PA01X+034571Y+097210X0160Y    R180 S0      
327m8055            U26   -AM63       A01X+034755Y+097315X0177Y    R180 S1      
317m8055            VIA   -    MD0100PA01X+020427Y+094089X0190Y         S0      
327m8055            J26   -56         A01X+020427Y+094089X0205Y0590R090 S1      
317m8056            VIA   -    MD0080PA01X+034571Y+095297X0160Y    R180 S0      
327m8056            U26   -AF63       A01X+034755Y+095402X0177Y    R180 S1      
317m8056            VIA   -    MD0100PA01X+020427Y+090408X0190Y         S0      
327m8056            J26   -45         A01X+020427Y+090408X0205Y0590R090 S1      
317m8057            VIA   -    MD0080PA01X+034571Y+093384X0160Y    R180 S0      
327m8057            U26   -Y63        A01X+034755Y+093488X0177Y    R180 S1      
317m8057            VIA   -    MD0100PA01X+020427Y+086726X0190Y         S0      
327m8057            J26   -34         A01X+020427Y+086726X0205Y0590R090 S1      
317m8058            VIA   -    MD0080PA01X+034571Y+091470X0160Y    R180 S0      
327m8058            U26   -P63        A01X+034755Y+091575X0177Y    R180 S1      
317m8058            VIA   -    MD0100PA01X+020427Y+083045X0190Y         S0      
327m8058            J26   -23         A01X+020427Y+083045X0205Y0590R090 S1      
317m8059            VIA   -    MD0080PA01X+034571Y+089557X0160Y    R180 S0      
327m8059            U26   -H63        A01X+034755Y+089662X0177Y    R180 S1      
317m8059            VIA   -    MD0100PA01X+020427Y+079364X0190Y         S0      
327m8059            J26   -12         A01X+020427Y+079364X0205Y0590R090 S1      
317m8060            VIA   -    MD0080PA01X+034941Y+090832X0160Y    R180 S0      
327m8060            U26   -M62        A01X+035125Y+090937X0177Y    R180 S1      
317m8060            VIA   -    MD0100PA01X+020427Y+082042X0190Y         S0      
327m8060            J26   -20         A01X+020427Y+082042X0205Y0590R090 S1      
317m8061            VIA   -    MD0080PA01X+034386Y+090514X0160Y    R180 S0      
327m8061            U26   -L64        A01X+034570Y+090618X0177Y    R180 S1      
317m8061            VIA   -    MD0100PA01X+020427Y+081372X0190Y         S0      
327m8061            J26   -18         A01X+020427Y+081372X0205Y0590R090 S1      
317m8062            VIA   -    MD0080PA01X+035126Y+090514X0160Y    R180 S0      
327m8062            U26   -L62        A01X+035310Y+090618X0177Y    R180 S1      
317m8062            VIA   -    MD0100PA01X+018813Y+081038X0190Y         S0      
327m8062            J26   -161        A01X+018813Y+081038X0205Y0590R090 S1      
317m8063            VIA   -    MD0080PA01X+034571Y+090195X0160Y    R180 S0      
327m8063            U26   -K63        A01X+034755Y+090299X0177Y    R180 S1      
317m8063            VIA   -    MD0100PA01X+018813Y+080368X0190Y         S0      
327m8063            J26   -159        A01X+018813Y+080368X0205Y0590R090 S1      
317m8064            VIA   -    MD0080PA01X+034941Y+090195X0160Y    R180 S0      
327m8064            U26   -K62        A01X+035125Y+090299X0177Y    R180 S1      
317m8064            VIA   -    MD0100PA01X+020427Y+080703X0190Y         S0      
327m8064            J26   -16         A01X+020427Y+080703X0205Y0590R090 S1      
317m8065            VIA   -    MD0080PA01X+034386Y+089876X0160Y    R180 S0      
327m8065            U26   -J64        A01X+034570Y+089980X0177Y    R180 S1      
317m8065            VIA   -    MD0100PA01X+020427Y+080034X0190Y         S0      
327m8065            J26   -14         A01X+020427Y+080034X0205Y0590R090 S1      
317m8066            VIA   -    MD0080PA01X+035126Y+089238X0160Y    R180 S0      
327m8066            U26   -G62        A01X+035310Y+089343X0177Y    R180 S1      
317m8066            VIA   -    MD0100PA01X+018813Y+078695X0190Y         S0      
327m8066            J26   -154        A01X+018813Y+078695X0205Y0590R090 S1      
317m8067            VIA   -    MD0080PA01X+035126Y+096254X0160Y    R180 S0      
327m8067            U26   -AJ62       A01X+035310Y+096358X0177Y    R180 S1      
317m8067            VIA   -    MD0100PA01X+018813Y+092081X0190Y         S0      
327m8067            J26   -194        A01X+018813Y+092081X0205Y0590R090 S1      
317m8068            VIA   -    MD0080PA01X+034571Y+095935X0160Y    R180 S0      
327m8068            U26   -AH63       A01X+034755Y+096040X0177Y    R180 S1      
317m8068            VIA   -    MD0100PA01X+018813Y+091412X0190Y         S0      
327m8068            J26   -192        A01X+018813Y+091412X0205Y0590R090 S1      
317m8069            VIA   -    MD0080PA01X+034571Y+088919X0160Y    R180 S0      
327m8069            U26   -F63        A01X+034755Y+089024X0177Y    R180 S1      
317m8069            VIA   -    MD0100PA01X+018813Y+078026X0190Y         S0      
327m8069            J26   -152        A01X+018813Y+078026X0205Y0590R090 S1      
317m8070            VIA   -    MD0080PA01X+034941Y+095935X0160Y    R180 S0      
327m8070            U26   -AH62       A01X+035125Y+096040X0177Y    R180 S1      
317m8070            VIA   -    MD0100PA01X+020427Y+091746X0190Y         S0      
327m8070            J26   -49         A01X+020427Y+091746X0205Y0590R090 S1      
317m8071            VIA   -    MD0080PA01X+034386Y+095616X0160Y    R180 S0      
327m8071            U26   -AG64       A01X+034570Y+095721X0177Y    R180 S1      
317m8071            VIA   -    MD0100PA01X+020427Y+091077X0190Y         S0      
327m8071            J26   -47         A01X+020427Y+091077X0205Y0590R090 S1      
317m8072            VIA   -    MD0080PA01X+035126Y+094978X0160Y    R180 S0      
327m8072            U26   -AE62       A01X+035310Y+095083X0177Y    R180 S1      
317m8072            VIA   -    MD0100PA01X+018813Y+089738X0190Y         S0      
327m8072            J26   -187        A01X+018813Y+089738X0205Y0590R090 S1      
317m8073            VIA   -    MD0080PA01X+034571Y+094659X0160Y    R180 S0      
327m8073            U26   -AD63       A01X+034755Y+094764X0177Y    R180 S1      
317m8073            VIA   -    MD0100PA01X+018813Y+089069X0190Y         S0      
327m8073            J26   -185        A01X+018813Y+089069X0205Y0590R090 S1      
317m8074            VIA   -    MD0080PA01X+034941Y+094659X0160Y    R180 S0      
327m8074            U26   -AD62       A01X+035125Y+094764X0177Y    R180 S1      
317m8074            VIA   -    MD0100PA01X+020427Y+089404X0190Y         S0      
327m8074            J26   -42         A01X+020427Y+089404X0205Y0590R090 S1      
317m8075            VIA   -    MD0080PA01X+034386Y+094340X0160Y    R180 S0      
327m8075            U26   -AC64       A01X+034570Y+094445X0177Y    R180 S1      
317m8075            VIA   -    MD0100PA01X+020427Y+088734X0190Y         S0      
327m8075            J26   -40         A01X+020427Y+088734X0205Y0590R090 S1      
317m8076            VIA   -    MD0080PA01X+035126Y+094340X0160Y    R180 S0      
327m8076            U26   -AC62       A01X+035310Y+094445X0177Y    R180 S1      
317m8076            VIA   -    MD0100PA01X+018813Y+088400X0190Y         S0      
327m8076            J26   -183        A01X+018813Y+088400X0205Y0590R090 S1      
317m8077            VIA   -    MD0080PA01X+034571Y+094021X0160Y    R180 S0      
327m8077            U26   -AB63       A01X+034755Y+094126X0177Y    R180 S1      
317m8077            VIA   -    MD0100PA01X+018813Y+087730X0190Y         S0      
327m8077            J26   -181        A01X+018813Y+087730X0205Y0590R090 S1      
317m8078            VIA   -    MD0080PA01X+034941Y+094021X0160Y    R180 S0      
327m8078            U26   -AB62       A01X+035125Y+094126X0177Y    R180 S1      
317m8078            VIA   -    MD0100PA01X+020427Y+088065X0190Y         S0      
327m8078            J26   -38         A01X+020427Y+088065X0205Y0590R090 S1      
317m8079            VIA   -    MD0080PA01X+034386Y+093702X0160Y    R180 S0      
327m8079            U26   -AA64       A01X+034570Y+093807X0177Y    R180 S1      
317m8079            VIA   -    MD0100PA01X+020427Y+087396X0190Y         S0      
327m8079            J26   -36         A01X+020427Y+087396X0205Y0590R090 S1      
317m8080            VIA   -    MD0080PA01X+034941Y+088919X0160Y    R180 S0      
327m8080            U26   -F62        A01X+035125Y+089024X0177Y    R180 S1      
317m8080            VIA   -    MD0100PA01X+020427Y+078360X0190Y         S0      
327m8080            J26   -9          A01X+020427Y+078360X0205Y0590R090 S1      
317m8081            VIA   -    MD0080PA01X+035126Y+093065X0160Y    R180 S0      
327m8081            U26   -W62        A01X+035310Y+093169X0177Y    R180 S1      
317m8081            VIA   -    MD0100PA01X+018813Y+086057X0190Y         S0      
327m8081            J26   -176        A01X+018813Y+086057X0205Y0590R090 S1      
317m8082            VIA   -    MD0080PA01X+034571Y+092746X0160Y    R180 S0      
327m8082            U26   -V63        A01X+034755Y+092850X0177Y    R180 S1      
317m8082            VIA   -    MD0100PA01X+018813Y+085388X0190Y         S0      
327m8082            J26   -174        A01X+018813Y+085388X0205Y0590R090 S1      
317m8083            VIA   -    MD0080PA01X+034941Y+092746X0160Y    R180 S0      
327m8083            U26   -V62        A01X+035125Y+092850X0177Y    R180 S1      
317m8083            VIA   -    MD0100PA01X+020427Y+085723X0190Y         S0      
327m8083            J26   -31         A01X+020427Y+085723X0205Y0590R090 S1      
317m8084            VIA   -    MD0080PA01X+034386Y+092427X0160Y    R180 S0      
327m8084            U26   -U64        A01X+034570Y+092532X0177Y    R180 S1      
317m8084            VIA   -    MD0100PA01X+020427Y+085053X0190Y         S0      
327m8084            J26   -29         A01X+020427Y+085053X0205Y0590R090 S1      
317m8085            VIA   -    MD0080PA01X+035126Y+092427X0160Y    R180 S0      
327m8085            U26   -U62        A01X+035310Y+092532X0177Y    R180 S1      
317m8085            VIA   -    MD0100PA01X+018813Y+084719X0190Y         S0      
327m8085            J26   -172        A01X+018813Y+084719X0205Y0590R090 S1      
317m8086            VIA   -    MD0080PA01X+034571Y+092108X0160Y    R180 S0      
327m8086            U26   -T63        A01X+034755Y+092213X0177Y    R180 S1      
317m8086            VIA   -    MD0100PA01X+018813Y+084049X0190Y         S0      
327m8086            J26   -170        A01X+018813Y+084049X0205Y0590R090 S1      
317m8087            VIA   -    MD0080PA01X+034941Y+092108X0160Y    R180 S0      
327m8087            U26   -T62        A01X+035125Y+092213X0177Y    R180 S1      
317m8087            VIA   -    MD0100PA01X+020427Y+084384X0190Y         S0      
327m8087            J26   -27         A01X+020427Y+084384X0205Y0590R090 S1      
317m8088            VIA   -    MD0080PA01X+034386Y+091789X0160Y    R180 S0      
327m8088            U26   -R64        A01X+034570Y+091894X0177Y    R180 S1      
317m8088            VIA   -    MD0100PA01X+020427Y+083715X0190Y         S0      
327m8088            J26   -25         A01X+020427Y+083715X0205Y0590R090 S1      
317m8089            VIA   -    MD0080PA01X+035126Y+091151X0160Y    R180 S0      
327m8089            U26   -N62        A01X+035310Y+091256X0177Y    R180 S1      
317m8089            VIA   -    MD0100PA01X+018813Y+082376X0190Y         S0      
327m8089            J26   -165        A01X+018813Y+082376X0205Y0590R090 S1      
317m8090            VIA   -    MD0080PA01X+034571Y+090832X0160Y    R180 S0      
327m8090            U26   -M63        A01X+034755Y+090937X0177Y    R180 S1      
317m8090            VIA   -    MD0100PA01X+018813Y+081707X0190Y         S0      
327m8090            J26   -163        A01X+018813Y+081707X0205Y0590R090 S1      
317m8091            VIA   -    MD0080PA01X+034386Y+088600X0160Y    R180 S0      
327m8091            U26   -E64        A01X+034570Y+088705X0177Y    R180 S1      
317m8091            VIA   -    MD0100PA01X+020427Y+077691X0190Y         S0      
327m8091            J26   -7          A01X+020427Y+077691X0205Y0590R090 S1      
317m8092            VIA   -    MD0080PA01X+035126Y+099443X0160Y    R180 S0      
327m8092            U26   -AW62       A01X+035310Y+099547X0177Y    R180 S1      
317m8092            VIA   -    MD0100PA01X+018813Y+097100X0190Y         S0      
327m8092            J26   -209        A01X+018813Y+097100X0205Y0590R090 S1      
317m8093            VIA   -    MD0080PA01X+034571Y+099124X0160Y    R180 S0      
327m8093            U26   -AV63       A01X+034755Y+099228X0177Y    R180 S1      
317m8093            VIA   -    MD0100PA01X+020427Y+096766X0190Y         S0      
327m8093            J26   -64         A01X+020427Y+096766X0205Y0590R090 S1      
317m8094            VIA   -    MD0080PA01X+035126Y+098167X0160Y    R180 S0      
327m8094            U26   -AR62       A01X+035310Y+098272X0177Y    R180 S1      
317m8094            VIA   -    MD0100PA01X+018813Y+095762X0190Y         S0      
327m8094            J26   -205        A01X+018813Y+095762X0205Y0590R090 S1      
317m8095            VIA   -    MD0080PA01X+034571Y+097848X0160Y    R180 S0      
327m8095            U26   -AP63       A01X+034755Y+097953X0177Y    R180 S1      
317m8095            VIA   -    MD0100PA01X+018813Y+095093X0190Y         S0      
327m8095            J26   -203        A01X+018813Y+095093X0205Y0590R090 S1      
317m8096            VIA   -    MD0080PA01X+034941Y+097848X0160Y    R180 S0      
327m8096            U26   -AP62       A01X+035125Y+097953X0177Y    R180 S1      
317m8096            VIA   -    MD0100PA01X+020427Y+095427X0190Y         S0      
327m8096            J26   -60         A01X+020427Y+095427X0205Y0590R090 S1      
317m8097            VIA   -    MD0080PA01X+034386Y+097529X0160Y    R180 S0      
327m8097            U26   -AN64       A01X+034570Y+097634X0177Y    R180 S1      
317m8097            VIA   -    MD0100PA01X+020427Y+094758X0190Y         S0      
327m8097            J26   -58         A01X+020427Y+094758X0205Y0590R090 S1      
317m8098            VIA   -    MD0080PA01X+035126Y+096892X0160Y    R180 S0      
327m8098            U26   -AL62       A01X+035310Y+096996X0177Y    R180 S1      
317m8098            VIA   -    MD0100PA01X+018813Y+093419X0190Y         S0      
327m8098            J26   -198        A01X+018813Y+093419X0205Y0590R090 S1      
317m8099            VIA   -    MD0080PA01X+034571Y+096573X0160Y    R180 S0      
327m8099            U26   -AK63       A01X+034755Y+096677X0177Y    R180 S1      
317m8099            VIA   -    MD0100PA01X+018813Y+092750X0190Y         S0      
327m8099            J26   -196        A01X+018813Y+092750X0205Y0590R090 S1      
317m8100            VIA   -    MD0080PA01X+034941Y+096573X0160Y    R180 S0      
327m8100            U26   -AK62       A01X+035125Y+096677X0177Y    R180 S1      
317m8100            VIA   -    MD0100PA01X+020427Y+093085X0190Y         S0      
327m8100            J26   -53         A01X+020427Y+093085X0205Y0590R090 S1      
317m8101            VIA   -    MD0080PA01X+034386Y+096254X0160Y    R180 S0      
327m8101            U26   -AJ64       A01X+034570Y+096358X0177Y    R180 S1      
317m8101            VIA   -    MD0100PA01X+020427Y+092416X0190Y         S0      
327m8101            J26   -51         A01X+020427Y+092416X0205Y0590R090 S1      
317m8102            VIA   -    MD0080PA01X+034941Y+100399X0160Y    R180 S0      
327m8102            U26   -BB62       A01X+035125Y+100504X0177Y    R180 S1      
317m8102            VIA   -    MD0100PA01X+020427Y+099443X0190Y         S0      
327m8102            J26   -72         A01X+020427Y+099443X0205Y0590R090 S1      
317m8103            VIA   -    MD0080PA01X+034571Y+100399X0160Y    R180 S0      
327m8103            U26   -BB63       A01X+034755Y+100504X0177Y    R180 S1      
317m8103            VIA   -    MD0100PA01X+018813Y+099108X0190Y         S0      
327m8103            J26   -215        A01X+018813Y+099108X0205Y0590R090 S1      
317m8104            VIA   -    MD0080PA01X+034386Y+100080X0160Y    R180 S0      
327m8104            U26   -BA64       A01X+034570Y+100185X0177Y    R180 S1      
317m8104            VIA   -    MD0100PA01X+020427Y+098774X0190Y         S0      
327m8104            J26   -70         A01X+020427Y+098774X0205Y0590R090 S1      
317m8105            VIA   -    MD0080PA01X+035126Y+100080X0160Y    R180 S0      
327m8105            U26   -BA62       A01X+035310Y+100185X0177Y    R180 S1      
317m8105            VIA   -    MD0100PA01X+018813Y+098439X0190Y         S0      
327m8105            J26   -213        A01X+018813Y+098439X0205Y0590R090 S1      
317m8106            VIA   -    MD0080PA01X+034941Y+099762X0160Y    R180 S0      
327m8106            U26   -AY62       A01X+035125Y+099866X0177Y    R180 S1      
317m8106            VIA   -    MD0100PA01X+020427Y+098104X0190Y         S0      
327m8106            J26   -68         A01X+020427Y+098104X0205Y0590R090 S1      
317m8107            VIA   -    MD0080PA01X+034571Y+099762X0160Y    R180 S0      
327m8107            U26   -AY63       A01X+034755Y+099866X0177Y    R180 S1      
317m8107            VIA   -    MD0100PA01X+018813Y+097770X0190Y         S0      
327m8107            J26   -211        A01X+018813Y+097770X0205Y0590R090 S1      
317m8108            VIA   -    MD0080PA01X+034386Y+099443X0160Y    R180 S0      
327m8108            U26   -AW64       A01X+034570Y+099547X0177Y    R180 S1      
317m8108            VIA   -    MD0100PA01X+020427Y+097435X0190Y         S0      
327m8108            J26   -66         A01X+020427Y+097435X0205Y0590R090 S1      
317m8109            VIA   -    MD0080PA01X+035126Y+098805X0160Y    R180 S0      
327m8109            U26   -AU62       A01X+035310Y+098910X0177Y    R180 S1      
317m8109            VIA   -    MD0100PA01X+018813Y+096431X0190Y         S0      
327m8109            J26   -207        A01X+018813Y+096431X0205Y0590R090 S1      
317m8110            VIA   -    MD0080PA01X+034386Y+100718X0160Y    R180 S0      
327m8110            U26   -BC64       A01X+034570Y+100823X0177Y    R180 S1      
317m8110            VIA   -    MD0100PA01X+018813Y+099778X0190Y         S0      
327m8110            J26   -217        A01X+018813Y+099778X0205Y0590R090 S1      
317m8111            VIA   -    MD0080PA01X+034571Y+101037X0160Y    R180 S0      
327m8111            U26   -BD63       A01X+034755Y+101142X0177Y    R180 S1      
317m8111            VIA   -    MD0100PA01X+018813Y+100112X0190Y         S0      
327m8111            J26   -218        A01X+018813Y+100112X0205Y0590R090 S1      
317m8112            VIA   -    MD0080PA01X+034941Y+098486X0160Y    R180 S0      
327m8112            U26   -AT62       A01X+035125Y+098591X0177Y    R180 S1      
317m8112            VIA   -    MD0100PA18X+020977Y+096097X0190Y         S0      
327m8112            R501  -2          A18X+020977Y+096097X0198Y0197R180 S2      
327m8113            J26   -62         A01X+020427Y+096097X0205Y0590R090 S1      
317m8113            VIA   -    MD0100PA00X+020427Y+096097X0190Y         S0      
327m8113            R501  -1          A18X+020662Y+096097X0198Y0197R180 S2      
317m8114            VIA   -    MD0080PA01X+132304Y+105357X0160Y         S0      
327m8114            U25   -BP63       A01X+132487Y+105252X0177Y    R180 S1      
317m8114            VIA   -    MD0100PA01X+118041Y+106470X0190Y         S0      
327m8114            J15   -87         A01X+118041Y+106470X0205Y0590R090 S1      
317m8115            VIA   -    MD0080PA01X+132118Y+104400X0160Y         S0      
327m8115            U25   -BL64       A01X+132302Y+104295X0177Y    R180 S1      
317m8115            VIA   -    MD0100PA01X+116427Y+105132X0190Y         S0      
327m8115            J15   -227        A01X+116427Y+105132X0205Y0590R090 S1      
317m8116            VIA   -    MD0080PA01X+132304Y+106632X0160Y         S0      
327m8116            U25   -BV63       A01X+132487Y+106528X0177Y    R180 S1      
317m8116            VIA   -    MD0100PA01X+118041Y+108478X0190Y         S0      
327m8116            J15   -93         A01X+118041Y+108478X0205Y0590R090 S1      
317m8117            VIA   -    MD0080PA01X+132674Y+114924X0160Y         S0      
327m8117            U25   -DD62       A01X+132858Y+114819X0177Y    R180 S1      
317m8117            VIA   -    MD0100PA01X+116427Y+123872X0190Y         S0      
327m8117            J15   -283        A01X+116427Y+123872X0205Y0590R090 S1      
317m8118            VIA   -    MD0080PA01X+132674Y+113010X0160Y         S0      
327m8118            U25   -CV62       A01X+132858Y+112906X0177Y    R180 S1      
317m8118            VIA   -    MD0100PA01X+116427Y+120191X0190Y         S0      
327m8118            J15   -272        A01X+116427Y+120191X0205Y0590R090 S1      
317m8119            VIA   -    MD0080PA01X+132674Y+111097X0160Y         S0      
327m8119            U25   -CM62       A01X+132858Y+110992X0177Y    R180 S1      
317m8119            VIA   -    MD0100PA01X+116427Y+116510X0190Y         S0      
327m8119            J15   -261        A01X+116427Y+116510X0205Y0590R090 S1      
317m8120            VIA   -    MD0080PA01X+132674Y+109184X0160Y         S0      
327m8120            U25   -CF62       A01X+132858Y+109079X0177Y    R180 S1      
317m8120            VIA   -    MD0100PA01X+116427Y+112829X0190Y         S0      
327m8120            J15   -250        A01X+116427Y+112829X0205Y0590R090 S1      
317m8121            VIA   -    MD0080PA01X+132674Y+107270X0160Y         S0      
327m8121            U25   -BY62       A01X+132858Y+107165X0177Y    R180 S1      
317m8121            VIA   -    MD0100PA01X+116427Y+109148X0190Y         S0      
327m8121            J15   -239        A01X+116427Y+109148X0205Y0590R090 S1      
317m8122            VIA   -    MD0080PA01X+132304Y+114286X0160Y         S0      
327m8122            U25   -DB63       A01X+132487Y+114181X0177Y    R180 S1      
317m8122            VIA   -    MD0100PA01X+118041Y+123203X0190Y         S0      
327m8122            J15   -137        A01X+118041Y+123203X0205Y0590R090 S1      
317m8123            VIA   -    MD0080PA01X+132304Y+112372X0160Y         S0      
327m8123            U25   -CT63       A01X+132487Y+112268X0177Y    R180 S1      
317m8123            VIA   -    MD0100PA01X+118041Y+119522X0190Y         S0      
327m8123            J15   -126        A01X+118041Y+119522X0205Y0590R090 S1      
317m8124            VIA   -    MD0080PA01X+132304Y+110459X0160Y         S0      
327m8124            U25   -CK63       A01X+132487Y+110354X0177Y    R180 S1      
317m8124            VIA   -    MD0100PA01X+118041Y+115841X0190Y         S0      
327m8124            J15   -115        A01X+118041Y+115841X0205Y0590R090 S1      
317m8125            VIA   -    MD0080PA01X+132304Y+108546X0160Y         S0      
327m8125            U25   -CD63       A01X+132487Y+108441X0177Y    R180 S1      
317m8125            VIA   -    MD0100PA01X+118041Y+112160X0190Y         S0      
327m8125            J15   -104        A01X+118041Y+112160X0205Y0590R090 S1      
317m8126            VIA   -    MD0080PA01X+132118Y+106951X0160Y         S0      
327m8126            U25   -BW64       A01X+132302Y+106846X0177Y    R180 S1      
317m8126            VIA   -    MD0100PA01X+118041Y+108813X0190Y         S0      
327m8126            J15   -94         A01X+118041Y+108813X0205Y0590R090 S1      
317m8127            VIA   -    MD0080PA01X+132859Y+114605X0160Y         S0      
327m8127            U25   -DC62       A01X+133042Y+114500X0177Y    R180 S1      
317m8127            VIA   -    MD0100PA01X+116427Y+123537X0190Y         S0      
327m8127            J15   -282        A01X+116427Y+123537X0205Y0590R090 S1      
317m8128            VIA   -    MD0080PA01X+132859Y+112691X0160Y         S0      
327m8128            U25   -CU62       A01X+133042Y+112587X0177Y    R180 S1      
317m8128            VIA   -    MD0100PA01X+116427Y+119856X0190Y         S0      
327m8128            J15   -271        A01X+116427Y+119856X0205Y0590R090 S1      
317m8129            VIA   -    MD0080PA01X+132859Y+110778X0160Y         S0      
327m8129            U25   -CL62       A01X+133042Y+110673X0177Y    R180 S1      
317m8129            VIA   -    MD0100PA01X+116427Y+116175X0190Y         S0      
327m8129            J15   -260        A01X+116427Y+116175X0205Y0590R090 S1      
317m8130            VIA   -    MD0080PA01X+132859Y+108865X0160Y         S0      
327m8130            U25   -CE62       A01X+133042Y+108760X0177Y    R180 S1      
317m8130            VIA   -    MD0100PA01X+116427Y+112494X0190Y         S0      
327m8130            J15   -249        A01X+116427Y+112494X0205Y0590R090 S1      
317m8131            VIA   -    MD0080PA01X+132859Y+106951X0160Y         S0      
327m8131            U25   -BW62       A01X+133042Y+106846X0177Y    R180 S1      
317m8131            VIA   -    MD0100PA01X+116427Y+108813X0190Y         S0      
327m8131            J15   -238        A01X+116427Y+108813X0205Y0590R090 S1      
317m8132            VIA   -    MD0080PA01X+132118Y+114605X0160Y         S0      
327m8132            U25   -DC64       A01X+132302Y+114500X0177Y    R180 S1      
317m8132            VIA   -    MD0100PA01X+118041Y+123537X0190Y         S0      
327m8132            J15   -138        A01X+118041Y+123537X0205Y0590R090 S1      
317m8133            VIA   -    MD0080PA01X+132118Y+112691X0160Y         S0      
327m8133            U25   -CU64       A01X+132302Y+112587X0177Y    R180 S1      
317m8133            VIA   -    MD0100PA01X+118041Y+119856X0190Y         S0      
327m8133            J15   -127        A01X+118041Y+119856X0205Y0590R090 S1      
317m8134            VIA   -    MD0080PA01X+132118Y+110778X0160Y         S0      
327m8134            U25   -CL64       A01X+132302Y+110673X0177Y    R180 S1      
317m8134            VIA   -    MD0100PA01X+118041Y+116175X0190Y         S0      
327m8134            J15   -116        A01X+118041Y+116175X0205Y0590R090 S1      
317m8135            VIA   -    MD0080PA01X+132118Y+108865X0160Y         S0      
327m8135            U25   -CE64       A01X+132302Y+108760X0177Y    R180 S1      
317m8135            VIA   -    MD0100PA01X+118041Y+112494X0190Y         S0      
327m8135            J15   -105        A01X+118041Y+112494X0205Y0590R090 S1      
317m8136            VIA   -    MD0080PA01X+132859Y+110140X0160Y         S0      
327m8136            U25   -CJ62       A01X+133042Y+110036X0177Y    R180 S1      
317m8136            VIA   -    MD0100PA01X+118041Y+115171X0190Y         S0      
327m8136            J15   -113        A01X+118041Y+115171X0205Y0590R090 S1      
317m8137            VIA   -    MD0080PA01X+132304Y+109821X0160Y         S0      
327m8137            U25   -CH63       A01X+132487Y+109717X0177Y    R180 S1      
317m8137            VIA   -    MD0100PA01X+118041Y+114502X0190Y         S0      
327m8137            J15   -111        A01X+118041Y+114502X0205Y0590R090 S1      
317m8138            VIA   -    MD0080PA01X+132674Y+109821X0160Y         S0      
327m8138            U25   -CH62       A01X+132858Y+109717X0177Y    R180 S1      
317m8138            VIA   -    MD0100PA01X+116427Y+114167X0190Y         S0      
327m8138            J15   -254        A01X+116427Y+114167X0205Y0590R090 S1      
317m8139            VIA   -    MD0080PA01X+132118Y+109502X0160Y         S0      
327m8139            U25   -CG64       A01X+132302Y+109398X0177Y    R180 S1      
317m8139            VIA   -    MD0100PA01X+116427Y+113498X0190Y         S0      
327m8139            J15   -252        A01X+116427Y+113498X0205Y0590R090 S1      
317m8140            VIA   -    MD0080PA01X+132859Y+109502X0160Y         S0      
327m8140            U25   -CG62       A01X+133042Y+109398X0177Y    R180 S1      
317m8140            VIA   -    MD0100PA01X+118041Y+113833X0190Y         S0      
327m8140            J15   -109        A01X+118041Y+113833X0205Y0590R090 S1      
317m8141            VIA   -    MD0080PA01X+132304Y+109184X0160Y         S0      
327m8141            U25   -CF63       A01X+132487Y+109079X0177Y    R180 S1      
317m8141            VIA   -    MD0100PA01X+118041Y+113163X0190Y         S0      
327m8141            J15   -107        A01X+118041Y+113163X0205Y0590R090 S1      
317m8142            VIA   -    MD0080PA01X+132674Y+108546X0160Y         S0      
327m8142            U25   -CD62       A01X+132858Y+108441X0177Y    R180 S1      
317m8142            VIA   -    MD0100PA01X+116427Y+111825X0190Y         S0      
327m8142            J15   -247        A01X+116427Y+111825X0205Y0590R090 S1      
317m8143            VIA   -    MD0080PA01X+132674Y+115561X0160Y         S0      
317m8143            VIA   -    MD0100PA01X+116427Y+125211X0190Y         S0      
327m8143            J15   -287        A01X+116427Y+125211X0205Y0590R090 S1      
327m8143            U25   -DF62       A01X+132858Y+115457X0177Y    R180 S1      
317m8144            VIA   -    MD0080PA01X+132118Y+115242X0160Y         S0      
327m8144            U25   -DE64       A01X+132302Y+115138X0177Y    R180 S1      
317m8144            VIA   -    MD0100PA01X+116427Y+124541X0190Y         S0      
327m8144            J15   -285        A01X+116427Y+124541X0205Y0590R090 S1      
317m8145            VIA   -    MD0080PA01X+132118Y+108227X0160Y         S0      
327m8145            U25   -CC64       A01X+132302Y+108122X0177Y    R180 S1      
317m8145            VIA   -    MD0100PA01X+116427Y+111156X0190Y         S0      
327m8145            J15   -245        A01X+116427Y+111156X0205Y0590R090 S1      
317m8146            VIA   -    MD0080PA01X+132859Y+115242X0160Y         S0      
327m8146            U25   -DE62       A01X+133042Y+115138X0177Y    R180 S1      
317m8146            VIA   -    MD0100PA01X+118041Y+124876X0190Y         S0      
327m8146            J15   -142        A01X+118041Y+124876X0205Y0590R090 S1      
317m8147            VIA   -    MD0080PA01X+132304Y+114924X0160Y         S0      
327m8147            U25   -DD63       A01X+132487Y+114819X0177Y    R180 S1      
317m8147            VIA   -    MD0100PA01X+118041Y+124207X0190Y         S0      
327m8147            J15   -140        A01X+118041Y+124207X0205Y0590R090 S1      
317m8148            VIA   -    MD0080PA01X+132674Y+114286X0160Y         S0      
327m8148            U25   -DB62       A01X+132858Y+114181X0177Y    R180 S1      
317m8148            VIA   -    MD0100PA01X+116427Y+122868X0190Y         S0      
327m8148            J15   -280        A01X+116427Y+122868X0205Y0590R090 S1      
317m8149            VIA   -    MD0080PA01X+132118Y+113967X0160Y         S0      
327m8149            U25   -DA64       A01X+132302Y+113862X0177Y    R180 S1      
317m8149            VIA   -    MD0100PA01X+116427Y+122199X0190Y         S0      
327m8149            J15   -278        A01X+116427Y+122199X0205Y0590R090 S1      
317m8150            VIA   -    MD0080PA01X+132859Y+113967X0160Y         S0      
327m8150            U25   -DA62       A01X+133042Y+113862X0177Y    R180 S1      
317m8150            VIA   -    MD0100PA01X+118041Y+122534X0190Y         S0      
327m8150            J15   -135        A01X+118041Y+122534X0205Y0590R090 S1      
317m8151            VIA   -    MD0080PA01X+132304Y+113648X0160Y         S0      
327m8151            U25   -CY63       A01X+132487Y+113543X0177Y    R180 S1      
317m8151            VIA   -    MD0100PA01X+118041Y+121864X0190Y         S0      
327m8151            J15   -133        A01X+118041Y+121864X0205Y0590R090 S1      
317m8152            VIA   -    MD0080PA01X+132674Y+113648X0160Y         S0      
327m8152            U25   -CY62       A01X+132858Y+113543X0177Y    R180 S1      
317m8152            VIA   -    MD0100PA01X+116427Y+121530X0190Y         S0      
327m8152            J15   -276        A01X+116427Y+121530X0205Y0590R090 S1      
317m8153            VIA   -    MD0080PA01X+132118Y+113329X0160Y         S0      
327m8153            U25   -CW64       A01X+132302Y+113224X0177Y    R180 S1      
317m8153            VIA   -    MD0100PA01X+116427Y+120860X0190Y         S0      
327m8153            J15   -274        A01X+116427Y+120860X0205Y0590R090 S1      
317m8154            VIA   -    MD0080PA01X+132859Y+113329X0160Y         S0      
327m8154            U25   -CW62       A01X+133042Y+113224X0177Y    R180 S1      
317m8154            VIA   -    MD0100PA01X+118041Y+121195X0190Y         S0      
327m8154            J15   -131        A01X+118041Y+121195X0205Y0590R090 S1      
317m8155            VIA   -    MD0080PA01X+132304Y+113010X0160Y         S0      
327m8155            U25   -CV63       A01X+132487Y+112906X0177Y    R180 S1      
317m8155            VIA   -    MD0100PA01X+118041Y+120526X0190Y         S0      
327m8155            J15   -129        A01X+118041Y+120526X0205Y0590R090 S1      
317m8156            VIA   -    MD0080PA01X+132859Y+108227X0160Y         S0      
327m8156            U25   -CC62       A01X+133042Y+108122X0177Y    R180 S1      
317m8156            VIA   -    MD0100PA01X+118041Y+111490X0190Y         S0      
327m8156            J15   -102        A01X+118041Y+111490X0205Y0590R090 S1      
317m8157            VIA   -    MD0080PA01X+132674Y+112372X0160Y         S0      
327m8157            U25   -CT62       A01X+132858Y+112268X0177Y    R180 S1      
317m8157            VIA   -    MD0100PA01X+116427Y+119187X0190Y         S0      
327m8157            J15   -269        A01X+116427Y+119187X0205Y0590R090 S1      
317m8158            VIA   -    MD0080PA01X+132118Y+112054X0160Y         S0      
327m8158            U25   -CR64       A01X+132302Y+111949X0177Y    R180 S1      
317m8158            VIA   -    MD0100PA01X+116427Y+118518X0190Y         S0      
327m8158            J15   -267        A01X+116427Y+118518X0205Y0590R090 S1      
317m8159            VIA   -    MD0080PA01X+132859Y+112054X0160Y         S0      
327m8159            U25   -CR62       A01X+133042Y+111949X0177Y    R180 S1      
317m8159            VIA   -    MD0100PA01X+118041Y+118852X0190Y         S0      
327m8159            J15   -124        A01X+118041Y+118852X0205Y0590R090 S1      
317m8160            VIA   -    MD0080PA01X+132304Y+111735X0160Y         S0      
327m8160            U25   -CP63       A01X+132487Y+111630X0177Y    R180 S1      
317m8160            VIA   -    MD0100PA01X+118041Y+118183X0190Y         S0      
327m8160            J15   -122        A01X+118041Y+118183X0205Y0590R090 S1      
317m8161            VIA   -    MD0080PA01X+132674Y+111735X0160Y         S0      
327m8161            U25   -CP62       A01X+132858Y+111630X0177Y    R180 S1      
317m8161            VIA   -    MD0100PA01X+116427Y+117848X0190Y         S0      
327m8161            J15   -265        A01X+116427Y+117848X0205Y0590R090 S1      
317m8162            VIA   -    MD0080PA01X+132118Y+111416X0160Y         S0      
327m8162            U25   -CN64       A01X+132302Y+111311X0177Y    R180 S1      
317m8162            VIA   -    MD0100PA01X+116427Y+117179X0190Y         S0      
327m8162            J15   -263        A01X+116427Y+117179X0205Y0590R090 S1      
317m8163            VIA   -    MD0080PA01X+132859Y+111416X0160Y         S0      
327m8163            U25   -CN62       A01X+133042Y+111311X0177Y    R180 S1      
317m8163            VIA   -    MD0100PA01X+118041Y+117514X0190Y         S0      
327m8163            J15   -120        A01X+118041Y+117514X0205Y0590R090 S1      
317m8164            VIA   -    MD0080PA01X+132304Y+111097X0160Y         S0      
327m8164            U25   -CM63       A01X+132487Y+110992X0177Y    R180 S1      
317m8164            VIA   -    MD0100PA01X+118041Y+116844X0190Y         S0      
327m8164            J15   -118        A01X+118041Y+116844X0205Y0590R090 S1      
317m8165            VIA   -    MD0080PA01X+132674Y+110459X0160Y         S0      
327m8165            U25   -CK62       A01X+132858Y+110354X0177Y    R180 S1      
317m8165            VIA   -    MD0100PA01X+116427Y+115506X0190Y         S0      
327m8165            J15   -258        A01X+116427Y+115506X0205Y0590R090 S1      
317m8166            VIA   -    MD0080PA01X+132118Y+110140X0160Y         S0      
327m8166            U25   -CJ64       A01X+132302Y+110036X0177Y    R180 S1      
317m8166            VIA   -    MD0100PA01X+116427Y+114837X0190Y         S0      
327m8166            J15   -256        A01X+116427Y+114837X0205Y0590R090 S1      
317m8167            VIA   -    MD0080PA01X+132304Y+107908X0160Y         S0      
327m8167            U25   -CB63       A01X+132487Y+107803X0177Y    R180 S1      
317m8167            VIA   -    MD0100PA01X+118041Y+110821X0190Y         S0      
327m8167            J15   -100        A01X+118041Y+110821X0205Y0590R090 S1      
317m8168            VIA   -    MD0080PA01X+132118Y+105038X0160Y         S0      
327m8168            U25   -BN64       A01X+132302Y+104933X0177Y    R180 S1      
317m8168            VIA   -    MD0100PA01X+116427Y+105801X0190Y         S0      
327m8168            J15   -229        A01X+116427Y+105801X0205Y0590R090 S1      
317m8169            VIA   -    MD0080PA01X+132674Y+104719X0160Y         S0      
327m8169            U25   -BM62       A01X+132858Y+104614X0177Y    R180 S1      
317m8169            VIA   -    MD0100PA01X+118041Y+105467X0190Y         S0      
327m8169            J15   -84         A01X+118041Y+105467X0205Y0590R090 S1      
317m8170            VIA   -    MD0080PA01X+132674Y+106632X0160Y         S0      
327m8170            U25   -BV62       A01X+132858Y+106528X0177Y    R180 S1      
317m8170            VIA   -    MD0100PA01X+116427Y+108144X0190Y         S0      
327m8170            J15   -236        A01X+116427Y+108144X0205Y0590R090 S1      
317m8171            VIA   -    MD0080PA01X+132118Y+106313X0160Y         S0      
327m8171            U25   -BU64       A01X+132302Y+106209X0177Y    R180 S1      
317m8171            VIA   -    MD0100PA01X+116427Y+107474X0190Y         S0      
327m8171            J15   -234        A01X+116427Y+107474X0205Y0590R090 S1      
317m8172            VIA   -    MD0080PA01X+132859Y+106313X0160Y         S0      
327m8172            U25   -BU62       A01X+133042Y+106209X0177Y    R180 S1      
317m8172            VIA   -    MD0100PA01X+118041Y+107809X0190Y         S0      
327m8172            J15   -91         A01X+118041Y+107809X0205Y0590R090 S1      
317m8173            VIA   -    MD0080PA01X+132304Y+105994X0160Y         S0      
327m8173            U25   -BT63       A01X+132487Y+105890X0177Y    R180 S1      
317m8173            VIA   -    MD0100PA01X+118041Y+107140X0190Y         S0      
327m8173            J15   -89         A01X+118041Y+107140X0205Y0590R090 S1      
317m8174            VIA   -    MD0080PA01X+132674Y+107908X0160Y         S0      
327m8174            U25   -CB62       A01X+132858Y+107803X0177Y    R180 S1      
317m8174            VIA   -    MD0100PA01X+116427Y+110486X0190Y         S0      
327m8174            J15   -243        A01X+116427Y+110486X0205Y0590R090 S1      
317m8175            VIA   -    MD0080PA01X+132118Y+107589X0160Y         S0      
327m8175            U25   -CA64       A01X+132302Y+107484X0177Y    R180 S1      
317m8175            VIA   -    MD0100PA01X+116427Y+109817X0190Y         S0      
327m8175            J15   -241        A01X+116427Y+109817X0205Y0590R090 S1      
317m8176            VIA   -    MD0080PA01X+132859Y+107589X0160Y         S0      
327m8176            U25   -CA62       A01X+133042Y+107484X0177Y    R180 S1      
317m8176            VIA   -    MD0100PA01X+118041Y+110152X0190Y         S0      
327m8176            J15   -98         A01X+118041Y+110152X0205Y0590R090 S1      
317m8177            VIA   -    MD0080PA01X+132304Y+107270X0160Y         S0      
327m8177            U25   -BY63       A01X+132487Y+107165X0177Y    R180 S1      
317m8177            VIA   -    MD0100PA01X+118041Y+109482X0190Y         S0      
327m8177            J15   -96         A01X+118041Y+109482X0205Y0590R090 S1      
317m8178            VIA   -    MD0080PA01X+132304Y+104081X0160Y         S0      
327m8178            U25   -BK63       A01X+132487Y+103976X0177Y    R180 S1      
317m8178            VIA   -    MD0100PA01X+118041Y+104797X0190Y         S0      
327m8178            J15   -82         A01X+118041Y+104797X0205Y0590R090 S1      
317m8179            VIA   -    MD0080PA01X+132674Y+104081X0160Y         S0      
327m8179            U25   -BK62       A01X+132858Y+103976X0177Y    R180 S1      
317m8179            VIA   -    MD0100PA01X+116427Y+104463X0190Y         S0      
327m8179            J15   -225        A01X+116427Y+104463X0205Y0590R090 S1      
317m8180            VIA   -    MD0080PA01X+132859Y+103762X0160Y         S0      
327m8180            U25   -BJ62       A01X+133042Y+103658X0177Y    R180 S1      
317m8180            VIA   -    MD0100PA01X+118041Y+104128X0190Y         S0      
327m8180            J15   -80         A01X+118041Y+104128X0205Y0590R090 S1      
317m8181            VIA   -    MD0080PA01X+132118Y+103762X0160Y         S0      
327m8181            U25   -BJ64       A01X+132302Y+103658X0177Y    R180 S1      
317m8181            VIA   -    MD0100PA01X+116427Y+103793X0190Y         S0      
327m8181            J15   -223        A01X+116427Y+103793X0205Y0590R090 S1      
317m8182            VIA   -    MD0080PA01X+132304Y+103443X0160Y         S0      
327m8182            U25   -BH63       A01X+132487Y+103339X0177Y    R180 S1      
317m8182            VIA   -    MD0100PA01X+118041Y+103459X0190Y         S0      
327m8182            J15   -78         A01X+118041Y+103459X0205Y0590R090 S1      
317m8183            VIA   -    MD0080PA01X+132674Y+103443X0160Y         S0      
327m8183            U25   -BH62       A01X+132858Y+103339X0177Y    R180 S1      
317m8183            VIA   -    MD0100PA01X+116427Y+103124X0190Y         S0      
327m8183            J15   -221        A01X+116427Y+103124X0205Y0590R090 S1      
317m8184            VIA   -    MD0080PA01X+132859Y+103124X0160Y         S0      
327m8184            U25   -BG62       A01X+133042Y+103020X0177Y    R180 S1      
317m8184            VIA   -    MD0100PA01X+118041Y+102789X0190Y         S0      
327m8184            J15   -76         A01X+118041Y+102789X0205Y0590R090 S1      
317m8185            VIA   -    MD0080PA01X+132859Y+105038X0160Y         S0      
327m8185            U25   -BN62       A01X+133042Y+104933X0177Y    R180 S1      
317m8185            VIA   -    MD0100PA01X+118041Y+106136X0190Y         S0      
327m8185            J15   -86         A01X+118041Y+106136X0205Y0590R090 S1      
317m8186            VIA   -    MD0080PA01X+132741Y+100718X0160Y    R180 S0      
327m8186            U25   -BC62       A01X+132924Y+100823X0177Y    R180 S1      
317m8186            VIA   -    MD0100PA01X+118041Y+100112X0190Y         S0      
327m8186            J15   -74         A01X+118041Y+100112X0205Y0590R090 S1      
317m8187            VIA   -    MD0080PA01X+132741Y+097529X0160Y    R180 S0      
327m8187            U25   -AN62       A01X+132924Y+097634X0177Y    R180 S1      
317m8187            VIA   -    MD0100PA01X+116427Y+094423X0190Y         S0      
327m8187            J15   -201        A01X+116427Y+094423X0205Y0590R090 S1      
317m8188            VIA   -    MD0080PA01X+132741Y+095616X0160Y    R180 S0      
327m8188            U25   -AG62       A01X+132924Y+095720X0177Y    R180 S1      
317m8188            VIA   -    MD0100PA01X+116427Y+090742X0190Y         S0      
327m8188            J15   -190        A01X+116427Y+090742X0205Y0590R090 S1      
317m8189            VIA   -    MD0080PA01X+132741Y+093702X0160Y    R180 S0      
327m8189            U25   -AA62       A01X+132924Y+093807X0177Y    R180 S1      
317m8189            VIA   -    MD0100PA01X+116427Y+087061X0190Y         S0      
327m8189            J15   -179        A01X+116427Y+087061X0205Y0590R090 S1      
317m8190            VIA   -    MD0080PA01X+132741Y+091789X0160Y    R180 S0      
327m8190            U25   -R62        A01X+132924Y+091894X0177Y    R180 S1      
317m8190            VIA   -    MD0100PA01X+116427Y+083380X0190Y         S0      
327m8190            J15   -168        A01X+116427Y+083380X0205Y0590R090 S1      
317m8191            VIA   -    MD0080PA01X+132741Y+089876X0160Y    R180 S0      
327m8191            U25   -J62        A01X+132924Y+089980X0177Y    R180 S1      
317m8191            VIA   -    MD0100PA01X+116427Y+079699X0190Y         S0      
327m8191            J15   -157        A01X+116427Y+079699X0205Y0590R090 S1      
317m8192            VIA   -    MD0080PA01X+132000Y+096891X0160Y    R180 S0      
327m8192            U25   -AL64       A01X+132184Y+096996X0177Y    R180 S1      
317m8192            VIA   -    MD0100PA01X+118041Y+093754X0190Y         S0      
327m8192            J15   -55         A01X+118041Y+093754X0205Y0590R090 S1      
317m8193            VIA   -    MD0080PA01X+132000Y+094978X0160Y    R180 S0      
327m8193            U25   -AE64       A01X+132184Y+095083X0177Y    R180 S1      
317m8193            VIA   -    MD0100PA01X+118041Y+090073X0190Y         S0      
327m8193            J15   -44         A01X+118041Y+090073X0205Y0590R090 S1      
317m8194            VIA   -    MD0080PA01X+132000Y+093065X0160Y    R180 S0      
327m8194            U25   -W64        A01X+132184Y+093169X0177Y    R180 S1      
317m8194            VIA   -    MD0100PA01X+118041Y+086392X0190Y         S0      
327m8194            J15   -33         A01X+118041Y+086392X0205Y0590R090 S1      
317m8195            VIA   -    MD0080PA01X+132000Y+091151X0160Y    R180 S0      
327m8195            U25   -N64        A01X+132184Y+091256X0177Y    R180 S1      
317m8195            VIA   -    MD0100PA01X+118041Y+082711X0190Y         S0      
327m8195            J15   -22         A01X+118041Y+082711X0205Y0590R090 S1      
317m8196            VIA   -    MD0080PA01X+132000Y+089238X0160Y    R180 S0      
327m8196            U25   -G64        A01X+132184Y+089343X0177Y    R180 S1      
317m8196            VIA   -    MD0100PA01X+118041Y+079030X0190Y         S0      
327m8196            J15   -11         A01X+118041Y+079030X0205Y0590R090 S1      
317m8197            VIA   -    MD0080PA01X+132556Y+097210X0160Y    R180 S0      
327m8197            U25   -AM62       A01X+132739Y+097315X0177Y    R180 S1      
317m8197            VIA   -    MD0100PA01X+116427Y+094089X0190Y         S0      
327m8197            J15   -200        A01X+116427Y+094089X0205Y0590R090 S1      
317m8198            VIA   -    MD0080PA01X+132556Y+095297X0160Y    R180 S0      
327m8198            U25   -AF62       A01X+132739Y+095402X0177Y    R180 S1      
317m8198            VIA   -    MD0100PA01X+116427Y+090408X0190Y         S0      
327m8198            J15   -189        A01X+116427Y+090408X0205Y0590R090 S1      
317m8199            VIA   -    MD0080PA01X+132556Y+093384X0160Y    R180 S0      
327m8199            U25   -Y62        A01X+132739Y+093488X0177Y    R180 S1      
317m8199            VIA   -    MD0100PA01X+116427Y+086726X0190Y         S0      
327m8199            J15   -178        A01X+116427Y+086726X0205Y0590R090 S1      
317m8200            VIA   -    MD0080PA01X+132556Y+091470X0160Y    R180 S0      
327m8200            U25   -P62        A01X+132739Y+091575X0177Y    R180 S1      
317m8200            VIA   -    MD0100PA01X+116427Y+083045X0190Y         S0      
327m8200            J15   -167        A01X+116427Y+083045X0205Y0590R090 S1      
317m8201            VIA   -    MD0080PA01X+132556Y+089557X0160Y    R180 S0      
327m8201            U25   -H62        A01X+132739Y+089662X0177Y    R180 S1      
317m8201            VIA   -    MD0100PA01X+116427Y+079364X0190Y         S0      
327m8201            J15   -156        A01X+116427Y+079364X0205Y0590R090 S1      
317m8202            VIA   -    MD0080PA01X+132186Y+097210X0160Y    R180 S0      
327m8202            U25   -AM63       A01X+132369Y+097315X0177Y    R180 S1      
317m8202            VIA   -    MD0100PA01X+118041Y+094089X0190Y         S0      
327m8202            J15   -56         A01X+118041Y+094089X0205Y0590R090 S1      
317m8203            VIA   -    MD0080PA01X+132186Y+095297X0160Y    R180 S0      
327m8203            U25   -AF63       A01X+132369Y+095402X0177Y    R180 S1      
317m8203            VIA   -    MD0100PA01X+118041Y+090408X0190Y         S0      
327m8203            J15   -45         A01X+118041Y+090408X0205Y0590R090 S1      
317m8204            VIA   -    MD0080PA01X+132186Y+093384X0160Y    R180 S0      
327m8204            U25   -Y63        A01X+132369Y+093488X0177Y    R180 S1      
317m8204            VIA   -    MD0100PA01X+118041Y+086726X0190Y         S0      
327m8204            J15   -34         A01X+118041Y+086726X0205Y0590R090 S1      
317m8205            VIA   -    MD0080PA01X+132186Y+091470X0160Y    R180 S0      
327m8205            U25   -P63        A01X+132369Y+091575X0177Y    R180 S1      
317m8205            VIA   -    MD0100PA01X+118041Y+083045X0190Y         S0      
327m8205            J15   -23         A01X+118041Y+083045X0205Y0590R090 S1      
317m8206            VIA   -    MD0080PA01X+132186Y+089557X0160Y    R180 S0      
327m8206            U25   -H63        A01X+132369Y+089662X0177Y    R180 S1      
317m8206            VIA   -    MD0100PA01X+118041Y+079364X0190Y         S0      
327m8206            J15   -12         A01X+118041Y+079364X0205Y0590R090 S1      
317m8207            VIA   -    MD0080PA01X+132556Y+090832X0160Y    R180 S0      
327m8207            U25   -M62        A01X+132739Y+090937X0177Y    R180 S1      
317m8207            VIA   -    MD0100PA01X+118041Y+082041X0190Y         S0      
327m8207            J15   -20         A01X+118041Y+082041X0205Y0590R090 S1      
317m8208            VIA   -    MD0080PA01X+132000Y+090513X0160Y    R180 S0      
327m8208            U25   -L64        A01X+132184Y+090618X0177Y    R180 S1      
317m8208            VIA   -    MD0100PA01X+118041Y+081372X0190Y         S0      
327m8208            J15   -18         A01X+118041Y+081372X0205Y0590R090 S1      
317m8209            VIA   -    MD0080PA01X+132741Y+090513X0160Y    R180 S0      
327m8209            U25   -L62        A01X+132924Y+090618X0177Y    R180 S1      
317m8209            VIA   -    MD0100PA01X+116427Y+081037X0190Y         S0      
327m8209            J15   -161        A01X+116427Y+081037X0205Y0590R090 S1      
317m8210            VIA   -    MD0080PA01X+132186Y+090195X0160Y    R180 S0      
327m8210            U25   -K63        A01X+132369Y+090299X0177Y    R180 S1      
317m8210            VIA   -    MD0100PA01X+116427Y+080368X0190Y         S0      
327m8210            J15   -159        A01X+116427Y+080368X0205Y0590R090 S1      
317m8211            VIA   -    MD0080PA01X+132556Y+090195X0160Y    R180 S0      
327m8211            U25   -K62        A01X+132739Y+090299X0177Y    R180 S1      
317m8211            VIA   -    MD0100PA01X+118041Y+080703X0190Y         S0      
327m8211            J15   -16         A01X+118041Y+080703X0205Y0590R090 S1      
317m8212            VIA   -    MD0080PA01X+132000Y+089876X0160Y    R180 S0      
327m8212            U25   -J64        A01X+132184Y+089980X0177Y    R180 S1      
317m8212            VIA   -    MD0100PA01X+118041Y+080034X0190Y         S0      
327m8212            J15   -14         A01X+118041Y+080034X0205Y0590R090 S1      
317m8213            VIA   -    MD0080PA01X+132741Y+089238X0160Y    R180 S0      
327m8213            U25   -G62        A01X+132924Y+089343X0177Y    R180 S1      
317m8213            VIA   -    MD0100PA01X+116427Y+078695X0190Y         S0      
327m8213            J15   -154        A01X+116427Y+078695X0205Y0590R090 S1      
317m8214            VIA   -    MD0080PA01X+132741Y+096254X0160Y    R180 S0      
327m8214            U25   -AJ62       A01X+132924Y+096358X0177Y    R180 S1      
317m8214            VIA   -    MD0100PA01X+116427Y+092081X0190Y         S0      
327m8214            J15   -194        A01X+116427Y+092081X0205Y0590R090 S1      
317m8215            VIA   -    MD0080PA01X+132186Y+095935X0160Y    R180 S0      
327m8215            U25   -AH63       A01X+132369Y+096039X0177Y    R180 S1      
317m8215            VIA   -    MD0100PA01X+116427Y+091411X0190Y         S0      
327m8215            J15   -192        A01X+116427Y+091411X0205Y0590R090 S1      
317m8216            VIA   -    MD0080PA01X+132186Y+088919X0160Y    R180 S0      
327m8216            U25   -F63        A01X+132369Y+089024X0177Y    R180 S1      
317m8216            VIA   -    MD0100PA01X+116427Y+078026X0190Y         S0      
327m8216            J15   -152        A01X+116427Y+078026X0205Y0590R090 S1      
317m8217            VIA   -    MD0080PA01X+132556Y+095935X0160Y    R180 S0      
327m8217            U25   -AH62       A01X+132739Y+096039X0177Y    R180 S1      
317m8217            VIA   -    MD0100PA01X+118041Y+091746X0190Y         S0      
327m8217            J15   -49         A01X+118041Y+091746X0205Y0590R090 S1      
317m8218            VIA   -    MD0080PA01X+132000Y+095616X0160Y    R180 S0      
327m8218            U25   -AG64       A01X+132184Y+095720X0177Y    R180 S1      
317m8218            VIA   -    MD0100PA01X+118041Y+091077X0190Y         S0      
327m8218            J15   -47         A01X+118041Y+091077X0205Y0590R090 S1      
317m8219            VIA   -    MD0080PA01X+132741Y+094978X0160Y    R180 S0      
327m8219            U25   -AE62       A01X+132924Y+095083X0177Y    R180 S1      
317m8219            VIA   -    MD0100PA01X+116427Y+089738X0190Y         S0      
327m8219            J15   -187        A01X+116427Y+089738X0205Y0590R090 S1      
317m8220            VIA   -    MD0080PA01X+132186Y+094659X0160Y    R180 S0      
327m8220            U25   -AD63       A01X+132369Y+094764X0177Y    R180 S1      
317m8220            VIA   -    MD0100PA01X+116427Y+089069X0190Y         S0      
327m8220            J15   -185        A01X+116427Y+089069X0205Y0590R090 S1      
317m8221            VIA   -    MD0080PA01X+132556Y+094659X0160Y    R180 S0      
327m8221            U25   -AD62       A01X+132739Y+094764X0177Y    R180 S1      
317m8221            VIA   -    MD0100PA01X+118041Y+089404X0190Y         S0      
327m8221            J15   -42         A01X+118041Y+089404X0205Y0590R090 S1      
317m8222            VIA   -    MD0080PA01X+132000Y+094340X0160Y    R180 S0      
327m8222            U25   -AC64       A01X+132184Y+094445X0177Y    R180 S1      
317m8222            VIA   -    MD0100PA01X+118041Y+088734X0190Y         S0      
327m8222            J15   -40         A01X+118041Y+088734X0205Y0590R090 S1      
317m8223            VIA   -    MD0080PA01X+132741Y+094340X0160Y    R180 S0      
327m8223            U25   -AC62       A01X+132924Y+094445X0177Y    R180 S1      
317m8223            VIA   -    MD0100PA01X+116427Y+088400X0190Y         S0      
327m8223            J15   -183        A01X+116427Y+088400X0205Y0590R090 S1      
317m8224            VIA   -    MD0080PA01X+132186Y+094021X0160Y    R180 S0      
327m8224            U25   -AB63       A01X+132369Y+094126X0177Y    R180 S1      
317m8224            VIA   -    MD0100PA01X+116427Y+087730X0190Y         S0      
327m8224            J15   -181        A01X+116427Y+087730X0205Y0590R090 S1      
317m8225            VIA   -    MD0080PA01X+132556Y+094021X0160Y    R180 S0      
327m8225            U25   -AB62       A01X+132739Y+094126X0177Y    R180 S1      
317m8225            VIA   -    MD0100PA01X+118041Y+088065X0190Y         S0      
327m8225            J15   -38         A01X+118041Y+088065X0205Y0590R090 S1      
317m8226            VIA   -    MD0080PA01X+132000Y+093702X0160Y    R180 S0      
327m8226            U25   -AA64       A01X+132184Y+093807X0177Y    R180 S1      
317m8226            VIA   -    MD0100PA01X+118041Y+087396X0190Y         S0      
327m8226            J15   -36         A01X+118041Y+087396X0205Y0590R090 S1      
317m8227            VIA   -    MD0080PA01X+132556Y+088919X0160Y    R180 S0      
327m8227            U25   -F62        A01X+132739Y+089024X0177Y    R180 S1      
317m8227            VIA   -    MD0100PA01X+118041Y+078360X0190Y         S0      
327m8227            J15   -9          A01X+118041Y+078360X0205Y0590R090 S1      
317m8228            VIA   -    MD0080PA01X+132741Y+093065X0160Y    R180 S0      
327m8228            U25   -W62        A01X+132924Y+093169X0177Y    R180 S1      
317m8228            VIA   -    MD0100PA01X+116427Y+086057X0190Y         S0      
327m8228            J15   -176        A01X+116427Y+086057X0205Y0590R090 S1      
317m8229            VIA   -    MD0080PA01X+132186Y+092746X0160Y    R180 S0      
327m8229            U25   -V63        A01X+132369Y+092850X0177Y    R180 S1      
317m8229            VIA   -    MD0100PA01X+116427Y+085388X0190Y         S0      
327m8229            J15   -174        A01X+116427Y+085388X0205Y0590R090 S1      
317m8230            VIA   -    MD0080PA01X+132556Y+092746X0160Y    R180 S0      
327m8230            U25   -V62        A01X+132739Y+092850X0177Y    R180 S1      
317m8230            VIA   -    MD0100PA01X+118041Y+085722X0190Y         S0      
327m8230            J15   -31         A01X+118041Y+085722X0205Y0590R090 S1      
317m8231            VIA   -    MD0080PA01X+132000Y+092427X0160Y    R180 S0      
327m8231            U25   -U64        A01X+132184Y+092532X0177Y    R180 S1      
317m8231            VIA   -    MD0100PA01X+118041Y+085053X0190Y         S0      
327m8231            J15   -29         A01X+118041Y+085053X0205Y0590R090 S1      
317m8232            VIA   -    MD0080PA01X+132741Y+092427X0160Y    R180 S0      
327m8232            U25   -U62        A01X+132924Y+092532X0177Y    R180 S1      
317m8232            VIA   -    MD0100PA01X+116427Y+084718X0190Y         S0      
327m8232            J15   -172        A01X+116427Y+084718X0205Y0590R090 S1      
317m8233            VIA   -    MD0080PA01X+132186Y+092108X0160Y    R180 S0      
327m8233            U25   -T63        A01X+132369Y+092213X0177Y    R180 S1      
317m8233            VIA   -    MD0100PA01X+116427Y+084049X0190Y         S0      
327m8233            J15   -170        A01X+116427Y+084049X0205Y0590R090 S1      
317m8234            VIA   -    MD0080PA01X+132556Y+092108X0160Y    R180 S0      
327m8234            U25   -T62        A01X+132739Y+092213X0177Y    R180 S1      
317m8234            VIA   -    MD0100PA01X+118041Y+084384X0190Y         S0      
327m8234            J15   -27         A01X+118041Y+084384X0205Y0590R090 S1      
317m8235            VIA   -    MD0080PA01X+132000Y+091789X0160Y    R180 S0      
327m8235            U25   -R64        A01X+132184Y+091894X0177Y    R180 S1      
317m8235            VIA   -    MD0100PA01X+118041Y+083715X0190Y         S0      
327m8235            J15   -25         A01X+118041Y+083715X0205Y0590R090 S1      
317m8236            VIA   -    MD0080PA01X+132741Y+091151X0160Y    R180 S0      
327m8236            U25   -N62        A01X+132924Y+091256X0177Y    R180 S1      
317m8236            VIA   -    MD0100PA01X+116427Y+082376X0190Y         S0      
327m8236            J15   -165        A01X+116427Y+082376X0205Y0590R090 S1      
317m8237            VIA   -    MD0080PA01X+132186Y+090832X0160Y    R180 S0      
327m8237            U25   -M63        A01X+132369Y+090937X0177Y    R180 S1      
317m8237            VIA   -    MD0100PA01X+116427Y+081707X0190Y         S0      
327m8237            J15   -163        A01X+116427Y+081707X0205Y0590R090 S1      
317m8238            VIA   -    MD0080PA01X+132000Y+088600X0160Y    R180 S0      
327m8238            U25   -E64        A01X+132184Y+088705X0177Y    R180 S1      
317m8238            VIA   -    MD0100PA01X+118041Y+077691X0190Y         S0      
327m8238            J15   -7          A01X+118041Y+077691X0205Y0590R090 S1      
317m8239            VIA   -    MD0080PA01X+132741Y+099443X0160Y    R180 S0      
327m8239            U25   -AW62       A01X+132924Y+099547X0177Y    R180 S1      
317m8239            VIA   -    MD0100PA01X+116427Y+097100X0190Y         S0      
327m8239            J15   -209        A01X+116427Y+097100X0205Y0590R090 S1      
317m8240            VIA   -    MD0080PA01X+132186Y+099124X0160Y    R180 S0      
327m8240            U25   -AV63       A01X+132369Y+099228X0177Y    R180 S1      
317m8240            VIA   -    MD0100PA01X+118041Y+096766X0190Y         S0      
327m8240            J15   -64         A01X+118041Y+096766X0205Y0590R090 S1      
317m8241            VIA   -    MD0080PA01X+132741Y+098167X0160Y    R180 S0      
327m8241            U25   -AR62       A01X+132924Y+098272X0177Y    R180 S1      
317m8241            VIA   -    MD0100PA01X+116427Y+095762X0190Y         S0      
327m8241            J15   -205        A01X+116427Y+095762X0205Y0590R090 S1      
317m8242            VIA   -    MD0080PA01X+132186Y+097848X0160Y    R180 S0      
327m8242            U25   -AP63       A01X+132369Y+097953X0177Y    R180 S1      
317m8242            VIA   -    MD0100PA01X+116427Y+095092X0190Y         S0      
327m8242            J15   -203        A01X+116427Y+095092X0205Y0590R090 S1      
317m8243            VIA   -    MD0080PA01X+132556Y+097848X0160Y    R180 S0      
327m8243            U25   -AP62       A01X+132739Y+097953X0177Y    R180 S1      
317m8243            VIA   -    MD0100PA01X+118041Y+095427X0190Y         S0      
327m8243            J15   -60         A01X+118041Y+095427X0205Y0590R090 S1      
317m8244            VIA   -    MD0080PA01X+132000Y+097529X0160Y    R180 S0      
327m8244            U25   -AN64       A01X+132184Y+097634X0177Y    R180 S1      
317m8244            VIA   -    MD0100PA01X+118041Y+094758X0190Y         S0      
327m8244            J15   -58         A01X+118041Y+094758X0205Y0590R090 S1      
317m8245            VIA   -    MD0080PA01X+132741Y+096891X0160Y    R180 S0      
327m8245            U25   -AL62       A01X+132924Y+096996X0177Y    R180 S1      
317m8245            VIA   -    MD0100PA01X+116427Y+093419X0190Y         S0      
327m8245            J15   -198        A01X+116427Y+093419X0205Y0590R090 S1      
317m8246            VIA   -    MD0080PA01X+132186Y+096572X0160Y    R180 S0      
327m8246            U25   -AK63       A01X+132369Y+096677X0177Y    R180 S1      
317m8246            VIA   -    MD0100PA01X+116427Y+092750X0190Y         S0      
327m8246            J15   -196        A01X+116427Y+092750X0205Y0590R090 S1      
317m8247            VIA   -    MD0080PA01X+132556Y+096572X0160Y    R180 S0      
327m8247            U25   -AK62       A01X+132739Y+096677X0177Y    R180 S1      
317m8247            VIA   -    MD0100PA01X+118041Y+093085X0190Y         S0      
327m8247            J15   -53         A01X+118041Y+093085X0205Y0590R090 S1      
317m8248            VIA   -    MD0080PA01X+132000Y+096254X0160Y    R180 S0      
327m8248            U25   -AJ64       A01X+132184Y+096358X0177Y    R180 S1      
317m8248            VIA   -    MD0100PA01X+118041Y+092415X0190Y         S0      
327m8248            J15   -51         A01X+118041Y+092415X0205Y0590R090 S1      
317m8249            VIA   -    MD0080PA01X+132556Y+100399X0160Y    R180 S0      
327m8249            U25   -BB62       A01X+132739Y+100504X0177Y    R180 S1      
317m8249            VIA   -    MD0100PA01X+118041Y+099443X0190Y         S0      
327m8249            J15   -72         A01X+118041Y+099443X0205Y0590R090 S1      
317m8250            VIA   -    MD0080PA01X+132186Y+100399X0160Y    R180 S0      
327m8250            U25   -BB63       A01X+132369Y+100504X0177Y    R180 S1      
317m8250            VIA   -    MD0100PA01X+116427Y+099108X0190Y         S0      
327m8250            J15   -215        A01X+116427Y+099108X0205Y0590R090 S1      
317m8251            VIA   -    MD0080PA01X+132000Y+100080X0160Y    R180 S0      
327m8251            U25   -BA64       A01X+132184Y+100185X0177Y    R180 S1      
317m8251            VIA   -    MD0100PA01X+118041Y+098774X0190Y         S0      
327m8251            J15   -70         A01X+118041Y+098774X0205Y0590R090 S1      
317m8252            VIA   -    MD0080PA01X+132741Y+100080X0160Y    R180 S0      
327m8252            U25   -BA62       A01X+132924Y+100185X0177Y    R180 S1      
317m8252            VIA   -    MD0100PA01X+116427Y+098439X0190Y         S0      
327m8252            J15   -213        A01X+116427Y+098439X0205Y0590R090 S1      
317m8253            VIA   -    MD0080PA01X+132556Y+099762X0160Y    R180 S0      
327m8253            U25   -AY62       A01X+132739Y+099866X0177Y    R180 S1      
317m8253            VIA   -    MD0100PA01X+118041Y+098104X0190Y         S0      
327m8253            J15   -68         A01X+118041Y+098104X0205Y0590R090 S1      
317m8254            VIA   -    MD0080PA01X+132186Y+099762X0160Y    R180 S0      
327m8254            U25   -AY63       A01X+132369Y+099866X0177Y    R180 S1      
317m8254            VIA   -    MD0100PA01X+116427Y+097770X0190Y         S0      
327m8254            J15   -211        A01X+116427Y+097770X0205Y0590R090 S1      
317m8255            VIA   -    MD0080PA01X+132000Y+099443X0160Y    R180 S0      
327m8255            U25   -AW64       A01X+132184Y+099547X0177Y    R180 S1      
317m8255            VIA   -    MD0100PA01X+118041Y+097435X0190Y         S0      
327m8255            J15   -66         A01X+118041Y+097435X0205Y0590R090 S1      
317m8256            VIA   -    MD0080PA01X+132741Y+098805X0160Y    R180 S0      
327m8256            U25   -AU62       A01X+132924Y+098910X0177Y    R180 S1      
317m8256            VIA   -    MD0100PA01X+116427Y+096431X0190Y         S0      
327m8256            J15   -207        A01X+116427Y+096431X0205Y0590R090 S1      
317m8257            VIA   -    MD0080PA01X+132000Y+100718X0160Y    R180 S0      
327m8257            U25   -BC64       A01X+132184Y+100823X0177Y    R180 S1      
317m8257            VIA   -    MD0100PA01X+116427Y+099778X0190Y         S0      
327m8257            J15   -217        A01X+116427Y+099778X0205Y0590R090 S1      
317m8258            VIA   -    MD0080PA01X+132186Y+101037X0160Y    R180 S0      
327m8258            U25   -BD63       A01X+132369Y+101142X0177Y    R180 S1      
317m8258            VIA   -    MD0100PA01X+116427Y+100112X0190Y         S0      
327m8258            J15   -218        A01X+116427Y+100112X0205Y0590R090 S1      
317m8259            VIA   -    MD0080PA01X+132556Y+098486X0160Y    R180 S0      
327m8259            U25   -AT62       A01X+132739Y+098591X0177Y    R180 S1      
317m8259            VIA   -    MD0100PA18X+118591Y+096096X0190Y         S0      
327m8259            R376  -2          A18X+118591Y+096096X0198Y0197R180 S2      
327m8260            J15   -62         A01X+118041Y+096096X0205Y0590R090 S1      
317m8260            VIA   -    MD0100PA00X+118041Y+096096X0190Y         S0      
327m8260            R376  -1          A18X+118276Y+096096X0198Y0197R180 S2      
327m8261            U26   -BP74       A01X+030802Y+105252X0177Y    R180 S1      
327m8261            J24   -87         A01X+023397Y+106471X0205Y0590R090 S1      
327m8262            U26   -BL74       A01X+030987Y+104295X0177Y    R180 S1      
327m8262            J24   -227        A01X+021783Y+105132X0205Y0590R090 S1      
327m8263            U26   -BV74       A01X+030802Y+106528X0177Y    R180 S1      
327m8263            J24   -93         A01X+023397Y+108478X0205Y0590R090 S1      
327m8264            U26   -DD72       A01X+031542Y+114819X0177Y    R180 S1      
327m8264            J24   -283        A01X+021783Y+123872X0205Y0590R090 S1      
327m8265            U26   -CV72       A01X+031542Y+112906X0177Y    R180 S1      
327m8265            J24   -272        A01X+021783Y+120191X0205Y0590R090 S1      
327m8266            U26   -CM72       A01X+031542Y+110992X0177Y    R180 S1      
327m8266            J24   -261        A01X+021783Y+116510X0205Y0590R090 S1      
327m8267            U26   -CF72       A01X+031542Y+109079X0177Y    R180 S1      
327m8267            J24   -250        A01X+021783Y+112829X0205Y0590R090 S1      
327m8268            U26   -BY72       A01X+031542Y+107166X0177Y    R180 S1      
327m8268            J24   -239        A01X+021783Y+109148X0205Y0590R090 S1      
327m8269            U26   -DB74       A01X+030802Y+114181X0177Y    R180 S1      
327m8269            J24   -137        A01X+023397Y+123203X0205Y0590R090 S1      
327m8270            U26   -CT74       A01X+030802Y+112268X0177Y    R180 S1      
327m8270            J24   -126        A01X+023397Y+119522X0205Y0590R090 S1      
327m8271            U26   -CK74       A01X+030802Y+110354X0177Y    R180 S1      
327m8271            J24   -115        A01X+023397Y+115841X0205Y0590R090 S1      
327m8272            U26   -CD74       A01X+030802Y+108441X0177Y    R180 S1      
327m8272            J24   -104        A01X+023397Y+112160X0205Y0590R090 S1      
327m8273            U26   -BW74       A01X+030987Y+106847X0177Y    R180 S1      
327m8273            J24   -94         A01X+023397Y+108813X0205Y0590R090 S1      
327m8274            U26   -DC73       A01X+031357Y+114500X0177Y    R180 S1      
327m8274            J24   -282        A01X+021783Y+123538X0205Y0590R090 S1      
327m8275            U26   -CU73       A01X+031357Y+112587X0177Y    R180 S1      
327m8275            J24   -271        A01X+021783Y+119856X0205Y0590R090 S1      
327m8276            U26   -CL73       A01X+031357Y+110673X0177Y    R180 S1      
327m8276            J24   -260        A01X+021783Y+116175X0205Y0590R090 S1      
327m8277            U26   -CE73       A01X+031357Y+108760X0177Y    R180 S1      
327m8277            J24   -249        A01X+021783Y+112494X0205Y0590R090 S1      
327m8278            U26   -BW73       A01X+031357Y+106847X0177Y    R180 S1      
327m8278            J24   -238        A01X+021783Y+108813X0205Y0590R090 S1      
327m8279            U26   -DC74       A01X+030987Y+114500X0177Y    R180 S1      
327m8279            J24   -138        A01X+023397Y+123538X0205Y0590R090 S1      
327m8280            U26   -CU74       A01X+030987Y+112587X0177Y    R180 S1      
327m8280            J24   -127        A01X+023397Y+119856X0205Y0590R090 S1      
327m8281            U26   -CL74       A01X+030987Y+110673X0177Y    R180 S1      
327m8281            J24   -116        A01X+023397Y+116175X0205Y0590R090 S1      
327m8282            U26   -CE74       A01X+030987Y+108760X0177Y    R180 S1      
327m8282            J24   -105        A01X+023397Y+112494X0205Y0590R090 S1      
327m8283            U26   -CJ73       A01X+031357Y+110036X0177Y    R180 S1      
327m8283            J24   -113        A01X+023397Y+115171X0205Y0590R090 S1      
327m8284            U26   -CH74       A01X+030802Y+109717X0177Y    R180 S1      
327m8284            J24   -111        A01X+023397Y+114502X0205Y0590R090 S1      
327m8285            U26   -CH72       A01X+031542Y+109717X0177Y    R180 S1      
327m8285            J24   -254        A01X+021783Y+114168X0205Y0590R090 S1      
327m8286            U26   -CG74       A01X+030987Y+109398X0177Y    R180 S1      
327m8286            J24   -252        A01X+021783Y+113498X0205Y0590R090 S1      
327m8287            U26   -CG73       A01X+031357Y+109398X0177Y    R180 S1      
327m8287            J24   -109        A01X+023397Y+113833X0205Y0590R090 S1      
327m8288            U26   -CF74       A01X+030802Y+109079X0177Y    R180 S1      
327m8288            J24   -107        A01X+023397Y+113164X0205Y0590R090 S1      
327m8289            U26   -CD72       A01X+031542Y+108441X0177Y    R180 S1      
327m8289            J24   -247        A01X+021783Y+111825X0205Y0590R090 S1      
327m8290            U26   -DF74       A01X+030802Y+115457X0177Y    R180 S1      
327m8290            J24   -287        A01X+021783Y+125211X0205Y0590R090 S1      
327m8291            U26   -DE74       A01X+030987Y+115138X0177Y    R180 S1      
327m8291            J24   -285        A01X+021783Y+124542X0205Y0590R090 S1      
327m8292            U26   -CC74       A01X+030987Y+108122X0177Y    R180 S1      
327m8292            J24   -245        A01X+021783Y+111156X0205Y0590R090 S1      
327m8293            U26   -DE73       A01X+031357Y+115138X0177Y    R180 S1      
327m8293            J24   -142        A01X+023397Y+124876X0205Y0590R090 S1      
327m8294            U26   -DD74       A01X+030802Y+114819X0177Y    R180 S1      
327m8294            J24   -140        A01X+023397Y+124207X0205Y0590R090 S1      
327m8295            U26   -DB72       A01X+031542Y+114181X0177Y    R180 S1      
327m8295            J24   -280        A01X+021783Y+122868X0205Y0590R090 S1      
327m8296            U26   -DA74       A01X+030987Y+113862X0177Y    R180 S1      
327m8296            J24   -278        A01X+021783Y+122199X0205Y0590R090 S1      
327m8297            U26   -DA73       A01X+031357Y+113862X0177Y    R180 S1      
327m8297            J24   -135        A01X+023397Y+122534X0205Y0590R090 S1      
327m8298            U26   -CY74       A01X+030802Y+113543X0177Y    R180 S1      
327m8298            J24   -133        A01X+023397Y+121864X0205Y0590R090 S1      
327m8299            U26   -CY72       A01X+031542Y+113543X0177Y    R180 S1      
327m8299            J24   -276        A01X+021783Y+121530X0205Y0590R090 S1      
327m8300            U26   -CW74       A01X+030987Y+113225X0177Y    R180 S1      
327m8300            J24   -274        A01X+021783Y+120860X0205Y0590R090 S1      
327m8301            U26   -CW73       A01X+031357Y+113225X0177Y    R180 S1      
327m8301            J24   -131        A01X+023397Y+121195X0205Y0590R090 S1      
327m8302            U26   -CV74       A01X+030802Y+112906X0177Y    R180 S1      
327m8302            J24   -129        A01X+023397Y+120526X0205Y0590R090 S1      
327m8303            U26   -CC73       A01X+031357Y+108122X0177Y    R180 S1      
327m8303            J24   -102        A01X+023397Y+111490X0205Y0590R090 S1      
327m8304            U26   -CT72       A01X+031542Y+112268X0177Y    R180 S1      
327m8304            J24   -269        A01X+021783Y+119187X0205Y0590R090 S1      
327m8305            U26   -CR74       A01X+030987Y+111949X0177Y    R180 S1      
327m8305            J24   -267        A01X+021783Y+118518X0205Y0590R090 S1      
327m8306            U26   -CR73       A01X+031357Y+111949X0177Y    R180 S1      
327m8306            J24   -124        A01X+023397Y+118852X0205Y0590R090 S1      
327m8307            U26   -CP74       A01X+030802Y+111630X0177Y    R180 S1      
327m8307            J24   -122        A01X+023397Y+118183X0205Y0590R090 S1      
327m8308            U26   -CP72       A01X+031542Y+111630X0177Y    R180 S1      
327m8308            J24   -265        A01X+021783Y+117849X0205Y0590R090 S1      
327m8309            U26   -CN74       A01X+030987Y+111311X0177Y    R180 S1      
327m8309            J24   -263        A01X+021783Y+117179X0205Y0590R090 S1      
327m8310            U26   -CN73       A01X+031357Y+111311X0177Y    R180 S1      
327m8310            J24   -120        A01X+023397Y+117514X0205Y0590R090 S1      
327m8311            U26   -CM74       A01X+030802Y+110992X0177Y    R180 S1      
327m8311            J24   -118        A01X+023397Y+116845X0205Y0590R090 S1      
327m8312            U26   -CK72       A01X+031542Y+110354X0177Y    R180 S1      
327m8312            J24   -258        A01X+021783Y+115506X0205Y0590R090 S1      
327m8313            U26   -CJ74       A01X+030987Y+110036X0177Y    R180 S1      
327m8313            J24   -256        A01X+021783Y+114837X0205Y0590R090 S1      
327m8314            U26   -CB74       A01X+030802Y+107803X0177Y    R180 S1      
327m8314            J24   -100        A01X+023397Y+110821X0205Y0590R090 S1      
327m8315            U26   -BN74       A01X+030987Y+104933X0177Y    R180 S1      
327m8315            J24   -229        A01X+021783Y+105801X0205Y0590R090 S1      
327m8316            U26   -BM72       A01X+031542Y+104614X0177Y    R180 S1      
327m8316            J24   -84         A01X+023397Y+105467X0205Y0590R090 S1      
327m8317            U26   -BV72       A01X+031542Y+106528X0177Y    R180 S1      
327m8317            J24   -236        A01X+021783Y+108144X0205Y0590R090 S1      
327m8318            U26   -BU74       A01X+030987Y+106209X0177Y    R180 S1      
327m8318            J24   -234        A01X+021783Y+107474X0205Y0590R090 S1      
327m8319            U26   -BU73       A01X+031357Y+106209X0177Y    R180 S1      
327m8319            J24   -91         A01X+023397Y+107809X0205Y0590R090 S1      
327m8320            U26   -BT74       A01X+030802Y+105890X0177Y    R180 S1      
327m8320            J24   -89         A01X+023397Y+107140X0205Y0590R090 S1      
327m8321            U26   -CB72       A01X+031542Y+107803X0177Y    R180 S1      
327m8321            J24   -243        A01X+021783Y+110486X0205Y0590R090 S1      
327m8322            U26   -CA74       A01X+030987Y+107484X0177Y    R180 S1      
327m8322            J24   -241        A01X+021783Y+109817X0205Y0590R090 S1      
327m8323            U26   -CA73       A01X+031357Y+107484X0177Y    R180 S1      
327m8323            J24   -98         A01X+023397Y+110152X0205Y0590R090 S1      
327m8324            U26   -BY74       A01X+030802Y+107166X0177Y    R180 S1      
327m8324            J24   -96         A01X+023397Y+109482X0205Y0590R090 S1      
327m8325            U26   -BK74       A01X+030802Y+103976X0177Y    R180 S1      
327m8325            J24   -82         A01X+023397Y+104797X0205Y0590R090 S1      
327m8326            U26   -BK72       A01X+031542Y+103976X0177Y    R180 S1      
327m8326            J24   -225        A01X+021783Y+104463X0205Y0590R090 S1      
327m8327            U26   -BJ73       A01X+031357Y+103658X0177Y    R180 S1      
327m8327            J24   -80         A01X+023397Y+104128X0205Y0590R090 S1      
327m8328            U26   -BJ74       A01X+030987Y+103658X0177Y    R180 S1      
327m8328            J24   -223        A01X+021783Y+103793X0205Y0590R090 S1      
327m8329            U26   -BH74       A01X+030802Y+103339X0177Y    R180 S1      
327m8329            J24   -78         A01X+023397Y+103459X0205Y0590R090 S1      
327m8330            U26   -BH72       A01X+031542Y+103339X0177Y    R180 S1      
327m8330            J24   -221        A01X+021783Y+103124X0205Y0590R090 S1      
327m8331            U26   -BG73       A01X+031357Y+103020X0177Y    R180 S1      
327m8331            J24   -76         A01X+023397Y+102790X0205Y0590R090 S1      
327m8332            U26   -BN73       A01X+031357Y+104933X0177Y    R180 S1      
327m8332            J24   -86         A01X+023397Y+106136X0205Y0590R090 S1      
327m8333            U26   -BC73       A01X+031239Y+100823X0177Y    R180 S1      
327m8333            J24   -74         A01X+023397Y+100112X0205Y0590R090 S1      
327m8334            U26   -AN73       A01X+031239Y+097634X0177Y    R180 S1      
327m8334            J24   -201        A01X+021783Y+094423X0205Y0590R090 S1      
327m8335            U26   -AG73       A01X+031239Y+095721X0177Y    R180 S1      
327m8335            J24   -190        A01X+021783Y+090742X0205Y0590R090 S1      
327m8336            U26   -AA73       A01X+031239Y+093807X0177Y    R180 S1      
327m8336            J24   -179        A01X+021783Y+087061X0205Y0590R090 S1      
327m8337            U26   -R73        A01X+031239Y+091894X0177Y    R180 S1      
327m8337            J24   -168        A01X+021783Y+083380X0205Y0590R090 S1      
327m8338            U26   -J73        A01X+031239Y+089980X0177Y    R180 S1      
327m8338            J24   -157        A01X+021783Y+079699X0205Y0590R090 S1      
327m8339            U26   -AL74       A01X+030869Y+096996X0177Y    R180 S1      
327m8339            J24   -55         A01X+023397Y+093754X0205Y0590R090 S1      
327m8340            U26   -AE74       A01X+030869Y+095083X0177Y    R180 S1      
327m8340            J24   -44         A01X+023397Y+090073X0205Y0590R090 S1      
327m8341            U26   -W74        A01X+030869Y+093169X0177Y    R180 S1      
327m8341            J24   -33         A01X+023397Y+086392X0205Y0590R090 S1      
327m8342            U26   -N74        A01X+030869Y+091256X0177Y    R180 S1      
327m8342            J24   -22         A01X+023397Y+082711X0205Y0590R090 S1      
327m8343            U26   -G74        A01X+030869Y+089343X0177Y    R180 S1      
327m8343            J24   -11         A01X+023397Y+079030X0205Y0590R090 S1      
327m8344            U26   -AM72       A01X+031424Y+097315X0177Y    R180 S1      
327m8344            J24   -200        A01X+021783Y+094089X0205Y0590R090 S1      
327m8345            U26   -AF72       A01X+031424Y+095402X0177Y    R180 S1      
327m8345            J24   -189        A01X+021783Y+090408X0205Y0590R090 S1      
327m8346            U26   -Y72        A01X+031424Y+093488X0177Y    R180 S1      
327m8346            J24   -178        A01X+021783Y+086726X0205Y0590R090 S1      
327m8347            U26   -P72        A01X+031424Y+091575X0177Y    R180 S1      
327m8347            J24   -167        A01X+021783Y+083045X0205Y0590R090 S1      
327m8348            U26   -H72        A01X+031424Y+089662X0177Y    R180 S1      
327m8348            J24   -156        A01X+021783Y+079364X0205Y0590R090 S1      
327m8349            U26   -AM74       A01X+030684Y+097315X0177Y    R180 S1      
327m8349            J24   -56         A01X+023397Y+094089X0205Y0590R090 S1      
327m8350            U26   -AF74       A01X+030684Y+095402X0177Y    R180 S1      
327m8350            J24   -45         A01X+023397Y+090408X0205Y0590R090 S1      
327m8351            U26   -Y74        A01X+030684Y+093488X0177Y    R180 S1      
327m8351            J24   -34         A01X+023397Y+086726X0205Y0590R090 S1      
327m8352            U26   -P74        A01X+030684Y+091575X0177Y    R180 S1      
327m8352            J24   -23         A01X+023397Y+083045X0205Y0590R090 S1      
327m8353            U26   -H74        A01X+030684Y+089662X0177Y    R180 S1      
327m8353            J24   -12         A01X+023397Y+079364X0205Y0590R090 S1      
327m8354            U26   -M72        A01X+031424Y+090937X0177Y    R180 S1      
327m8354            J24   -20         A01X+023397Y+082042X0205Y0590R090 S1      
327m8355            U26   -L74        A01X+030869Y+090618X0177Y    R180 S1      
327m8355            J24   -18         A01X+023397Y+081372X0205Y0590R090 S1      
327m8356            U26   -L73        A01X+031239Y+090618X0177Y    R180 S1      
327m8356            J24   -161        A01X+021783Y+081038X0205Y0590R090 S1      
327m8357            U26   -K74        A01X+030684Y+090299X0177Y    R180 S1      
327m8357            J24   -159        A01X+021783Y+080368X0205Y0590R090 S1      
327m8358            U26   -K72        A01X+031424Y+090299X0177Y    R180 S1      
327m8358            J24   -16         A01X+023397Y+080703X0205Y0590R090 S1      
327m8359            U26   -J74        A01X+030869Y+089980X0177Y    R180 S1      
327m8359            J24   -14         A01X+023397Y+080034X0205Y0590R090 S1      
327m8360            U26   -G73        A01X+031239Y+089343X0177Y    R180 S1      
327m8360            J24   -154        A01X+021783Y+078695X0205Y0590R090 S1      
327m8361            U26   -AJ73       A01X+031239Y+096358X0177Y    R180 S1      
327m8361            J24   -194        A01X+021783Y+092081X0205Y0590R090 S1      
327m8362            U26   -AH74       A01X+030684Y+096040X0177Y    R180 S1      
327m8362            J24   -192        A01X+021783Y+091412X0205Y0590R090 S1      
327m8363            U26   -F74        A01X+030684Y+089024X0177Y    R180 S1      
327m8363            J24   -152        A01X+021783Y+078026X0205Y0590R090 S1      
327m8364            U26   -AH72       A01X+031424Y+096040X0177Y    R180 S1      
327m8364            J24   -49         A01X+023397Y+091746X0205Y0590R090 S1      
327m8365            U26   -AG74       A01X+030869Y+095721X0177Y    R180 S1      
327m8365            J24   -47         A01X+023397Y+091077X0205Y0590R090 S1      
327m8366            U26   -AE73       A01X+031239Y+095083X0177Y    R180 S1      
327m8366            J24   -187        A01X+021783Y+089738X0205Y0590R090 S1      
327m8367            U26   -AD74       A01X+030684Y+094764X0177Y    R180 S1      
327m8367            J24   -185        A01X+021783Y+089069X0205Y0590R090 S1      
327m8368            U26   -AD72       A01X+031424Y+094764X0177Y    R180 S1      
327m8368            J24   -42         A01X+023397Y+089404X0205Y0590R090 S1      
327m8369            U26   -AC74       A01X+030869Y+094445X0177Y    R180 S1      
327m8369            J24   -40         A01X+023397Y+088734X0205Y0590R090 S1      
327m8370            U26   -AC73       A01X+031239Y+094445X0177Y    R180 S1      
327m8370            J24   -183        A01X+021783Y+088400X0205Y0590R090 S1      
327m8371            U26   -AB74       A01X+030684Y+094126X0177Y    R180 S1      
327m8371            J24   -181        A01X+021783Y+087730X0205Y0590R090 S1      
327m8372            U26   -AB72       A01X+031424Y+094126X0177Y    R180 S1      
327m8372            J24   -38         A01X+023397Y+088065X0205Y0590R090 S1      
327m8373            U26   -AA74       A01X+030869Y+093807X0177Y    R180 S1      
327m8373            J24   -36         A01X+023397Y+087396X0205Y0590R090 S1      
327m8374            U26   -F72        A01X+031424Y+089024X0177Y    R180 S1      
327m8374            J24   -9          A01X+023397Y+078360X0205Y0590R090 S1      
327m8375            U26   -W73        A01X+031239Y+093169X0177Y    R180 S1      
327m8375            J24   -176        A01X+021783Y+086057X0205Y0590R090 S1      
327m8376            U26   -V74        A01X+030684Y+092850X0177Y    R180 S1      
327m8376            J24   -174        A01X+021783Y+085388X0205Y0590R090 S1      
327m8377            U26   -V72        A01X+031424Y+092850X0177Y    R180 S1      
327m8377            J24   -31         A01X+023397Y+085723X0205Y0590R090 S1      
327m8378            U26   -U74        A01X+030869Y+092532X0177Y    R180 S1      
327m8378            J24   -29         A01X+023397Y+085053X0205Y0590R090 S1      
327m8379            U26   -U73        A01X+031239Y+092532X0177Y    R180 S1      
327m8379            J24   -172        A01X+021783Y+084719X0205Y0590R090 S1      
327m8380            U26   -T74        A01X+030684Y+092213X0177Y    R180 S1      
327m8380            J24   -170        A01X+021783Y+084049X0205Y0590R090 S1      
327m8381            U26   -T72        A01X+031424Y+092213X0177Y    R180 S1      
327m8381            J24   -27         A01X+023397Y+084384X0205Y0590R090 S1      
327m8382            U26   -R74        A01X+030869Y+091894X0177Y    R180 S1      
327m8382            J24   -25         A01X+023397Y+083715X0205Y0590R090 S1      
327m8383            U26   -N73        A01X+031239Y+091256X0177Y    R180 S1      
327m8383            J24   -165        A01X+021783Y+082376X0205Y0590R090 S1      
327m8384            U26   -M74        A01X+030684Y+090937X0177Y    R180 S1      
327m8384            J24   -163        A01X+021783Y+081707X0205Y0590R090 S1      
327m8385            U26   -E74        A01X+030869Y+088705X0177Y    R180 S1      
327m8385            J24   -7          A01X+023397Y+077691X0205Y0590R090 S1      
327m8386            U26   -AW73       A01X+031239Y+099547X0177Y    R180 S1      
327m8386            J24   -209        A01X+021783Y+097100X0205Y0590R090 S1      
327m8387            U26   -AV74       A01X+030684Y+099228X0177Y    R180 S1      
327m8387            J24   -64         A01X+023397Y+096766X0205Y0590R090 S1      
327m8388            U26   -AR73       A01X+031239Y+098272X0177Y    R180 S1      
327m8388            J24   -205        A01X+021783Y+095762X0205Y0590R090 S1      
327m8389            U26   -AP74       A01X+030684Y+097953X0177Y    R180 S1      
327m8389            J24   -203        A01X+021783Y+095093X0205Y0590R090 S1      
327m8390            U26   -AP72       A01X+031424Y+097953X0177Y    R180 S1      
327m8390            J24   -60         A01X+023397Y+095427X0205Y0590R090 S1      
327m8391            U26   -AN74       A01X+030869Y+097634X0177Y    R180 S1      
327m8391            J24   -58         A01X+023397Y+094758X0205Y0590R090 S1      
327m8392            U26   -AL73       A01X+031239Y+096996X0177Y    R180 S1      
327m8392            J24   -198        A01X+021783Y+093419X0205Y0590R090 S1      
327m8393            U26   -AK74       A01X+030684Y+096677X0177Y    R180 S1      
327m8393            J24   -196        A01X+021783Y+092750X0205Y0590R090 S1      
327m8394            U26   -AK72       A01X+031424Y+096677X0177Y    R180 S1      
327m8394            J24   -53         A01X+023397Y+093085X0205Y0590R090 S1      
327m8395            U26   -AJ74       A01X+030869Y+096358X0177Y    R180 S1      
327m8395            J24   -51         A01X+023397Y+092416X0205Y0590R090 S1      
327m8396            U26   -BB72       A01X+031424Y+100504X0177Y    R180 S1      
327m8396            J24   -72         A01X+023397Y+099443X0205Y0590R090 S1      
327m8397            U26   -BB74       A01X+030684Y+100504X0177Y    R180 S1      
327m8397            J24   -215        A01X+021783Y+099108X0205Y0590R090 S1      
327m8398            U26   -BA74       A01X+030869Y+100185X0177Y    R180 S1      
327m8398            J24   -70         A01X+023397Y+098774X0205Y0590R090 S1      
327m8399            U26   -BA73       A01X+031239Y+100185X0177Y    R180 S1      
327m8399            J24   -213        A01X+021783Y+098439X0205Y0590R090 S1      
327m8400            U26   -AY72       A01X+031424Y+099866X0177Y    R180 S1      
327m8400            J24   -68         A01X+023397Y+098104X0205Y0590R090 S1      
327m8401            U26   -AY74       A01X+030684Y+099866X0177Y    R180 S1      
327m8401            J24   -211        A01X+021783Y+097770X0205Y0590R090 S1      
327m8402            U26   -AW74       A01X+030869Y+099547X0177Y    R180 S1      
327m8402            J24   -66         A01X+023397Y+097435X0205Y0590R090 S1      
327m8403            U26   -AT74       A01X+030684Y+098591X0177Y    R180 S1      
327m8403            J24   -207        A01X+021783Y+096431X0205Y0590R090 S1      
327m8404            U26   -BC74       A01X+030869Y+100823X0177Y    R180 S1      
327m8404            J24   -217        A01X+021783Y+099778X0205Y0590R090 S1      
327m8405            U26   -BD74       A01X+030684Y+101142X0177Y    R180 S1      
327m8405            J24   -218        A01X+021783Y+100112X0205Y0590R090 S1      
327m8406            U26   -AR74       A01X+030869Y+098272X0177Y    R180 S1      
327m8406            R500  -2          A18X+022754Y+096097X0198Y0197     S2      
317m8406            VIA   -    MD0100PA00X+022754Y+096097X0190Y    R180 S0      
327m8407            J24   -62         A01X+023397Y+096097X0205Y0590R090 S1      
317m8407            VIA   -    MD0100PA00X+023397Y+096097X0190Y         S0      
327m8407            R500  -1          A18X+023069Y+096097X0198Y0197     S2      
327m8408            U25   -BP74       A01X+128416Y+105252X0177Y    R180 S1      
327m8408            J1    -87         A01X+121011Y+106470X0205Y0590R090 S1      
327m8409            U25   -BL74       A01X+128602Y+104295X0177Y    R180 S1      
327m8409            J1    -227        A01X+119397Y+105132X0205Y0590R090 S1      
327m8410            U25   -BV74       A01X+128416Y+106528X0177Y    R180 S1      
327m8410            J1    -93         A01X+121011Y+108478X0205Y0590R090 S1      
327m8411            U25   -DD72       A01X+129157Y+114819X0177Y    R180 S1      
327m8411            J1    -283        A01X+119397Y+123872X0205Y0590R090 S1      
327m8412            U25   -CV72       A01X+129157Y+112906X0177Y    R180 S1      
327m8412            J1    -272        A01X+119397Y+120191X0205Y0590R090 S1      
327m8413            U25   -CM72       A01X+129157Y+110992X0177Y    R180 S1      
327m8413            J1    -261        A01X+119397Y+116510X0205Y0590R090 S1      
327m8414            U25   -CF72       A01X+129157Y+109079X0177Y    R180 S1      
327m8414            J1    -250        A01X+119397Y+112829X0205Y0590R090 S1      
327m8415            U25   -BY72       A01X+129157Y+107165X0177Y    R180 S1      
327m8415            J1    -239        A01X+119397Y+109148X0205Y0590R090 S1      
327m8416            U25   -DB74       A01X+128416Y+114181X0177Y    R180 S1      
327m8416            J1    -137        A01X+121011Y+123203X0205Y0590R090 S1      
327m8417            U25   -CT74       A01X+128416Y+112268X0177Y    R180 S1      
327m8417            J1    -126        A01X+121011Y+119522X0205Y0590R090 S1      
327m8418            U25   -CK74       A01X+128416Y+110354X0177Y    R180 S1      
327m8418            J1    -115        A01X+121011Y+115841X0205Y0590R090 S1      
327m8419            U25   -CD74       A01X+128416Y+108441X0177Y    R180 S1      
327m8419            J1    -104        A01X+121011Y+112160X0205Y0590R090 S1      
327m8420            U25   -BW74       A01X+128602Y+106846X0177Y    R180 S1      
327m8420            J1    -94         A01X+121011Y+108813X0205Y0590R090 S1      
327m8421            U25   -DC73       A01X+128972Y+114500X0177Y    R180 S1      
327m8421            J1    -282        A01X+119397Y+123537X0205Y0590R090 S1      
327m8422            U25   -CU73       A01X+128972Y+112587X0177Y    R180 S1      
327m8422            J1    -271        A01X+119397Y+119856X0205Y0590R090 S1      
327m8423            U25   -CL73       A01X+128972Y+110673X0177Y    R180 S1      
327m8423            J1    -260        A01X+119397Y+116175X0205Y0590R090 S1      
327m8424            U25   -CE73       A01X+128972Y+108760X0177Y    R180 S1      
327m8424            J1    -249        A01X+119397Y+112494X0205Y0590R090 S1      
327m8425            U25   -BW73       A01X+128972Y+106846X0177Y    R180 S1      
327m8425            J1    -238        A01X+119397Y+108813X0205Y0590R090 S1      
327m8426            U25   -DC74       A01X+128602Y+114500X0177Y    R180 S1      
327m8426            J1    -138        A01X+121011Y+123537X0205Y0590R090 S1      
327m8427            U25   -CU74       A01X+128602Y+112587X0177Y    R180 S1      
327m8427            J1    -127        A01X+121011Y+119856X0205Y0590R090 S1      
327m8428            U25   -CL74       A01X+128602Y+110673X0177Y    R180 S1      
327m8428            J1    -116        A01X+121011Y+116175X0205Y0590R090 S1      
327m8429            U25   -CE74       A01X+128602Y+108760X0177Y    R180 S1      
327m8429            J1    -105        A01X+121011Y+112494X0205Y0590R090 S1      
327m8430            U25   -CJ73       A01X+128972Y+110036X0177Y    R180 S1      
327m8430            J1    -113        A01X+121011Y+115171X0205Y0590R090 S1      
327m8431            U25   -CH74       A01X+128416Y+109717X0177Y    R180 S1      
327m8431            J1    -111        A01X+121011Y+114502X0205Y0590R090 S1      
327m8432            U25   -CH72       A01X+129157Y+109717X0177Y    R180 S1      
327m8432            J1    -254        A01X+119397Y+114167X0205Y0590R090 S1      
327m8433            U25   -CG74       A01X+128602Y+109398X0177Y    R180 S1      
327m8433            J1    -252        A01X+119397Y+113498X0205Y0590R090 S1      
327m8434            U25   -CG73       A01X+128972Y+109398X0177Y    R180 S1      
327m8434            J1    -109        A01X+121011Y+113833X0205Y0590R090 S1      
327m8435            U25   -CF74       A01X+128416Y+109079X0177Y    R180 S1      
327m8435            J1    -107        A01X+121011Y+113163X0205Y0590R090 S1      
327m8436            U25   -CD72       A01X+129157Y+108441X0177Y    R180 S1      
327m8436            J1    -247        A01X+119397Y+111825X0205Y0590R090 S1      
327m8437            U25   -DF74       A01X+128416Y+115457X0177Y    R180 S1      
327m8437            J1    -287        A01X+119397Y+125211X0205Y0590R090 S1      
327m8438            U25   -DE74       A01X+128602Y+115138X0177Y    R180 S1      
327m8438            J1    -285        A01X+119397Y+124541X0205Y0590R090 S1      
327m8439            U25   -CC74       A01X+128602Y+108122X0177Y    R180 S1      
327m8439            J1    -245        A01X+119397Y+111156X0205Y0590R090 S1      
327m8440            U25   -DE73       A01X+128972Y+115138X0177Y    R180 S1      
327m8440            J1    -142        A01X+121011Y+124876X0205Y0590R090 S1      
327m8441            U25   -DD74       A01X+128416Y+114819X0177Y    R180 S1      
327m8441            J1    -140        A01X+121011Y+124207X0205Y0590R090 S1      
327m8442            U25   -DB72       A01X+129157Y+114181X0177Y    R180 S1      
327m8442            J1    -280        A01X+119397Y+122868X0205Y0590R090 S1      
327m8443            U25   -DA74       A01X+128602Y+113862X0177Y    R180 S1      
327m8443            J1    -278        A01X+119397Y+122199X0205Y0590R090 S1      
327m8444            U25   -DA73       A01X+128972Y+113862X0177Y    R180 S1      
327m8444            J1    -135        A01X+121011Y+122534X0205Y0590R090 S1      
327m8445            U25   -CY74       A01X+128416Y+113543X0177Y    R180 S1      
327m8445            J1    -133        A01X+121011Y+121864X0205Y0590R090 S1      
327m8446            U25   -CY72       A01X+129157Y+113543X0177Y    R180 S1      
327m8446            J1    -276        A01X+119397Y+121530X0205Y0590R090 S1      
327m8447            U25   -CW74       A01X+128602Y+113224X0177Y    R180 S1      
327m8447            J1    -274        A01X+119397Y+120860X0205Y0590R090 S1      
327m8448            U25   -CW73       A01X+128972Y+113224X0177Y    R180 S1      
327m8448            J1    -131        A01X+121011Y+121195X0205Y0590R090 S1      
327m8449            U25   -CV74       A01X+128416Y+112906X0177Y    R180 S1      
327m8449            J1    -129        A01X+121011Y+120526X0205Y0590R090 S1      
327m8450            U25   -CC73       A01X+128972Y+108122X0177Y    R180 S1      
327m8450            J1    -102        A01X+121011Y+111490X0205Y0590R090 S1      
327m8451            U25   -CT72       A01X+129157Y+112268X0177Y    R180 S1      
327m8451            J1    -269        A01X+119397Y+119187X0205Y0590R090 S1      
327m8452            U25   -CR74       A01X+128602Y+111949X0177Y    R180 S1      
327m8452            J1    -267        A01X+119397Y+118518X0205Y0590R090 S1      
327m8453            U25   -CR73       A01X+128972Y+111949X0177Y    R180 S1      
327m8453            J1    -124        A01X+121011Y+118852X0205Y0590R090 S1      
327m8454            U25   -CP74       A01X+128416Y+111630X0177Y    R180 S1      
327m8454            J1    -122        A01X+121011Y+118183X0205Y0590R090 S1      
327m8455            U25   -CP72       A01X+129157Y+111630X0177Y    R180 S1      
327m8455            J1    -265        A01X+119397Y+117848X0205Y0590R090 S1      
327m8456            U25   -CN74       A01X+128602Y+111311X0177Y    R180 S1      
327m8456            J1    -263        A01X+119397Y+117179X0205Y0590R090 S1      
327m8457            U25   -CN73       A01X+128972Y+111311X0177Y    R180 S1      
327m8457            J1    -120        A01X+121011Y+117514X0205Y0590R090 S1      
327m8458            U25   -CM74       A01X+128416Y+110992X0177Y    R180 S1      
327m8458            J1    -118        A01X+121011Y+116844X0205Y0590R090 S1      
327m8459            U25   -CK72       A01X+129157Y+110354X0177Y    R180 S1      
327m8459            J1    -258        A01X+119397Y+115506X0205Y0590R090 S1      
327m8460            U25   -CJ74       A01X+128602Y+110036X0177Y    R180 S1      
327m8460            J1    -256        A01X+119397Y+114837X0205Y0590R090 S1      
327m8461            U25   -CB74       A01X+128416Y+107803X0177Y    R180 S1      
327m8461            J1    -100        A01X+121011Y+110821X0205Y0590R090 S1      
327m8462            U25   -BN74       A01X+128602Y+104933X0177Y    R180 S1      
327m8462            J1    -229        A01X+119397Y+105801X0205Y0590R090 S1      
327m8463            U25   -BM72       A01X+129157Y+104614X0177Y    R180 S1      
327m8463            J1    -84         A01X+121011Y+105467X0205Y0590R090 S1      
327m8464            U25   -BV72       A01X+129157Y+106528X0177Y    R180 S1      
327m8464            J1    -236        A01X+119397Y+108144X0205Y0590R090 S1      
327m8465            U25   -BU74       A01X+128602Y+106209X0177Y    R180 S1      
327m8465            J1    -234        A01X+119397Y+107474X0205Y0590R090 S1      
327m8466            U25   -BU73       A01X+128972Y+106209X0177Y    R180 S1      
327m8466            J1    -91         A01X+121011Y+107809X0205Y0590R090 S1      
327m8467            U25   -BT74       A01X+128416Y+105890X0177Y    R180 S1      
327m8467            J1    -89         A01X+121011Y+107140X0205Y0590R090 S1      
327m8468            U25   -CB72       A01X+129157Y+107803X0177Y    R180 S1      
327m8468            J1    -243        A01X+119397Y+110486X0205Y0590R090 S1      
327m8469            U25   -CA74       A01X+128602Y+107484X0177Y    R180 S1      
327m8469            J1    -241        A01X+119397Y+109817X0205Y0590R090 S1      
327m8470            U25   -CA73       A01X+128972Y+107484X0177Y    R180 S1      
327m8470            J1    -98         A01X+121011Y+110152X0205Y0590R090 S1      
327m8471            U25   -BY74       A01X+128416Y+107165X0177Y    R180 S1      
327m8471            J1    -96         A01X+121011Y+109482X0205Y0590R090 S1      
327m8472            U25   -BK74       A01X+128416Y+103976X0177Y    R180 S1      
327m8472            J1    -82         A01X+121011Y+104797X0205Y0590R090 S1      
327m8473            U25   -BK72       A01X+129157Y+103976X0177Y    R180 S1      
327m8473            J1    -225        A01X+119397Y+104463X0205Y0590R090 S1      
327m8474            U25   -BJ73       A01X+128972Y+103658X0177Y    R180 S1      
327m8474            J1    -80         A01X+121011Y+104128X0205Y0590R090 S1      
327m8475            U25   -BJ74       A01X+128602Y+103658X0177Y    R180 S1      
327m8475            J1    -223        A01X+119397Y+103793X0205Y0590R090 S1      
327m8476            U25   -BH74       A01X+128416Y+103339X0177Y    R180 S1      
327m8476            J1    -78         A01X+121011Y+103459X0205Y0590R090 S1      
327m8477            U25   -BH72       A01X+129157Y+103339X0177Y    R180 S1      
327m8477            J1    -221        A01X+119397Y+103124X0205Y0590R090 S1      
327m8478            U25   -BG73       A01X+128972Y+103020X0177Y    R180 S1      
327m8478            J1    -76         A01X+121011Y+102789X0205Y0590R090 S1      
327m8479            U25   -BN73       A01X+128972Y+104933X0177Y    R180 S1      
327m8479            J1    -86         A01X+121011Y+106136X0205Y0590R090 S1      
327m8480            U25   -BC73       A01X+128854Y+100823X0177Y    R180 S1      
327m8480            J1    -74         A01X+121011Y+100112X0205Y0590R090 S1      
327m8481            U25   -AN73       A01X+128854Y+097634X0177Y    R180 S1      
327m8481            J1    -201        A01X+119397Y+094423X0205Y0590R090 S1      
327m8482            U25   -AG73       A01X+128854Y+095720X0177Y    R180 S1      
327m8482            J1    -190        A01X+119397Y+090742X0205Y0590R090 S1      
327m8483            U25   -AA73       A01X+128854Y+093807X0177Y    R180 S1      
327m8483            J1    -179        A01X+119397Y+087061X0205Y0590R090 S1      
327m8484            U25   -R73        A01X+128854Y+091894X0177Y    R180 S1      
327m8484            J1    -168        A01X+119397Y+083380X0205Y0590R090 S1      
327m8485            U25   -J73        A01X+128854Y+089980X0177Y    R180 S1      
327m8485            J1    -157        A01X+119397Y+079699X0205Y0590R090 S1      
327m8486            U25   -AL74       A01X+128484Y+096996X0177Y    R180 S1      
327m8486            J1    -55         A01X+121011Y+093754X0205Y0590R090 S1      
327m8487            U25   -AE74       A01X+128484Y+095083X0177Y    R180 S1      
327m8487            J1    -44         A01X+121011Y+090073X0205Y0590R090 S1      
327m8488            U25   -W74        A01X+128484Y+093169X0177Y    R180 S1      
327m8488            J1    -33         A01X+121011Y+086392X0205Y0590R090 S1      
327m8489            U25   -N74        A01X+128484Y+091256X0177Y    R180 S1      
327m8489            J1    -22         A01X+121011Y+082711X0205Y0590R090 S1      
327m8490            U25   -G74        A01X+128484Y+089343X0177Y    R180 S1      
327m8490            J1    -11         A01X+121011Y+079030X0205Y0590R090 S1      
327m8491            U25   -AM72       A01X+129039Y+097315X0177Y    R180 S1      
327m8491            J1    -200        A01X+119397Y+094089X0205Y0590R090 S1      
327m8492            U25   -AF72       A01X+129039Y+095402X0177Y    R180 S1      
327m8492            J1    -189        A01X+119397Y+090408X0205Y0590R090 S1      
327m8493            U25   -Y72        A01X+129039Y+093488X0177Y    R180 S1      
327m8493            J1    -178        A01X+119397Y+086726X0205Y0590R090 S1      
327m8494            U25   -P72        A01X+129039Y+091575X0177Y    R180 S1      
327m8494            J1    -167        A01X+119397Y+083045X0205Y0590R090 S1      
327m8495            U25   -H72        A01X+129039Y+089662X0177Y    R180 S1      
327m8495            J1    -156        A01X+119397Y+079364X0205Y0590R090 S1      
327m8496            U25   -AM74       A01X+128298Y+097315X0177Y    R180 S1      
327m8496            J1    -56         A01X+121011Y+094089X0205Y0590R090 S1      
327m8497            U25   -AF74       A01X+128298Y+095402X0177Y    R180 S1      
327m8497            J1    -45         A01X+121011Y+090408X0205Y0590R090 S1      
327m8498            U25   -Y74        A01X+128298Y+093488X0177Y    R180 S1      
327m8498            J1    -34         A01X+121011Y+086726X0205Y0590R090 S1      
327m8499            U25   -P74        A01X+128298Y+091575X0177Y    R180 S1      
327m8499            J1    -23         A01X+121011Y+083045X0205Y0590R090 S1      
327m8500            U25   -H74        A01X+128298Y+089662X0177Y    R180 S1      
327m8500            J1    -12         A01X+121011Y+079364X0205Y0590R090 S1      
327m8501            U25   -M72        A01X+129039Y+090937X0177Y    R180 S1      
327m8501            J1    -20         A01X+121011Y+082041X0205Y0590R090 S1      
327m8502            U25   -L74        A01X+128484Y+090618X0177Y    R180 S1      
327m8502            J1    -18         A01X+121011Y+081372X0205Y0590R090 S1      
327m8503            U25   -L73        A01X+128854Y+090618X0177Y    R180 S1      
327m8503            J1    -161        A01X+119397Y+081037X0205Y0590R090 S1      
327m8504            U25   -K74        A01X+128298Y+090299X0177Y    R180 S1      
327m8504            J1    -159        A01X+119397Y+080368X0205Y0590R090 S1      
327m8505            U25   -K72        A01X+129039Y+090299X0177Y    R180 S1      
327m8505            J1    -16         A01X+121011Y+080703X0205Y0590R090 S1      
327m8506            U25   -J74        A01X+128484Y+089980X0177Y    R180 S1      
327m8506            J1    -14         A01X+121011Y+080034X0205Y0590R090 S1      
327m8507            U25   -G73        A01X+128854Y+089343X0177Y    R180 S1      
327m8507            J1    -154        A01X+119397Y+078695X0205Y0590R090 S1      
327m8508            U25   -AJ73       A01X+128854Y+096358X0177Y    R180 S1      
327m8508            J1    -194        A01X+119397Y+092081X0205Y0590R090 S1      
327m8509            U25   -AH74       A01X+128298Y+096039X0177Y    R180 S1      
327m8509            J1    -192        A01X+119397Y+091411X0205Y0590R090 S1      
327m8510            U25   -F74        A01X+128298Y+089024X0177Y    R180 S1      
327m8510            J1    -152        A01X+119397Y+078026X0205Y0590R090 S1      
327m8511            U25   -AH72       A01X+129039Y+096039X0177Y    R180 S1      
327m8511            J1    -49         A01X+121011Y+091746X0205Y0590R090 S1      
327m8512            U25   -AG74       A01X+128484Y+095720X0177Y    R180 S1      
327m8512            J1    -47         A01X+121011Y+091077X0205Y0590R090 S1      
327m8513            U25   -AE73       A01X+128854Y+095083X0177Y    R180 S1      
327m8513            J1    -187        A01X+119397Y+089738X0205Y0590R090 S1      
327m8514            U25   -AD74       A01X+128298Y+094764X0177Y    R180 S1      
327m8514            J1    -185        A01X+119397Y+089069X0205Y0590R090 S1      
327m8515            U25   -AD72       A01X+129039Y+094764X0177Y    R180 S1      
327m8515            J1    -42         A01X+121011Y+089404X0205Y0590R090 S1      
327m8516            U25   -AC74       A01X+128484Y+094445X0177Y    R180 S1      
327m8516            J1    -40         A01X+121011Y+088734X0205Y0590R090 S1      
327m8517            U25   -AC73       A01X+128854Y+094445X0177Y    R180 S1      
327m8517            J1    -183        A01X+119397Y+088400X0205Y0590R090 S1      
327m8518            U25   -AB74       A01X+128298Y+094126X0177Y    R180 S1      
327m8518            J1    -181        A01X+119397Y+087730X0205Y0590R090 S1      
327m8519            U25   -AB72       A01X+129039Y+094126X0177Y    R180 S1      
327m8519            J1    -38         A01X+121011Y+088065X0205Y0590R090 S1      
327m8520            U25   -AA74       A01X+128484Y+093807X0177Y    R180 S1      
327m8520            J1    -36         A01X+121011Y+087396X0205Y0590R090 S1      
327m8521            U25   -F72        A01X+129039Y+089024X0177Y    R180 S1      
327m8521            J1    -9          A01X+121011Y+078360X0205Y0590R090 S1      
327m8522            U25   -W73        A01X+128854Y+093169X0177Y    R180 S1      
327m8522            J1    -176        A01X+119397Y+086057X0205Y0590R090 S1      
327m8523            U25   -V74        A01X+128298Y+092850X0177Y    R180 S1      
327m8523            J1    -174        A01X+119397Y+085388X0205Y0590R090 S1      
327m8524            U25   -V72        A01X+129039Y+092850X0177Y    R180 S1      
327m8524            J1    -31         A01X+121011Y+085722X0205Y0590R090 S1      
327m8525            U25   -U74        A01X+128484Y+092532X0177Y    R180 S1      
327m8525            J1    -29         A01X+121011Y+085053X0205Y0590R090 S1      
327m8526            U25   -U73        A01X+128854Y+092532X0177Y    R180 S1      
327m8526            J1    -172        A01X+119397Y+084718X0205Y0590R090 S1      
327m8527            U25   -T74        A01X+128298Y+092213X0177Y    R180 S1      
327m8527            J1    -170        A01X+119397Y+084049X0205Y0590R090 S1      
327m8528            U25   -T72        A01X+129039Y+092213X0177Y    R180 S1      
327m8528            J1    -27         A01X+121011Y+084384X0205Y0590R090 S1      
327m8529            U25   -R74        A01X+128484Y+091894X0177Y    R180 S1      
327m8529            J1    -25         A01X+121011Y+083715X0205Y0590R090 S1      
327m8530            U25   -N73        A01X+128854Y+091256X0177Y    R180 S1      
327m8530            J1    -165        A01X+119397Y+082376X0205Y0590R090 S1      
327m8531            U25   -M74        A01X+128298Y+090937X0177Y    R180 S1      
327m8531            J1    -163        A01X+119397Y+081707X0205Y0590R090 S1      
327m8532            U25   -E74        A01X+128484Y+088705X0177Y    R180 S1      
327m8532            J1    -7          A01X+121011Y+077691X0205Y0590R090 S1      
327m8533            U25   -AW73       A01X+128854Y+099547X0177Y    R180 S1      
327m8533            J1    -209        A01X+119397Y+097100X0205Y0590R090 S1      
327m8534            U25   -AV74       A01X+128298Y+099228X0177Y    R180 S1      
327m8534            J1    -64         A01X+121011Y+096766X0205Y0590R090 S1      
327m8535            U25   -AR73       A01X+128854Y+098272X0177Y    R180 S1      
327m8535            J1    -205        A01X+119397Y+095762X0205Y0590R090 S1      
327m8536            U25   -AP74       A01X+128298Y+097953X0177Y    R180 S1      
327m8536            J1    -203        A01X+119397Y+095092X0205Y0590R090 S1      
327m8537            U25   -AP72       A01X+129039Y+097953X0177Y    R180 S1      
327m8537            J1    -60         A01X+121011Y+095427X0205Y0590R090 S1      
327m8538            U25   -AN74       A01X+128484Y+097634X0177Y    R180 S1      
327m8538            J1    -58         A01X+121011Y+094758X0205Y0590R090 S1      
327m8539            U25   -AL73       A01X+128854Y+096996X0177Y    R180 S1      
327m8539            J1    -198        A01X+119397Y+093419X0205Y0590R090 S1      
327m8540            U25   -AK74       A01X+128298Y+096677X0177Y    R180 S1      
327m8540            J1    -196        A01X+119397Y+092750X0205Y0590R090 S1      
327m8541            U25   -AK72       A01X+129039Y+096677X0177Y    R180 S1      
327m8541            J1    -53         A01X+121011Y+093085X0205Y0590R090 S1      
327m8542            U25   -AJ74       A01X+128484Y+096358X0177Y    R180 S1      
327m8542            J1    -51         A01X+121011Y+092415X0205Y0590R090 S1      
327m8543            U25   -BB72       A01X+129039Y+100504X0177Y    R180 S1      
327m8543            J1    -72         A01X+121011Y+099443X0205Y0590R090 S1      
327m8544            U25   -BB74       A01X+128298Y+100504X0177Y    R180 S1      
327m8544            J1    -215        A01X+119397Y+099108X0205Y0590R090 S1      
327m8545            U25   -BA74       A01X+128484Y+100185X0177Y    R180 S1      
327m8545            J1    -70         A01X+121011Y+098774X0205Y0590R090 S1      
327m8546            U25   -BA73       A01X+128854Y+100185X0177Y    R180 S1      
327m8546            J1    -213        A01X+119397Y+098439X0205Y0590R090 S1      
327m8547            U25   -AY72       A01X+129039Y+099866X0177Y    R180 S1      
327m8547            J1    -68         A01X+121011Y+098104X0205Y0590R090 S1      
327m8548            U25   -AY74       A01X+128298Y+099866X0177Y    R180 S1      
327m8548            J1    -211        A01X+119397Y+097770X0205Y0590R090 S1      
327m8549            U25   -AW74       A01X+128484Y+099547X0177Y    R180 S1      
327m8549            J1    -66         A01X+121011Y+097435X0205Y0590R090 S1      
327m8550            U25   -AT74       A01X+128298Y+098591X0177Y    R180 S1      
327m8550            J1    -207        A01X+119397Y+096431X0205Y0590R090 S1      
327m8551            U25   -BC74       A01X+128484Y+100823X0177Y    R180 S1      
327m8551            J1    -217        A01X+119397Y+099778X0205Y0590R090 S1      
327m8552            U25   -BD74       A01X+128298Y+101142X0177Y    R180 S1      
327m8552            J1    -218        A01X+119397Y+100112X0205Y0590R090 S1      
327m8553            U25   -AR74       A01X+128484Y+098272X0177Y    R180 S1      
327m8553            R375  -2          A18X+120368Y+096096X0198Y0197     S2      
317m8553            VIA   -    MD0100PA00X+120368Y+096096X0190Y         S0      
327m8554            J1    -62         A01X+121011Y+096096X0205Y0590R090 S1      
317m8554            VIA   -    MD0100PA00X+121011Y+096096X0190Y         S0      
327m8554            R375  -1          A18X+120683Y+096096X0198Y0197     S2      
317m8555            VIA   -    MD0100PA00X+155315Y+047906X0200Y         S0      
317m8555            VIA   -    MD0100PA00X+122209Y+029707X0200Y    R270 S0      
317m8555            VIA   -    MD0100PA00X+087764Y+031579X0200Y         S0      
327m8555            R3048 -1   M      A18X+122209Y+029957X0198Y0197R270 S2      
327m8555            R3047 -1          A18X+122609Y+029957X0198Y0197R270 S2      
317m8555            VIA   -    MD0100PA00X+123400Y+038550X0200Y         S0      
317m8555            VIA   -    MD0100PA00X+088837Y+054752X0200Y         S0      
317m8555            VIA   -    MD0100PA00X+102943Y+058734X0200Y         S0      
317m8555            VIA   -    MD0100PA00X+084474Y+054386X0200Y         S0      
327m8555            R2531 -1          A01X+084190Y+054537X0198Y0197R270 S1      
317m8555            VIA   -    MD0100PA00X+090081Y+143780X0200Y         S0      
327m8555            R6097 -1          A01X+161054Y+054273X0198Y0197     S1      
317m8555            VIA   -    MD0100PA00X+075816Y+150260X0200Y    R090 S0      
327m8555            PJ38  -15         A01X+076291Y+150260X0240Y0650R090 S1      
327m8555            PU289 -13         A01X+071881Y+159117X0090Y0150     S1      
317m8555            VIA   -    M      A01X+070938Y+160121X0300Y    R270 S1      
017m8555            VIA   -    M      A18X+070938Y+160121X0200Y    R270 S1      
017m8555                  -    MD0100PA00X+070938Y+160121                       
327m8555            R3933 -2          A01X+070508Y+160850X0198Y0197     S1      
327m8555            R1117 -1   M      A01X+070508Y+160450X0198Y0197R180 S1      
327m8556            J59   -52         A01X+066755Y+017146X0110Y0630R270 S1      
327m8556            VIA   -    M      A01X+065416Y+016920X0300Y         S1      
327m8556            R155  -2          A01X+064939Y+016605X0198Y0197     S1      
327m8556            R153  -2   M      A01X+064939Y+017005X0198Y0197     S1      
327m8557            U259  -1          A01X+056591Y+040372X0140Y0440R270 S1      
317m8557            VIA   -    M      A01X+056221Y+040472X0200Y    R090 S2      
017m8557            VIA   -    M      A18X+056221Y+040472X0260Y    R090 S2      
017m8557                  -    MD0100PA00X+056221Y+040472                       
327m8557            R6053 -1          A01X+073550Y+039329X0198Y0197R090 S1      
317m8557            VIA   -    MD0100PA00X+073550Y+039086X0200Y    R090 S0      
317m8557            VIA   -    MD0100PA00X+060333Y+042953X0200Y         S0      
317m8557            VIA   -    MD0100PA00X+060353Y+023000X0200Y         S0      
317m8557            VIA   -    MD0100PA00X+064092Y+016939X0200Y         S0      
327m8557            R138  -1          A01X+064629Y+017420X0198Y0197     S1      
327m8557            R153  -1   M      A01X+064624Y+017005X0198Y0197     S1      
327M2_0_PEWAKE_N    R3301 -2          A01X+064939Y+016186X0198Y0197     S1      
327M2_0_PEWAKE_N    J59   -54         A01X+066755Y+016949X0110Y0630R270 S1      
327M2_0_PEWAKE_N    VIA   -    M      A01X+065447Y+016397X0300Y         S1      
327m8558            J59   -10         A01X+066755Y+021280X0110Y0630R270 S1      
317m8558            VIA   -    MD0100PA00X+067823Y+021577X0200Y         S0      
327m8558            R3294 -1          A01X+059024Y+040029X0198Y0197     S1      
317m8558            VIA   -    M      A01X+058771Y+039929X0200Y    R270 S2      
017m8558            VIA   -    M      A18X+058771Y+039929X0260Y    R270 S2      
017m8558                  -    MD0100PA00X+058771Y+039929                       
327m8559            R3294 -2          A01X+059338Y+040029X0198Y0197     S1      
327m8559            U239  -2          A01X+060324Y+040429X0170Y0240R270 S1      
327m8559            R3295 -2   M      A01X+059338Y+040429X0198Y0197     S1      
327m8559            VIA   -    M      A01X+059818Y+040429X0300Y         S1      
327m8560            R6075 -1          A01X+073150Y+036329X0198Y0197R090 S1      
317m8560            VIA   -    MD0100PA00X+073150Y+036086X0200Y         S0      
317m8560            VIA   -    M      A01X+061798Y+040173X0200Y    R090 S2      
017m8560            VIA   -    M      A18X+061798Y+040173X0260Y    R090 S2      
017m8560                  -    MD0100PA00X+061798Y+040173                       
327m8560            U239  -4          A01X+061072Y+040173X0170Y0240R270 S1      
327m8560            R3297 -1   M      A01X+061538Y+040173X0198Y0197R270 S1      
327m8560            R3254 -2          A01X+051554Y+008572X0198Y0197R090 S1      
317m8560            VIA   -    MD0100PA00X+050480Y+008632X0200Y    R090 S0      
317m8560            VIA   -    MD0100PA00X+052468Y+041760X0200Y         S0      
327m8561            R1444 -2          A01X+132002Y+006140X0198Y0197R270 S1      
327m8561            VIA   -    M      A01X+132002Y+005660X0300Y         S1      
327m8561            D9    -A          A01X+132553Y+006082X0240Y0280R090 S1      
327m8562            Q29   -G          A01X+132754Y+008369X0400Y0480R180 S1      
327m8562            VIA   -    M      A01X+133340Y+008771X0300Y         S1      
327m8562            Q30   -D          A01X+132360Y+009251X0400Y0480R180 S1      
327m8562            R1507 -2   M      A01X+133340Y+009251X0198Y0197R270 S1      
327m8563            VIA   -    M      A01X+132944Y+007045X0300Y    R270 S1      
327m8563            D9    -C          A01X+132553Y+006456X0240Y0280R090 S1      
327m8563            Q29   -D          A01X+132360Y+007487X0400Y0480R180 S1      
327JTAG_TRST_R_N    R1635 -1          A01X+102454Y+038876X0198Y0197R180 S1      
327JTAG_TRST_R_N    VIA   -    M      A01X+102927Y+038624X0300Y    R090 S1      
327JTAG_TRST_R_N    U148  -12         A01X+104042Y+042194X0140Y0630R090 S1      
327JTAG_TRST_R_N    U149  -12  M      A01X+104004Y+038624X0140Y0630R090 S1      
327JTAG_TRST_N      U151  -5          A01X+111916Y+038571X0140Y0630R090 S1      
327JTAG_TRST_N      VIA   -    M      A01X+112741Y+038627X0300Y         S1      
327JTAG_TRST_N      C1511 -1   M      A01X+113333Y+038570X0198Y0197     S1      
327JTAG_TRST_N      R1635 -2          A01X+102139Y+038876X0198Y0197R180 S1      
327JTAG_TRST_N      U150  -5   M      A01X+099434Y+040105X0140Y0630R180 S1      
327JTAG_TMS_R       U148  -13         A01X+104042Y+041938X0140Y0630R090 S1      
327JTAG_TMS_R       U149  -13  M      A01X+104004Y+038368X0140Y0630R090 S1      
327JTAG_TMS_R       VIA   -    M      A01X+103307Y+038276X0300Y    R090 S1      
327JTAG_TMS_R       R1634 -1          A01X+102454Y+038376X0198Y0197R180 S1      
327JTAG_TMS         VIA   -    M      A01X+113871Y+037050X0300Y         S1      
327JTAG_TMS         U151  -4          A01X+111916Y+038315X0140Y0630R090 S1      
327JTAG_TMS         R1634 -2          A01X+102139Y+038376X0198Y0197R180 S1      
327JTAG_TMS         U150  -4   M      A01X+099690Y+040105X0140Y0630R180 S1      
317JTAG_TDO         VIA   -    MD0100PA00X+050824Y+019951X0200Y    R270 S0      
327JTAG_TDO         R6109 -1          A01X+050820Y+020240X0198Y0197     S1      
317JTAG_TDO         VIA   -    M      A01X+049414Y+022137X0200Y    R090 S2      
017JTAG_TDO         VIA   -    M      A18X+049414Y+022137X0260Y    R090 S2      
017JTAG_TDO               -    MD0100PA00X+049414Y+022137                       
327JTAG_TDO         R6111 -2          A01X+049414Y+021880X0198Y0197R090 S1      
317JTAG_TDI_R       VIA   -    MD0100PA00X+056880Y+022193X0200Y    R180 S0      
327JTAG_TDI_R       U147  -5          A01X+057234Y+022392X0070Y0320R270 S1      
317JTAG_TDI_R       VIA   -    M      A01X+049683Y+020503X0200Y    R270 S2      
017JTAG_TDI_R       VIA   -    M      A18X+049683Y+020503X0260Y    R270 S2      
017JTAG_TDI_R             -    MD0100PA00X+049683Y+020503                       
327JTAG_TDI_R       R1625 -1          A01X+050120Y+020528X0198Y0197     S1      
317JTAG_TDI_R       VIA   -    MD0100PA00X+049164Y+022597X0200Y    R270 S0      
327JTAG_TDI_R       U146  -5          A01X+048830Y+021723X0070Y0320R090 S1      
327JTAG_TDI         U152  -8          A01X+051050Y+020974X0070Y0320R180 S1      
317JTAG_TDI         VIA   -           A01X+050435Y+020278X0200Y         S2      
017JTAG_TDI         VIA   -           A18X+050435Y+020278X0260Y         S2      
017JTAG_TDI               -     D0100PA00X+050435Y+020278                       
327JTAG_TDI         R1625 -2   M      A01X+050435Y+020528X0198Y0197     S1      
327JTAG_TDI         C86   -1   M      A01X+050435Y+020928X0198Y0197R180 S1      
327JTAG_TCK_R       VIA   -    M      A01X+102927Y+037876X0300Y    R090 S1      
327JTAG_TCK_R       U148  -14         A01X+104042Y+041682X0140Y0630R090 S1      
327JTAG_TCK_R       U149  -14  M      A01X+104004Y+038112X0140Y0630R090 S1      
327JTAG_TCK_R       R1633 -1          A01X+102454Y+037876X0198Y0197R180 S1      
327JTAG_TCK         VIA   -    M      A01X+112810Y+037686X0300Y         S1      
327JTAG_TCK         C1510 -1   M      A01X+113333Y+038053X0198Y0197     S1      
327JTAG_TCK         U151  -3          A01X+111916Y+038059X0140Y0630R090 S1      
327JTAG_TCK         R1633 -2          A01X+102139Y+037876X0198Y0197R180 S1      
327JTAG_TCK         U150  -3   M      A01X+099946Y+040105X0140Y0630R180 S1      
327m8564            U18   -D11        A01X+070678Y+045139X0160Y    R090 S1      
327m8564            VIA   -    M      A01X+068025Y+045207X0300Y         S1      
327m8564            R160  -1          A01X+067558Y+044986X0198Y0197R180 S1      
327m8565            U148  -5          A01X+106247Y+042194X0140Y0630R090 S1      
317m8565            VIA   -    M      A01X+107274Y+042192X0200Y         S2      
017m8565            VIA   -    M      A18X+107274Y+042192X0260Y         S2      
017m8565                  -    MD0100PA00X+107274Y+042192                       
327m8565            R160  -2          A01X+067242Y+044986X0198Y0197R180 S1      
317m8565            VIA   -    MD0100PA00X+066200Y+044986X0200Y    R270 S0      
327JTAG_SCM_TMS     J41   -A35        A01X+061046Y+005354X0150Y0570R180 S1      
327JTAG_SCM_TMS     U160  -3          A01X+042890Y+023544X0160Y0540R270 S1      
327JTAG_SCM_TMS     R1731 -2          A01X+041752Y+023544X0198Y0197     S1      
317JTAG_SCM_TMS     VIA   -    M      A01X+042012Y+023544X0200Y         S2      
017JTAG_SCM_TMS     VIA   -    M      A18X+042012Y+023544X0260Y         S2      
017JTAG_SCM_TMS           -    MD0100PA00X+042012Y+023544                       
317JTAG_SCM_TMS     VIA   -    MD0100PA00X+061873Y+003991X0200Y         S0      
327JTAG_SCM_TDO     R6068 -2   M      A18X+060857Y+003575X0180Y0200R270 S2      
327JTAG_SCM_TDO     R6069 -2          A18X+060857Y+003575X0180Y0200R090 S2      
327JTAG_SCM_TDO     U212  -3          A01X+050694Y+023812X0160Y0540R270 S1      
317JTAG_SCM_TDO     VIA   -    MD0100PA00X+061261Y+003596X0200Y         S0      
317JTAG_SCM_TDO     VIA   -    M      A01X+050532Y+019694X0200Y         S2      
017JTAG_SCM_TDO     VIA   -    M      A18X+050532Y+019694X0260Y         S2      
017JTAG_SCM_TDO           -    MD0100PA00X+050532Y+019694                       
317JTAG_SCM_TDO     VIA   -    MD0100PA00X+050021Y+023812X0200Y    R180 S0      
327JTAG_SCM_TDO     R1727 -2          A01X+049761Y+023812X0198Y0197     S1      
327JTAG_SCM_TDI     U212  -13         A01X+052998Y+023556X0160Y0540R270 S1      
327JTAG_SCM_TDI     R1728 -2          A01X+054341Y+023556X0198Y0197R180 S1      
317JTAG_SCM_TDI     VIA   -    MD0100PA00X+053428Y+023556X0200Y         S0      
317JTAG_SCM_TDI     VIA   -    M      A01X+051960Y+019612X0200Y         S2      
017JTAG_SCM_TDI     VIA   -    M      A18X+051960Y+019612X0260Y         S2      
017JTAG_SCM_TDI           -    MD0100PA00X+051960Y+019612                       
327JTAG_SCM_TDI     R6066 -2          A18X+051440Y+019647X0180Y0200R090 S2      
327JTAG_SCM_TDI     R6067 -2   M      A18X+051440Y+019647X0180Y0200R270 S2      
327JTAG_SCM_TCK     J41   -A34        A01X+061282Y+005354X0150Y0570R180 S1      
327JTAG_SCM_TCK     U160  -13         A01X+045193Y+023288X0160Y0540R270 S1      
327JTAG_SCM_TCK     R1734 -2          A01X+046582Y+023576X0198Y0197R180 S1      
327JTAG_SCM_TCK     R1735 -1   M      A01X+046582Y+023176X0198Y0197     S1      
317JTAG_SCM_TCK     VIA   -    M      A01X+045623Y+023288X0200Y    R180 S2      
017JTAG_SCM_TCK     VIA   -    M      A18X+045623Y+023288X0260Y    R180 S2      
017JTAG_SCM_TCK           -    MD0100PA00X+045623Y+023288                       
317JTAG_SCM_TCK     VIA   -    MD0100PA00X+061302Y+004272X0200Y         S0      
317m8566            VIA   -    MD0100PA00X+056509Y+024264X0200Y         S0      
327m8566            U18   -C10        A01X+070363Y+044824X0160Y    R090 S1      
317m8566            VIA   -    MD0100PA00X+070210Y+044670X0180Y    R090 S0      
327m8566            R1741 -2          A01X+041436Y+024050X0198Y0197R180 S1      
317m8566            VIA   -    M      A01X+041194Y+024050X0200Y    R180 S2      
017m8566            VIA   -    M      A18X+041194Y+024050X0260Y    R180 S2      
017m8566                  -    MD0100PA00X+041194Y+024050                       
327m8566            R14   -2   M      A18X+055897Y+025056X0198Y0197R090 S2      
317m8567            VIA   -    MD0100PA00X+070840Y+044356X0180Y    R090 S0      
327m8567            U18   -E9         A01X+070993Y+044509X0160Y    R090 S1      
327m8567            R13   -2   M      A18X+058897Y+025056X0198Y0197R090 S2      
317m8567            VIA   -           A01X+058897Y+024011X0200Y    R180 S2      
017m8567            VIA   -           A18X+058897Y+024011X0260Y    R180 S2      
017m8567                  -     D0100PA00X+058897Y+024011                       
327m8567            R1743 -2          A01X+049446Y+024318X0198Y0197R180 S1      
317m8567            VIA   -    MD0100PA00X+049158Y+024324X0200Y    R180 S0      
327m8568            R9    -2          A18X+065888Y+044450X0198Y0197R180 S2      
317m8568            VIA   -    MD0100PA00X+066155Y+044450X0200Y         S0      
327m8568            U18   -E8         A01X+070993Y+044194X0160Y    R090 S1      
317m8568            VIA   -    MD0100PA00X+070840Y+044040X0180Y    R090 S0      
327m8568            R1742 -2          A01X+054656Y+023044X0198Y0197     S1      
317m8568            VIA   -    M      A01X+054925Y+023044X0200Y         S2      
017m8568            VIA   -    M      A18X+054925Y+023044X0260Y         S2      
017m8568                  -    MD0100PA00X+054925Y+023044                       
317m8569            VIA   -    MD0100PA00X+055977Y+024318X0200Y         S0      
327m8569            U18   -D10        A01X+070678Y+044824X0160Y    R090 S1      
317m8569            VIA   -    MD0100PA00X+070524Y+044670X0180Y    R090 S0      
327m8569            R1740 -2          A01X+046897Y+022776X0198Y0197     S1      
317m8569            VIA   -    M      A01X+047137Y+022776X0200Y         S2      
017m8569            VIA   -    M      A18X+047137Y+022776X0260Y         S2      
017m8569                  -    MD0100PA00X+047137Y+022776                       
327m8569            R15   -2   M      A18X+053897Y+025056X0198Y0197R090 S2      
327m8569            R6090 -1   M      A18X+054303Y+025054X0198Y0197R270 S2      
327m8570            U160  -2   M      A01X+042890Y+023800X0160Y0540R270 S1      
327m8570            U160  -4          A01X+042890Y+023288X0160Y0540R270 S1      
327m8570            R1741 -1          A01X+041752Y+024050X0198Y0197R180 S1      
317m8570            VIA   -    M      A01X+042012Y+024050X0200Y         S2      
017m8570            VIA   -    M      A18X+042012Y+024050X0260Y         S2      
017m8570                  -    MD0100PA00X+042012Y+024050                       
327m8571            U212  -2   M      A01X+050694Y+024068X0160Y0540R270 S1      
327m8571            U212  -4          A01X+050694Y+023556X0160Y0540R270 S1      
327m8571            R1743 -1          A01X+049761Y+024318X0198Y0197R180 S1      
317m8571            VIA   -    M      A01X+050012Y+024317X0200Y         S2      
017m8571            VIA   -    M      A18X+050012Y+024317X0260Y         S2      
017m8571                  -    MD0100PA00X+050012Y+024317                       
327m8572            U212  -15         A01X+052998Y+024068X0160Y0540R270 S1      
327m8572            U212  -11  M      A01X+052998Y+023044X0160Y0540R270 S1      
327m8572            R1742 -1          A01X+054341Y+023044X0198Y0197     S1      
317m8572            VIA   -    M      A01X+053428Y+023044X0200Y    R180 S2      
017m8572            VIA   -    M      A18X+053428Y+023044X0260Y    R180 S2      
017m8572                  -    MD0100PA00X+053428Y+023044                       
327m8573            U160  -15         A01X+045193Y+023800X0160Y0540R270 S1      
327m8573            U160  -11  M      A01X+045193Y+022776X0160Y0540R270 S1      
327m8573            R1740 -1          A01X+046582Y+022776X0198Y0197     S1      
317m8573            VIA   -    M      A01X+045623Y+022776X0200Y    R180 S2      
017m8573            VIA   -    M      A18X+045623Y+022776X0260Y    R180 S2      
017m8573                  -    MD0100PA00X+045623Y+022776                       
317m8574            VIA   -    MD0100PA00X+046754Y+035686X0200Y         S0      
327m8574            R1737 -2   M      A01X+041436Y+023032X0198Y0197R180 S1      
327m8574            R1746 -2          A01X+041436Y+022632X0198Y0197R180 S1      
317m8574            VIA   -    M      A01X+107274Y+041676X0200Y         S2      
017m8574            VIA   -    M      A18X+107274Y+041676X0260Y         S2      
017m8574                  -    MD0100PA00X+107274Y+041676                       
327m8574            U148  -4          A01X+106247Y+041938X0140Y0630R090 S1      
317m8575            VIA   -    MD0100PA00X+058277Y+022142X0200Y    R180 S0      
327m8575            U147  -8          A01X+057943Y+022392X0070Y0320R270 S1      
327m8575            R1739 -2          A01X+049446Y+023300X0198Y0197R180 S1      
327m8575            R1745 -2          A01X+048926Y+023300X0198Y0197     S1      
317m8575            VIA   -    M      A01X+049186Y+023300X0200Y    R180 S2      
017m8575            VIA   -    M      A18X+049186Y+023300X0260Y    R180 S2      
017m8575                  -    MD0100PA00X+049186Y+023300                       
317m8576            VIA   -    MD0100PA00X+058277Y+022550X0200Y    R180 S0      
327m8576            U147  -9          A01X+057943Y+022550X0070Y0320R270 S1      
317m8576            VIA   -    M      A01X+054925Y+023765X0200Y         S2      
017m8576            VIA   -    M      A18X+054925Y+023765X0260Y         S2      
017m8576                  -    MD0100PA00X+054925Y+023765                       
327m8576            R1744 -2          A01X+055136Y+023957X0198Y0197R180 S1      
327m8576            R1738 -2          A01X+054656Y+023957X0198Y0197     S1      
327m8577            R1736 -2          A01X+046897Y+023976X0198Y0197     S1      
327m8577            R1747 -2   M      A01X+046897Y+024776X0198Y0197     S1      
327m8577            U148  -3          A01X+106247Y+041682X0140Y0630R090 S1      
317m8577            VIA   -    M      A01X+107274Y+041132X0200Y         S2      
017m8577            VIA   -    M      A18X+107274Y+041132X0260Y         S2      
017m8577                  -    MD0100PA00X+107274Y+041132                       
317m8577            VIA   -    MD0100PA00X+048783Y+035402X0200Y         S0      
327m8577            R1748 -1   M      A01X+046897Y+024376X0198Y0197R180 S1      
327m8578            U160  -5          A01X+042890Y+023032X0160Y0540R270 S1      
327m8578            R1737 -1          A01X+041752Y+023032X0198Y0197R180 S1      
317m8578            VIA   -    M      A01X+042012Y+023032X0200Y         S2      
017m8578            VIA   -    M      A18X+042012Y+023032X0260Y         S2      
017m8578                  -    MD0100PA00X+042012Y+023032                       
327m8579            U212  -5          A01X+050694Y+023300X0160Y0540R270 S1      
327m8579            R1739 -1          A01X+049761Y+023300X0198Y0197R180 S1      
317m8579            VIA   -    M      A01X+050021Y+023300X0200Y         S2      
017m8579            VIA   -    M      A18X+050021Y+023300X0260Y         S2      
017m8579                  -    MD0100PA00X+050021Y+023300                       
327m8580            U212  -14         A01X+052998Y+023812X0160Y0540R270 S1      
327m8580            R1738 -1          A01X+054341Y+023957X0198Y0197     S1      
317m8580            VIA   -    M      A01X+053861Y+023812X0200Y    R180 S2      
017m8580            VIA   -    M      A18X+053861Y+023812X0260Y    R180 S2      
017m8580                  -    MD0100PA00X+053861Y+023812                       
327m8581            U160  -14         A01X+045193Y+023544X0160Y0540R270 S1      
327m8581            R1736 -1          A01X+046582Y+023976X0198Y0197     S1      
317m8581            VIA   -    M      A01X+046057Y+023544X0200Y    R180 S2      
017m8581            VIA   -    M      A18X+046057Y+023544X0260Y    R180 S2      
017m8581                  -    MD0100PA00X+046057Y+023544                       
317m8582            VIA   -    MD0100PA00X+107882Y+026940X0200Y         S0      
317m8582            VIA   -    MD0100PA00X+056479Y+005891X0200Y         S0      
327m8582            R6032 -1          A18X+056020Y+005576X0198Y0197R090 S2      
317m8582            VIA   -    M      A01X+109006Y+042802X0200Y         S2      
017m8582            VIA   -    M      A18X+109006Y+042802X0260Y         S2      
017m8582                  -    MD0100PA00X+109006Y+042802                       
327m8582            U148  -6          A01X+106247Y+042450X0140Y0630R090 S1      
327m8582            R6070 -2   M      A01X+107553Y+042439X0198Y0197R270 S1      
317JTAG_PLD_TMS     J57   -6    D0460PA00X+055902Y+027427X0660Y    R180 S3      
327JTAG_PLD_TMS     VIA   -    M      A18X+055897Y+025840X0260Y         S2      
327JTAG_PLD_TMS     R14   -1          A18X+055897Y+025371X0198Y0197R090 S2      
317JTAG_PLD_TDO     J57   -3    D0460PA00X+058902Y+027427X0660Y    R180 S3      
327JTAG_PLD_TDO     VIA   -    M      A18X+059090Y+025826X0260Y         S2      
327JTAG_PLD_TDO     R13   -1          A18X+058897Y+025371X0198Y0197R090 S2      
317JTAG_PLD_TDI     J57   -2    D0460PA00X+059902Y+027427X0660Y    R180 S3      
317JTAG_PLD_TDI     VIA   -    MD0100PA00X+065138Y+044525X0200Y         S0      
327JTAG_PLD_TDI     R9    -1          A18X+065573Y+044450X0198Y0197R180 S2      
317JTAG_PLD_TDI     VIA   -    M      A01X+059897Y+023888X0200Y    R180 S2      
017JTAG_PLD_TDI     VIA   -    M      A18X+059897Y+023888X0260Y    R180 S2      
017JTAG_PLD_TDI           -    MD0100PA00X+059897Y+023888                       
317JTAG_PLD_TCK     J57   -8    D0460PA00X+053902Y+027427X0660Y    R180 S3      
327JTAG_PLD_TCK     VIA   -    M      A18X+053897Y+025826X0260Y         S2      
327JTAG_PLD_TCK     R15   -1          A18X+053897Y+025371X0198Y0197R090 S2      
327m8583            VIA   -    M      A01X+109004Y+038848X0300Y         S1      
327m8583            U151  -12         A01X+109711Y+038571X0140Y0630R090 S1      
327m8583            R1644 -1          A01X+108481Y+038723X0198Y0197R180 S1      
327JTAG_P1_R_TMS    VIA   -    M      A01X+108859Y+038251X0300Y         S1      
327JTAG_P1_R_TMS    U151  -13         A01X+109711Y+038315X0140Y0630R090 S1      
327JTAG_P1_R_TMS    R1643 -1          A01X+108481Y+038323X0198Y0197R180 S1      
327JTAG_P1_R_TCK    VIA   -    M      A01X+108856Y+037731X0300Y         S1      
327JTAG_P1_R_TCK    U151  -14         A01X+109711Y+038059X0140Y0630R090 S1      
327JTAG_P1_R_TCK    R1642 -1          A01X+108481Y+037923X0198Y0197R180 S1      
327m8584            VIA   -    M      A01X+108822Y+039417X0300Y         S1      
327m8584            U151  -11         A01X+109711Y+038826X0140Y0630R090 S1      
327m8584            R1645 -1          A01X+108481Y+039123X0198Y0197R180 S1      
317m8585            VIA   -    M      A01X+099246Y+037066X0200Y         S2      
017m8585            VIA   -    M      A18X+099246Y+037066X0260Y         S2      
017m8585                  -    MD0100PA00X+099246Y+037066                       
327m8585            R1640 -1          A01X+099246Y+036661X0198Y0197R270 S1      
327m8585            U150  -12         A01X+099434Y+037900X0140Y0630R180 S1      
317JTAG_P0_R_TMS    VIA   -    M      A01X+099689Y+037416X0200Y         S2      
017JTAG_P0_R_TMS    VIA   -    M      A18X+099689Y+037416X0260Y         S2      
017JTAG_P0_R_TMS          -    MD0100PA00X+099689Y+037416                       
327JTAG_P0_R_TMS    R1639 -1          A01X+099646Y+036661X0198Y0197R270 S1      
327JTAG_P0_R_TMS    U150  -13         A01X+099690Y+037900X0140Y0630R180 S1      
317JTAG_P0_R_TCK    VIA   -    M      A01X+100046Y+036954X0200Y         S2      
017JTAG_P0_R_TCK    VIA   -    M      A18X+100046Y+036954X0260Y         S2      
017JTAG_P0_R_TCK          -    MD0100PA00X+100046Y+036954                       
327JTAG_P0_R_TCK    R1638 -1          A01X+100046Y+036661X0198Y0197R270 S1      
327JTAG_P0_R_TCK    U150  -14         A01X+099946Y+037900X0140Y0630R180 S1      
327m8586            U150  -11         A01X+099179Y+037900X0140Y0630R180 S1      
327m8586            VIA   -    M      A01X+098865Y+037143X0300Y         S1      
327m8586            R1641 -1          A01X+098846Y+036661X0198Y0197R270 S1      
327JTAG_DBREQ_R_N   VIA   -    M      A01X+103345Y+042450X0300Y    R090 S1      
327JTAG_DBREQ_R_N   U148  -11         A01X+104042Y+042450X0140Y0630R090 S1      
327JTAG_DBREQ_R_N   U149  -11  M      A01X+104004Y+038880X0140Y0630R090 S1      
327JTAG_DBREQ_R_N   R1636 -1          A01X+102454Y+039376X0198Y0197R180 S1      
327JTAG_DBREQ_N     VIA   -    M      A01X+113140Y+039156X0300Y         S1      
327JTAG_DBREQ_N     U151  -6          A01X+111916Y+038826X0140Y0630R090 S1      
327JTAG_DBREQ_N     U150  -6   M      A01X+099179Y+040105X0140Y0630R180 S1      
327JTAG_DBREQ_N     R1636 -2          A01X+102139Y+039376X0198Y0197R180 S1      
327JTAG_DBREQ_N     C1512 -1   M      A01X+102138Y+039773X0198Y0197     S1      
327JTAG_CPUX_TDO    R6110 -2          A01X+094763Y+062866X0198Y0197     S1      
317JTAG_CPUX_TDO    VIA   -    M      A01X+095110Y+062866X0200Y         S2      
017JTAG_CPUX_TDO    VIA   -    M      A18X+095110Y+062866X0260Y         S2      
017JTAG_CPUX_TDO          -    MD0100PA00X+095110Y+062866                       
327JTAG_CPUX_TDO    U152  -4          A01X+051208Y+021683X0070Y0320R180 S1      
317JTAG_CPUX_TDO    VIA   -    MD0100PA00X+051168Y+022122X0200Y    R270 S0      
317JTAG_CPUX_TDI    VIA   -    MD0100PA00X+049938Y+022251X0200Y    R270 S0      
327JTAG_CPUX_TDI    R6103 -2          A01X+050120Y+022017X0198Y0197R180 S1      
317JTAG_CPUX_TDI    VIA   -    M      A01X+093731Y+058076X0200Y         S2      
017JTAG_CPUX_TDI    VIA   -    M      A18X+093731Y+058076X0260Y         S2      
017JTAG_CPUX_TDI          -    MD0100PA00X+093731Y+058076                       
327JTAG_CPUX_TDI    U153  -1          A01X+093146Y+058257X0140Y0520R090 S1      
327JTAG_CPUX_TDI    U153  -5          A01X+091689Y+059025X0140Y0520R090 S1      
317JTAG_CPUX_TDI    VIA   -    MD0100PA00X+091073Y+059025X0200Y         S0      
317m8587            VIA   -    MD0080PA00X+051778Y+087325X0160Y    R180 S0      
327m8587            U26   -A17        A01X+051594Y+087429X0177Y    R180 S1      
327m8587            R525  -2          A18X+059157Y+079361X0198Y0197R090 S2      
327m8587            C232  -1   M      A18X+059557Y+079361X0198Y0197R270 S2      
317m8587            VIA   -    MD0100PA00X+060283Y+079175X0200Y         S0      
317m8587            VIA   -    M      A01X+107425Y+038780X0200Y         S2      
017m8587            VIA   -    M      A18X+107425Y+038780X0260Y         S2      
017m8587                  -    MD0100PA00X+107425Y+038780                       
327m8587            R1644 -2          A01X+108166Y+038723X0198Y0197R180 S1      
317m8587            VIA   -    MD0100PA00X+065743Y+067476X0200Y         S0      
317JTAG_CPU1_TMS    VIA   -    MD0080PA00X+052148Y+087325X0160Y    R180 S0      
317JTAG_CPU1_TMS    VIA   -    MD0100PA00X+107840Y+038323X0200Y         S0      
317JTAG_CPU1_TMS    VIA   -    M      A01X+065023Y+067476X0200Y         S2      
017JTAG_CPU1_TMS    VIA   -    M      A18X+065023Y+067476X0260Y         S2      
017JTAG_CPU1_TMS          -    MD0100PA00X+065023Y+067476                       
327JTAG_CPU1_TMS    U26   -A16        A01X+051964Y+087429X0177Y    R180 S1      
317JTAG_CPU1_TMS    VIA   -    MD0100PA00X+059562Y+080608X0200Y         S0      
327JTAG_CPU1_TMS    C234  -1   M      A18X+057977Y+080031X0198Y0197R270 S2      
327JTAG_CPU1_TMS    R527  -2          A18X+057567Y+080031X0198Y0197R090 S2      
327JTAG_CPU1_TMS    R1643 -2          A01X+108166Y+038323X0198Y0197R180 S1      
317JTAG_CPU1_TDO    VIA   -    MD0100PA00X+069142Y+068038X0200Y         S0      
317JTAG_CPU1_TDO    VIA   -    MD0100PA00X+092499Y+062252X0200Y         S0      
327JTAG_CPU1_TDO    U154  -1          A01X+093146Y+062607X0140Y0520R090 S1      
317JTAG_CPU1_TDO    VIA   -    MD0100PA00X+069757Y+073045X0200Y         S0      
327JTAG_CPU1_TDO    VIA   -    M      A18X+061970Y+075876X0260Y    R180 S2      
327JTAG_CPU1_TDO    R529  -2          A18X+051808Y+083781X0198Y0197R090 S2      
327JTAG_CPU1_TDO    R523  -2   M      A18X+060377Y+078281X0198Y0197R090 S2      
327JTAG_CPU1_TDO    C230  -1   M      A18X+060767Y+078281X0198Y0197R270 S2      
317JTAG_CPU1_TDI    VIA   -    MD0080PA00X+051778Y+087962X0160Y    R180 S0      
327JTAG_CPU1_TDI    U26   -C17        A01X+051594Y+088067X0177Y    R180 S1      
317JTAG_CPU1_TDI    VIA   -    M      A01X+066018Y+067952X0200Y         S2      
017JTAG_CPU1_TDI    VIA   -    M      A18X+066018Y+067952X0260Y         S2      
017JTAG_CPU1_TDI          -    MD0100PA00X+066018Y+067952                       
317JTAG_CPU1_TDI    VIA   -    MD0100PA00X+095250Y+061408X0200Y         S0      
327JTAG_CPU1_TDI    R1651 -2          A01X+094881Y+061415X0198Y0197     S1      
317JTAG_CPU1_TDI    VIA   -    MD0100PA00X+061864Y+078358X0200Y         S0      
327JTAG_CPU1_TDI    R524  -2   M      A18X+061557Y+078281X0198Y0197R090 S2      
327JTAG_CPU1_TDI    C231  -1          A18X+061167Y+078281X0198Y0197R270 S2      
317JTAG_CPU1_TCK    VIA   -    MD0080PA00X+051962Y+087644X0160Y    R180 S0      
327JTAG_CPU1_TCK    U26   -B17        A01X+051779Y+087748X0177Y    R180 S1      
317JTAG_CPU1_TCK    VIA   -    MD0100PA00X+060374Y+079496X0200Y         S0      
327JTAG_CPU1_TCK    C233  -1          A18X+059947Y+079361X0198Y0197R270 S2      
327JTAG_CPU1_TCK    R526  -2   M      A18X+060326Y+079736X0198Y0197R090 S2      
317JTAG_CPU1_TCK    VIA   -    M      A01X+107465Y+038019X0200Y         S2      
017JTAG_CPU1_TCK    VIA   -    M      A18X+107465Y+038019X0260Y         S2      
017JTAG_CPU1_TCK          -    MD0100PA00X+107465Y+038019                       
327JTAG_CPU1_TCK    R1642 -2          A01X+108166Y+037923X0198Y0197R180 S1      
317JTAG_CPU1_TCK    VIA   -    MD0100PA00X+066263Y+067476X0200Y         S0      
317m8588            VIA   -    MD0080PA00X+051407Y+087962X0160Y    R180 S0      
327m8588            U26   -C18        A01X+051224Y+088067X0177Y    R180 S1      
327m8588            VIA   -    M      A18X+051808Y+084566X0260Y         S2      
327m8588            R529  -1          A18X+051808Y+084096X0198Y0197R090 S2      
327m8589            VIA   -    M      A01X+094086Y+061415X0300Y    R270 S1      
327m8589            U14   -2          A01X+093146Y+061413X0140Y0520R090 S1      
327m8589            R1651 -1          A01X+094566Y+061415X0198Y0197     S1      
317m8590            VIA   -    MD0080PA00X+052148Y+087962X0160Y    R180 S0      
327m8590            U26   -C16        A01X+051964Y+088067X0177Y    R180 S1      
317m8590            VIA   -    MD0100PA00X+059071Y+080419X0200Y         S0      
327m8590            C235  -1          A18X+058367Y+080041X0198Y0197R270 S2      
327m8590            R528  -2   M      A18X+058757Y+080041X0198Y0197R090 S2      
317m8590            VIA   -    M      A01X+107840Y+039123X0200Y         S2      
017m8590            VIA   -    M      A18X+107840Y+039123X0260Y         S2      
017m8590                  -    MD0100PA00X+107840Y+039123                       
327m8590            R1645 -2          A01X+108166Y+039123X0198Y0197R180 S1      
317m8590            VIA   -    MD0100PA00X+064645Y+067464X0200Y         S0      
317m8591            VIA   -    M      A01X+092099Y+061769X0200Y         S2      
017m8591            VIA   -    M      A18X+092099Y+061769X0260Y         S2      
017m8591                  -    MD0100PA00X+092099Y+061769                       
327m8591            U154  -5          A01X+091689Y+063375X0140Y0520R090 S1      
327m8591            U14   -6          A01X+091689Y+061669X0140Y0520R090 S1      
327m8592            U25   -A17        A01X+149208Y+087429X0177Y    R180 S1      
317m8592            VIA   -    MD0100PA00X+148676Y+082628X0200Y    R180 S0      
327m8592            R1640 -2          A01X+099246Y+036346X0198Y0197R270 S1      
317m8592            VIA   -    M      A01X+099346Y+035840X0200Y         S2      
017m8592            VIA   -    M      A18X+099346Y+035840X0260Y         S2      
017m8592                  -    MD0100PA00X+099346Y+035840                       
327m8592            R400  -2          A18X+147418Y+082256X0198Y0197R270 S2      
327m8592            C209  -1   M      A18X+147818Y+082256X0198Y0197R090 S2      
327JTAG_CPU0_TMS    U25   -A16        A01X+149578Y+087429X0177Y    R180 S1      
317JTAG_CPU0_TMS    VIA   -    MD0100PA00X+149567Y+082607X0200Y    R180 S0      
327JTAG_CPU0_TMS    R1639 -2          A01X+099646Y+036346X0198Y0197R270 S1      
317JTAG_CPU0_TMS    VIA   -    M      A01X+099846Y+035840X0200Y         S2      
017JTAG_CPU0_TMS    VIA   -    M      A18X+099846Y+035840X0260Y         S2      
017JTAG_CPU0_TMS          -    MD0100PA00X+099846Y+035840                       
327JTAG_CPU0_TMS    C211  -1   M      A18X+149418Y+082256X0198Y0197R090 S2      
327JTAG_CPU0_TMS    R402  -2          A18X+149018Y+082256X0198Y0197R270 S2      
317m8593            VIA   -    M      A01X+093575Y+061157X0200Y         S2      
017m8593            VIA   -    M      A18X+093575Y+061157X0260Y         S2      
017m8593                  -    MD0100PA00X+093575Y+061157                       
327m8593            U14   -5          A01X+091689Y+061925X0140Y0520R090 S1      
317m8593            VIA   -    MD0100PA00X+091054Y+061925X0200Y         S0      
327m8593            U14   -1          A01X+093146Y+061157X0140Y0520R090 S1      
327m8593            U13   -2          A01X+093146Y+059963X0140Y0520R090 S1      
327m8593            R6105 -2          A01X+090222Y+060218X0198Y0197R180 S1      
317m8593            VIA   -    MD0100PA00X+090032Y+060438X0200Y         S0      
317JTAG_CPU0_TDO    VIA   -    M      A01X+093951Y+059707X0200Y         S2      
017JTAG_CPU0_TDO    VIA   -    M      A18X+093951Y+059707X0260Y         S2      
017JTAG_CPU0_TDO          -    MD0100PA00X+093951Y+059707                       
327JTAG_CPU0_TDO    U13   -1          A01X+093146Y+059707X0140Y0520R090 S1      
317JTAG_CPU0_TDO    VIA   -    MD0100PA00X+148418Y+081299X0200Y    R180 S0      
327JTAG_CPU0_TDO    R398  -2   M      A18X+148118Y+080906X0198Y0197R270 S2      
327JTAG_CPU0_TDO    R404  -2          A18X+147318Y+080591X0198Y0197R090 S2      
327JTAG_CPU0_TDO    C207  -1   M      A18X+147718Y+080906X0198Y0197R090 S2      
327JTAG_CPU0_TDI    U25   -C17        A01X+149208Y+088067X0177Y    R180 S1      
317JTAG_CPU0_TDI    VIA   -    M      A01X+149818Y+082936X0200Y    R180 S2      
017JTAG_CPU0_TDI    VIA   -    M      A18X+149818Y+082936X0260Y    R180 S2      
017JTAG_CPU0_TDI          -    MD0100PA00X+149818Y+082936                       
317JTAG_CPU0_TDI    VIA   -    MD0100PA00X+094816Y+059391X0200Y         S0      
327JTAG_CPU0_TDI    R1648 -2          A01X+094812Y+058520X0198Y0197     S1      
327JTAG_CPU0_TDI    C1520 -1   M      A01X+094816Y+059042X0198Y0197R180 S1      
327JTAG_CPU0_TDI    R399  -2          A18X+150218Y+082256X0198Y0197R270 S2      
327JTAG_CPU0_TDI    C208  -1   M      A18X+149818Y+082256X0198Y0197R090 S2      
327JTAG_CPU0_TCK    U25   -B17        A01X+149393Y+087748X0177Y    R180 S1      
317JTAG_CPU0_TCK    VIA   -    MD0100PA00X+149097Y+082556X0200Y    R180 S0      
327JTAG_CPU0_TCK    R1638 -2          A01X+100046Y+036346X0198Y0197R270 S1      
317JTAG_CPU0_TCK    VIA   -    M      A01X+100346Y+035840X0200Y         S2      
017JTAG_CPU0_TCK    VIA   -    M      A18X+100346Y+035840X0260Y         S2      
017JTAG_CPU0_TCK          -    MD0100PA00X+100346Y+035840                       
327JTAG_CPU0_TCK    C210  -1          A18X+148218Y+082256X0198Y0197R090 S2      
327JTAG_CPU0_TCK    R401  -2   M      A18X+148618Y+082256X0198Y0197R270 S2      
317m8594            VIA   -    MD0080PA00X+149022Y+087962X0160Y    R180 S0      
327m8594            U25   -C18        A01X+148838Y+088067X0177Y    R180 S1      
317m8594            VIA   -    M      A01X+148068Y+081349X0200Y    R180 S2      
017m8594            VIA   -    M      A18X+148068Y+081349X0260Y    R180 S2      
017m8594                  -    MD0100PA00X+148068Y+081349                       
327m8594            R404  -1          A18X+147318Y+080906X0198Y0197R090 S2      
327m8595            VIA   -    M      A01X+093896Y+058513X0300Y         S1      
327m8595            U153  -2          A01X+093146Y+058513X0140Y0520R090 S1      
327m8595            R1648 -1          A01X+094497Y+058520X0198Y0197     S1      
327m8596            U25   -C16        A01X+149578Y+088067X0177Y    R180 S1      
327m8596            C212  -1   M      A18X+148918Y+080906X0198Y0197R090 S2      
327m8596            R403  -2          A18X+148518Y+080906X0198Y0197R270 S2      
317m8596            VIA   -    MD0100PA00X+148918Y+081299X0200Y    R180 S0      
327m8596            R1641 -2          A01X+098846Y+036346X0198Y0197R270 S1      
317m8596            VIA   -    M      A01X+098846Y+035840X0200Y         S2      
017m8596            VIA   -    M      A18X+098846Y+035840X0260Y         S2      
017m8596                  -    MD0100PA00X+098846Y+035840                       
317m8597            VIA   -    M      A01X+090238Y+059017X0200Y         S2      
017m8597            VIA   -    M      A18X+090238Y+059017X0260Y         S2      
017m8597                  -    MD0100PA00X+090238Y+059017                       
327m8597            R6104 -1          A01X+090221Y+060692X0198Y0197     S1      
327m8597            U153  -6          A01X+091689Y+058769X0140Y0520R090 S1      
327m8598            C8006 -1          A01X+102458Y+040200X0198Y0197R180 S1      
317m8598            VIA   -    M      A01X+061356Y+035082X0200Y         S2      
017m8598            VIA   -    M      A18X+061356Y+035082X0260Y         S2      
017m8598                  -    MD0100PA00X+061356Y+035082                       
327m8598            U149  -9          A01X+104004Y+039392X0140Y0630R090 S1      
317m8598            VIA   -    MD0100PA00X+102960Y+039439X0200Y         S0      
327m8598            U146  -2          A01X+048554Y+021290X0070Y0320R180 S1      
327m8598            R617  -2   M      A01X+048633Y+020683X0198Y0197     S1      
327m8598            R1619 -2   M      A01X+057795Y+025717X0198Y0197R180 S1      
327JTAG_BMC_OE_N    Q62   -D   M      A01X+059676Y+025743X0400Y0560R270 S1      
327JTAG_BMC_OE_N    U147  -2          A01X+057510Y+022825X0070Y0320     S1      
327JTAG_BMC_OE_N    R1622 -2   M      A01X+057431Y+023582X0198Y0197     S1      
317JTAG_BMC_OE_N    VIA   -    M      A01X+103441Y+042962X0200Y         S2      
017JTAG_BMC_OE_N    VIA   -    M      A18X+103441Y+042962X0260Y         S2      
017JTAG_BMC_OE_N          -    MD0100PA00X+103441Y+042962                       
327JTAG_BMC_OE_N    U148  -9          A01X+104042Y+042962X0140Y0630R090 S1      
317JTAG_BMC_OE_N    VIA   -    MD0100PA00X+061112Y+035946X0200Y         S0      
317JTAG_BMC_OE      VIA   -    MD0100PA00X+058110Y+026368X0200Y    R180 S0      
317JTAG_BMC_OE      VIA   -    M      A01X+107170Y+027070X0200Y         S2      
017JTAG_BMC_OE      VIA   -    M      A18X+107170Y+027070X0260Y         S2      
017JTAG_BMC_OE            -    MD0100PA00X+107170Y+027070                       
317JTAG_BMC_OE      VIA   -    MD0100PA00X+159335Y+024816X0200Y         S0      
317JTAG_BMC_OE      VIA   -    MD0100PA00X+168243Y+022086X0200Y    R270 S0      
327JTAG_BMC_OE      U124  -4          A01X+167826Y+022086X0220Y0530R270 S1      
327JTAG_BMC_OE      Q62   -G          A01X+058810Y+026117X0400Y0560R270 S1      
327JTAG_BMC_OE      R1619 -1   M      A01X+058110Y+025717X0198Y0197R180 S1      
327JTAG_BMC_OE      R8    -2   M      A01X+058110Y+026117X0198Y0197     S1      
327IRQ_WAKE_R_N     Q4    -3          A01X+063630Y+029717X0170Y0200R090 S1      
327IRQ_WAKE_R_N     VIA   -    M      A01X+063150Y+029473X0300Y         S1      
327IRQ_WAKE_R_N     R1311 -1          A01X+063150Y+028993X0198Y0197R270 S1      
317IRQ_WAKE_N       VIA   -    M      A01X+086374Y+144456X0200Y         S2      
017IRQ_WAKE_N       VIA   -    M      A18X+086374Y+144456X0260Y         S2      
017IRQ_WAKE_N             -    MD0100PA00X+086374Y+144456                       
327IRQ_WAKE_N       U26   -DJ10       A01X+054302Y+116414X0177Y    R180 S1      
317IRQ_WAKE_N       VIA   -    MD0100PA00X+056554Y+123546X0200Y         S0      
317IRQ_WAKE_N       VIA   -    MD0100PA00X+083235Y+125170X0200Y         S0      
317IRQ_WAKE_N       VIA   -    MD0100PA00X+082279Y+079751X0200Y         S0      
327IRQ_WAKE_N       R1311 -2          A01X+063150Y+028678X0198Y0197R270 S1      
317IRQ_WAKE_N       VIA   -    MD0100PA00X+063150Y+028436X0200Y         S0      
317IRQ_WAKE_N       VIA   -    MD0100PA00X+064305Y+050289X0200Y         S0      
317IRQ_WAKE_N       VIA   -    MD0100PA00X+073444Y+067570X0200Y         S0      
327IRQ_WAKE_N       U25   -DJ10       A01X+151916Y+116413X0177Y    R180 S1      
327IRQ_WAKE_N       R437  -2          A01X+154710Y+127419X0198Y0197R180 S1      
317IRQ_WAKE_N       VIA   -    MD0100PA00X+154563Y+125407X0200Y    R180 S0      
327m8599            R8124 -2          A01X+056208Y+047750X0198Y0197     S1      
327m8599            R8125 -2   M      A01X+057308Y+047150X0198Y0197     S1      
327m8599            R6038 -2          A01X+064292Y+045386X0198Y0197R180 S1      
317m8599            VIA   -    MD0100PA00X+063931Y+045236X0200Y         S0      
317m8599            VIA   -    M      A01X+062736Y+047882X0200Y         S2      
017m8599            VIA   -    M      A18X+062736Y+047882X0260Y         S2      
017m8599                  -    MD0100PA00X+062736Y+047882                       
327m8599            R4620 -2   M      A01X+059360Y+047963X0198Y0197     S1      
327m8599            U325  -D   M      A01X+060756Y+047961X0400Y0560R090 S1      
317m8600            VIA   -    MD0100PA00X+090088Y+143504X0200Y         S0      
317m8600            VIA   -    MD0100PA00X+101926Y+057132X0200Y         S0      
327m8600            U18   -B21        A01X+070048Y+048288X0160Y    R090 S1      
317m8600            VIA   -    MD0100PA00X+069895Y+048442X0180Y    R090 S0      
317m8600            VIA   -    M      A01X+072011Y+160954X0200Y         S2      
017m8600            VIA   -    M      A18X+072011Y+160954X0260Y         S2      
017m8600                  -    MD0100PA00X+072011Y+160954                       
327m8600            R3924 -1          A18X+072018Y+159075X0198Y0197R180 S2      
317m8600            VIA   -    MD0100PA00X+075816Y+152229X0200Y    R090 S0      
327m8600            PJ38  -20         A01X+076291Y+152229X0240Y0650R090 S1      
327m8601            R3924 -2          A18X+072332Y+159075X0198Y0197R180 S2      
317m8601            VIA   -    M      A01X+072359Y+159532X0200Y    R270 S2      
017m8601            VIA   -    M      A18X+072359Y+159532X0260Y    R270 S2      
017m8601                  -    MD0100PA00X+072359Y+159532                       
327m8601            R3925 -1          A01X+071711Y+159945X0198Y0197R090 S1      
327m8601            PU289 -10         A01X+072413Y+159117X0090Y0150     S1      
327m8602            R994  -2   M      A01X+062670Y+029973X0198Y0197R270 S1      
327m8602            Q4    -2          A01X+063630Y+029973X0170Y0200R090 S1      
327m8602            VIA   -    M      A01X+063150Y+029973X0300Y         S1      
327m8602            R116  -2   M      A01X+062670Y+029588X0198Y0197R090 S1      
327m8602            R6063 -2          A01X+061870Y+029588X0198Y0197R090 S1      
327m8602            R1005 -2   M      A01X+062270Y+029588X0198Y0197R090 S1      
327m8603            VIA   -    M      A01X+064239Y+014426X0300Y         S1      
327m8603            R2489 -1          A01X+064623Y+014998X0198Y0197R090 S1      
327m8603            U157  -4          A01X+064239Y+013750X0220Y0320     S1      
327m8603            R2487 -2   M      A01X+064230Y+014998X0198Y0197R270 S1      
327IRQ_LVC3_WAKE    R1009 -2          A01X+064858Y+030709X0198Y0197R180 S1      
327IRQ_LVC3_WAKE    VIA   -    M      A01X+064858Y+030229X0300Y    R180 S1      
327IRQ_LVC3_WAKE    Q4    -5          A01X+064378Y+029973X0170Y0200R090 S1      
327IRQ_LVC3_WAKE    Q4    -6   M      A01X+064378Y+030229X0170Y0200R090 S1      
327m8604            R3192 -2          A01X+039587Y+013898X0198Y0197     S1      
327m8604            U219  -4          A01X+038045Y+013516X0220Y0320R270 S1      
327m8604            VIA   -    M      A01X+038789Y+013516X0300Y         S1      
327m8604            R3193 -1   M      A01X+039583Y+013498X0198Y0197     S1      
327m8605            J35   -OA3        A01X+030261Y+003276X0150Y0570R180 S1      
317m8605            VIA   -    MD0100PA00X+030261Y+002636X0200Y         S0      
317m8605            VIA   -    M      A01X+041068Y+015914X0200Y         S2      
017m8605            VIA   -    M      A18X+041068Y+015914X0260Y         S2      
017m8605                  -    MD0100PA00X+041068Y+015914                       
327m8605            U217  -2          A01X+039164Y+015538X0170Y0240R090 S1      
327m8605            R3182 -2   M      A01X+040222Y+015703X0198Y0197R180 S1      
317m8606            VIA   -    M      A01X+179769Y+014628X0300Y         S1      
017m8606            VIA   -    M      A18X+179769Y+014628X0200Y         S1      
017m8606                  -    MD0100PA00X+179769Y+014628                       
327m8606            U8082 -2          A01X+180280Y+014928X0170Y0240R270 S1      
327m8606            R1824 -2          A01X+179296Y+014683X0198Y0197     S1      
317m8606            VIA   -    MD0100PA00X+177592Y+002707X0200Y    R225 S0      
327m8606            J38   -OA3        A01X+177702Y+003276X0150Y0570R180 S1      
327m8607            R9025 -1   M      A01X+063800Y+041858X0198Y0197R270 S1      
327m8607            R9024 -2   M      A01X+064692Y+041850X0198Y0197R180 S1      
327m8607            R9028 -1   M      A01X+064250Y+041892X0198Y0197R090 S1      
327m8607            R2587 -1          A18X+075301Y+158717X0198Y0197R090 S2      
317m8607            VIA   -    MD0100PA00X+066600Y+043386X0200Y    R270 S0      
317m8607            VIA   -    MD0100PA00X+082262Y+076353X0200Y         S0      
317m8607            VIA   -    MD0100PA00X+065141Y+050118X0200Y         S0      
317m8607            VIA   -    MD0100PA00X+074666Y+067888X0200Y         S0      
317m8607            VIA   -    MD0100PA00X+075816Y+149473X0200Y    R090 S0      
327m8607            PJ38  -13         A01X+076291Y+149473X0240Y0650R090 S1      
317m8607            VIA   -    M      A01X+075761Y+158402X0200Y    R270 S2      
017m8607            VIA   -    M      A18X+075761Y+158402X0260Y    R270 S2      
017m8607                  -    MD0100PA00X+075761Y+158402                       
327m8607            R2588 -2          A01X+075518Y+158402X0198Y0197     S1      
317m8607            VIA   -    MD0100PA00X+065203Y+041593X0200Y         S0      
327m8607            Q9003 -2          A01X+063224Y+041900X0170Y0200R270 S1      
327IRQ0_A56         J41   -A56        A01X+054389Y+005354X0150Y0570R180 S1      
327IRQ0_A56         R321  -2          A18X+053512Y+003711X0198Y0197R270 S2      
317IRQ0_A56         VIA   -    M      A01X+053972Y+004286X0200Y         S2      
017IRQ0_A56         VIA   -    M      A18X+053972Y+004286X0260Y         S2      
017IRQ0_A56               -    MD0100PA00X+053972Y+004286                       
317m8608            VIA   -    MD0080PA00X+045234Y+116518X0160Y         S0      
327m8608            U26   -DJ35       A01X+045050Y+116414X0177Y    R180 S1      
327m8608            VIA   -    M      A18X+038745Y+120749X0260Y    R090 S2      
327m8608            R1424 -2          A18X+038285Y+120749X0198Y0197R180 S2      
327m8609            PL36  -2          A01X+048946Y+068242X0540Y1780R090 S1      
327m8609            PL38  -3          A01X+052206Y+065757X0540Y1780R090 S1      
327m8610            PL35  -2          A01X+045709Y+070892X0540Y1780R090 S1      
327m8610            PL36  -3          A01X+048946Y+069167X0540Y1780R090 S1      
327m8611            PL38  -2          A01X+052206Y+064832X0540Y1780R090 S1      
327m8611            PL34  -2          A01X+055379Y+064057X0790Y1660R090 S1      
327m8612            PL66  -3          A01X+163304Y+068606X0540Y1780R090 S1      
327m8612            PL64  -2          A01X+160024Y+069581X0540Y1780R090 S1      
327m8613            PL63  -2          A01X+156711Y+072958X0540Y1780R090 S1      
327m8613            PL64  -3          A01X+160024Y+070506X0540Y1780R090 S1      
327m8614            PL62  -2          A01X+166413Y+068319X0790Y1660R090 S1      
327m8614            PL66  -2          A01X+163304Y+067681X0540Y1780R090 S1      
327m8615            PL68  -2          A01X+014566Y+133299X0540Y1780R270 S1      
327m8615            PL67  -3          A01X+011306Y+132374X0540Y1780R270 S1      
327m8616            PL48  -2          A01X+017816Y+133299X0540Y1780R270 S1      
327m8616            PL68  -3          A01X+014566Y+132374X0540Y1780R270 S1      
327m8617            PL47  -2          A01X+021076Y+133299X0540Y1780R270 S1      
327m8617            PL48  -3          A01X+017816Y+132374X0540Y1780R270 S1      
327m8618            PL67  -2          A01X+011306Y+133299X0540Y1780R270 S1      
327m8618            PL46  -1          A01X+008297Y+132647X0790Y1660R090 S1      
327m8619            PL21  -2          A01X+111740Y+133297X0540Y1780R270 S1      
327m8619            PL20  -3          A01X+108480Y+132372X0540Y1780R270 S1      
327m8620            PL18  -2          A01X+115010Y+133297X0540Y1780R270 S1      
327m8620            PL21  -3          A01X+111740Y+132372X0540Y1780R270 S1      
327m8621            PL17  -2          A01X+118300Y+133297X0540Y1780R270 S1      
327m8621            PL18  -3          A01X+115010Y+132372X0540Y1780R270 S1      
327m8622            PL20  -2          A01X+108480Y+133297X0540Y1780R270 S1      
327m8622            PL16  -1          A01X+105471Y+132645X0790Y1660R090 S1      
327m8623            PL69  -3          A01X+040885Y+129704X0540Y1780R270 S1      
327m8623            PL45  -2          A01X+037596Y+128681X0540Y1780R270 S1      
327m8624            PL40  -2          A01X+034346Y+128676X0540Y1780R270 S1      
327m8624            PL45  -3          A01X+037596Y+127756X0540Y1780R270 S1      
327m8625            PL43  -2          A01X+024336Y+133299X0540Y1780R270 S1      
327m8625            PL44  -3          A01X+027766Y+127759X0540Y1780R270 S1      
327m8626            PL44  -2          A01X+027766Y+128684X0540Y1780R270 S1      
327m8626            PL41  -3          A01X+031056Y+127750X0540Y1780R270 S1      
327m8627            PL41  -2          A01X+031056Y+128676X0540Y1780R270 S1      
327m8627            PL40  -3          A01X+034346Y+127750X0540Y1780R270 S1      
327m8628            PL39  -1          A01X+043870Y+130092X0790Y1660R090 S1      
327m8628            PL69  -2          A01X+040885Y+130629X0540Y1780R270 S1      
327m8629            PL7   -3          A01X+138498Y+129702X0540Y1780R270 S1      
327m8629            PL15  -2          A01X+135209Y+128680X0540Y1780R270 S1      
327m8630            PL10  -2          A01X+131959Y+128674X0540Y1780R270 S1      
327m8630            PL15  -3          A01X+135209Y+127754X0540Y1780R270 S1      
327m8631            PL13  -2          A01X+121580Y+133297X0540Y1780R270 S1      
327m8631            PL14  -3          A01X+125379Y+127757X0540Y1780R270 S1      
327m8632            PL14  -2          A01X+125379Y+128682X0540Y1780R270 S1      
327m8632            PL11  -3          A01X+128669Y+127749X0540Y1780R270 S1      
327m8633            PL11  -2          A01X+128669Y+128674X0540Y1780R270 S1      
327m8633            PL10  -3          A01X+131959Y+127749X0540Y1780R270 S1      
327m8634            PL7   -2          A01X+138498Y+130627X0540Y1780R270 S1      
327m8634            PL9   -1          A01X+141456Y+130032X0790Y1660R090 S1      
327m8635            PL33  -2          A01X+029072Y+073137X0540Y1780R090 S1      
327m8635            PL8   -3          A01X+025799Y+070638X0540Y1780R090 S1      
327m8636            PL28  -2          A01X+032349Y+075152X0540Y1780R090 S1      
327m8636            PL33  -3          A01X+029072Y+074062X0540Y1780R090 S1      
327m8637            PL31  -3          A01X+038959Y+076057X0540Y1780R090 S1      
327m8637            PL32  -2          A01X+042556Y+073354X0540Y1780R090 S1      
327m8638            PL31  -2          A01X+038959Y+075132X0540Y1780R090 S1      
327m8638            PL29  -3          A01X+035655Y+076068X0540Y1780R090 S1      
327m8639            PL29  -2          A01X+035655Y+075143X0540Y1780R090 S1      
327m8639            PL28  -3          A01X+032349Y+076077X0540Y1780R090 S1      
327m8640            PL8   -2          A01X+025799Y+069713X0540Y1780R090 S1      
327m8640            PL27  -2          A01X+022796Y+070127X0790Y1660R090 S1      
327m8641            PL61  -2          A01X+140124Y+069936X0540Y1780R090 S1      
327m8641            PL70  -3          A01X+136886Y+067572X0540Y1780R090 S1      
327m8642            PL51  -2          A01X+143384Y+073194X0540Y1780R090 S1      
327m8642            PL61  -3          A01X+140124Y+070862X0540Y1780R090 S1      
327m8643            PL60  -2          A01X+153264Y+075152X0540Y1780R090 S1      
327m8643            PL59  -3          A01X+149984Y+076077X0540Y1780R090 S1      
327m8644            PL59  -2          A01X+149984Y+075152X0540Y1780R090 S1      
327m8644            PL52  -3          A01X+146676Y+076077X0540Y1780R090 S1      
327m8645            PL52  -2          A01X+146676Y+075152X0540Y1780R090 S1      
327m8645            PL51  -3          A01X+143384Y+074120X0540Y1780R090 S1      
327m8646            PL70  -2          A01X+136886Y+066646X0540Y1780R090 S1      
327m8646            PL50  -2          A01X+133922Y+066183X0790Y1660R090 S1      
327m8647            R1591 -2          A18X+081032Y+076766X0198Y0197     S2      
327m8647            J37   -4          A01X+081200Y+076687X0205Y0590R090 S1      
317m8647            VIA   -    MD0100PA00X+080745Y+076730X0200Y         S0      
327m8648            R1579 -2          A18X+178674Y+076756X0198Y0197R180 S2      
317m8648            VIA   -    MD0100PA00X+179269Y+076687X0200Y         S2      
327m8648            J67   -4          A01X+178814Y+076687X0205Y0590R090 S1      
327m8649            VIA   -    M      A18X+078422Y+076767X0260Y         S2      
317m8649            VIA   -    MD0100PA00X+078685Y+076687X0190Y         S0      
327m8649            R1590 -2          A18X+078090Y+076730X0198Y0197R180 S2      
327m8649            J99   -4          A01X+078230Y+076687X0205Y0590R090 S1      
327m8650            VIA   -    M      A18X+176025Y+076747X0260Y         S2      
317m8650            VIA   -    MD0100PA00X+176299Y+076687X0190Y         S0      
327m8650            R1578 -2          A18X+175704Y+076730X0198Y0197R180 S2      
327m8650            J20   -4          A01X+175844Y+076687X0205Y0590R090 S1      
327m8651            VIA   -    M      A18X+075460Y+076793X0260Y         S2      
317m8651            VIA   -    MD0100PA00X+075715Y+076687X0190Y         S0      
327m8651            R1589 -2          A18X+075120Y+076730X0198Y0197R180 S2      
327m8651            J29   -4          A01X+075260Y+076687X0205Y0590R090 S1      
327m8652            VIA   -    M      A18X+173091Y+076698X0260Y         S2      
317m8652            VIA   -    MD0100PA00X+173373Y+076687X0190Y         S0      
327m8652            R1577 -2          A18X+172734Y+076730X0198Y0197R180 S2      
327m8652            J68   -4          A01X+172874Y+076687X0205Y0590R090 S1      
317m8653            VIA   -    MD0100PA00X+072745Y+076687X0200Y         S2      
327m8653            R1588 -2          A18X+072150Y+076730X0198Y0197R180 S2      
327m8653            J100  -4          A01X+072290Y+076687X0205Y0590R090 S1      
327m8654            VIA   -    M      A18X+170087Y+076610X0260Y         S2      
317m8654            VIA   -    MD0100PA00X+170359Y+076687X0190Y         S0      
327m8654            R1576 -2          A18X+169764Y+076726X0198Y0197R180 S2      
327m8654            J18   -4          A01X+169904Y+076687X0205Y0590R090 S1      
327m8655            VIA   -    M      A18X+069525Y+076813X0260Y         S2      
317m8655            VIA   -    MD0100PA00X+069775Y+076687X0190Y         S0      
327m8655            R1587 -2          A18X+069180Y+076730X0198Y0197R180 S2      
327m8655            J27   -4          A01X+069320Y+076687X0205Y0590R090 S1      
317m8656            VIA   -    MD0100PA00X+167389Y+076687X0200Y         S2      
327m8656            R1575 -2          A18X+166794Y+076726X0198Y0197R180 S2      
327m8656            J69   -4          A01X+166934Y+076687X0205Y0590R090 S1      
327m8657            VIA   -    M      A18X+066542Y+076809X0260Y         S2      
317m8657            VIA   -    MD0100PA00X+066805Y+076687X0190Y         S0      
327m8657            R1586 -2          A18X+066210Y+076730X0198Y0197R180 S2      
327m8657            J102  -4          A01X+066350Y+076687X0205Y0590R090 S1      
327m8658            R1574 -2          A18X+163824Y+076726X0198Y0197R180 S2      
317m8658            VIA   -    MD0100PA00X+164419Y+076687X0200Y         S2      
327m8658            J16   -4          A01X+163964Y+076687X0205Y0590R090 S1      
327m8659            VIA   -    M      A01X+073169Y+066206X0300Y         S1      
317m8659            VIA   -    MD0100PA00X+065895Y+077110X0200Y         S0      
327m8659            R1705 -1          A18X+065895Y+077110X0198Y0197R180 S2      
317m8659            VIA   -    MD0100PA00X+071835Y+077110X0200Y         S0      
327m8659            R1708 -1          A18X+071835Y+077110X0198Y0197R180 S2      
317m8659            VIA   -    MD0100PA00X+068865Y+077110X0200Y         S0      
327m8659            R1707 -1          A18X+068865Y+077110X0198Y0197R180 S2      
317m8659            VIA   -    MD0100PA00X+074805Y+077110X0200Y         S0      
327m8659            R1709 -1          A18X+074805Y+077110X0198Y0197R180 S2      
317m8659            VIA   -    MD0100PA00X+077775Y+077110X0200Y         S0      
327m8659            R1710 -1          A18X+077775Y+077110X0198Y0197R180 S2      
327m8659            R1711 -1          A18X+081347Y+077146X0198Y0197     S2      
317m8659            VIA   -    MD0100PA00X+081655Y+077022X0190Y         S0      
327m8659            R1296 -1          A01X+072620Y+066424X0180Y0200R090 S1      
327m8659            R1337 -2   M      A01X+072620Y+066424X0180Y0200R090 S1      
327m8660            R1590 -1          A18X+077775Y+076730X0198Y0197R180 S2      
317m8660            VIA   -    MD0100PA00X+077775Y+076730X0200Y    R180 S0      
327m8660            R1589 -1          A18X+074805Y+076730X0198Y0197R180 S2      
317m8660            VIA   -    MD0100PA00X+074805Y+076730X0200Y    R180 S0      
327m8660            R1588 -1          A18X+071835Y+076730X0198Y0197R180 S2      
317m8660            VIA   -    MD0100PA00X+071835Y+076730X0200Y    R180 S0      
327m8660            R1587 -1          A18X+068865Y+076730X0198Y0197R180 S2      
317m8660            VIA   -    MD0100PA00X+068865Y+076730X0200Y    R180 S0      
327m8660            R1586 -1          A18X+065895Y+076730X0198Y0197R180 S2      
317m8660            VIA   -    MD0100PA00X+065895Y+076730X0200Y    R180 S0      
327m8660            R1591 -1          A18X+081347Y+076766X0198Y0197     S2      
317m8660            VIA   -    MD0100PA00X+081655Y+076687X0200Y         S2      
327m8660            R1295 -1          A01X+071413Y+066424X0180Y0200R090 S1      
327m8660            R1336 -2   M      A01X+071413Y+066424X0180Y0200R090 S1      
317m8660            VIA   -    MD0100PA00X+082256Y+080741X0200Y         S0      
317m8660            VIA   -    M      A01X+073077Y+064422X0200Y         S2      
017m8660            VIA   -    M      A18X+073077Y+064422X0260Y         S2      
017m8660                  -    MD0100PA00X+073077Y+064422                       
317m8660            VIA   -    MD0100PA00X+071130Y+066512X0200Y         S0      
327m8661            R1296 -2          A01X+072620Y+066109X0180Y0200R090 S1      
327m8661            VIA   -    M      A01X+072317Y+065622X0300Y         S1      
327m8661            U108  -7          A01X+072111Y+065119X0100Y0210R180 S1      
327m8661            R5013 -2   M      A01X+072213Y+066109X0198Y0197R270 S1      
327m8662            R1295 -2          A01X+071413Y+066109X0180Y0200R090 S1      
327m8662            VIA   -    M      A01X+071813Y+065613X0300Y         S1      
327m8662            U108  -8          A01X+071914Y+065119X0100Y0210R180 S1      
327m8662            R5012 -2   M      A01X+071813Y+066109X0198Y0197R270 S1      
327m8663            R991  -2          A18X+063495Y+076420X0180Y0200R090 S2      
327m8663            R1337 -1          A01X+072620Y+066739X0180Y0200R090 S1      
327m8663            VIA   -    M      A01X+071580Y+067095X0300Y         S1      
317m8663            VIA   -    MD0100PA00X+063655Y+076790X0200Y         S0      
327m8664            VIA   -    M      A01X+070471Y+066800X0300Y         S1      
327m8664            R990  -2          A18X+062841Y+076515X0180Y0200R090 S2      
327m8664            R1336 -1          A01X+071413Y+066739X0180Y0200R090 S1      
317m8664            VIA   -    MD0100PA00X+063174Y+077032X0200Y         S0      
317m8665            VIA   -    MD0100PA00X+163509Y+077100X0200Y         S0      
327m8665            R1680 -1          A18X+163509Y+077106X0198Y0197R180 S2      
317m8665            VIA   -    MD0100PA00X+166479Y+077106X0200Y         S0      
327m8665            R1681 -1          A18X+166479Y+077106X0198Y0197R180 S2      
317m8665            VIA   -    MD0100PA00X+169449Y+077106X0200Y         S0      
327m8665            R1683 -1          A18X+169449Y+077106X0198Y0197R180 S2      
317m8665            VIA   -    MD0100PA00X+172419Y+077110X0200Y         S0      
327m8665            R1684 -1          A18X+172419Y+077110X0198Y0197R180 S2      
317m8665            VIA   -    MD0100PA00X+175389Y+077110X0200Y         S0      
327m8665            R1685 -1          A18X+175389Y+077110X0198Y0197R180 S2      
317m8665            VIA   -    MD0100PA00X+178359Y+077136X0200Y         S0      
327m8665            R1686 -1          A18X+178359Y+077136X0198Y0197R180 S2      
327m8665            R1300 -1          A01X+171300Y+067358X0180Y0200R090 S1      
327m8665            R1333 -2   M      A01X+171300Y+067358X0180Y0200R090 S1      
317m8665            VIA   -    M      A01X+171869Y+067615X0200Y         S2      
017m8665            VIA   -    M      A18X+171869Y+067615X0260Y         S2      
017m8665                  -    MD0100PA00X+171869Y+067615                       
317m8666            VIA   -    MD0100PA00X+178359Y+076756X0200Y    R180 S0      
327m8666            R1579 -1          A18X+178359Y+076756X0198Y0197R180 S2      
327m8666            R1578 -1          A18X+175389Y+076730X0198Y0197R180 S2      
317m8666            VIA   -    MD0100PA00X+175389Y+076730X0200Y    R180 S0      
327m8666            R1577 -1          A18X+172419Y+076730X0198Y0197R180 S2      
317m8666            VIA   -    MD0100PA00X+172419Y+076730X0200Y    R180 S0      
327m8666            R1576 -1          A18X+169449Y+076726X0198Y0197R180 S2      
317m8666            VIA   -    MD0100PA00X+169449Y+076726X0200Y    R180 S0      
327m8666            R1575 -1          A18X+166479Y+076726X0198Y0197R180 S2      
317m8666            VIA   -    MD0100PA00X+166479Y+076726X0200Y    R180 S0      
327m8666            R1574 -1          A18X+163509Y+076726X0198Y0197R180 S2      
317m8666            VIA   -    MD0100PA00X+163509Y+076720X0200Y    R180 S0      
317m8666            VIA   -    M      A01X+173685Y+065097X0200Y         S2      
017m8666            VIA   -    M      A18X+173685Y+065097X0260Y         S2      
017m8666                  -    MD0100PA00X+173685Y+065097                       
327m8666            R1332 -2   M      A01X+171300Y+065492X0180Y0200R270 S1      
327m8666            R1299 -1          A01X+171300Y+065492X0180Y0200R270 S1      
327m8667            R1300 -2          A01X+171300Y+067042X0180Y0200R090 S1      
327m8667            VIA   -    M      A01X+171858Y+066624X0300Y         S1      
327m8667            U106  -7          A01X+172381Y+066522X0100Y0210R270 S1      
327m8667            R5009 -2   M      A01X+171291Y+066624X0198Y0197     S1      
327m8668            R1299 -2          A01X+171300Y+065808X0180Y0200R270 S1      
327m8668            VIA   -    M      A01X+171846Y+066098X0300Y         S1      
327m8668            U106  -8          A01X+172381Y+066325X0100Y0210R270 S1      
327m8668            R5008 -2   M      A01X+171291Y+066224X0198Y0197     S1      
327m8669            R987  -2          A18X+150818Y+081221X0180Y0200R090 S2      
327m8669            R1333 -1          A01X+171300Y+067672X0180Y0200R090 S1      
317m8669            VIA   -    M      A01X+169950Y+067374X0200Y         S2      
017m8669            VIA   -    M      A18X+169950Y+067374X0260Y         S2      
017m8669                  -    MD0100PA00X+169950Y+067374                       
317m8669            VIA   -    MD0100PA00X+151252Y+080968X0200Y    R180 S0      
327m8670            R986  -2          A18X+149718Y+081221X0180Y0200R090 S2      
327m8670            R1332 -1          A01X+171300Y+065178X0180Y0200R270 S1      
317m8670            VIA   -    M      A01X+169950Y+065474X0200Y         S2      
017m8670            VIA   -    M      A18X+169950Y+065474X0260Y         S2      
017m8670                  -    MD0100PA00X+169950Y+065474                       
317m8670            VIA   -    MD0100PA00X+150042Y+081418X0200Y         S0      
327m8671            VIA   -    M      A18X+008726Y+076695X0260Y         S2      
317m8671            VIA   -    MD0100PA00X+009002Y+076687X0190Y         S0      
327m8671            J33   -4          A01X+008546Y+076687X0205Y0590R090 S1      
327m8671            R1585 -2          A18X+008393Y+076777X0198Y0197R180 S2      
327m8672            VIA   -    M      A18X+106347Y+076766X0260Y         S2      
317m8672            VIA   -    MD0100PA00X+106616Y+076687X0190Y         S0      
327m8672            R1573 -2          A18X+106021Y+076730X0198Y0197R180 S2      
327m8672            J23   -4          A01X+106161Y+076687X0205Y0590R090 S1      
327m8673            VIA   -    M      A18X+011688Y+076676X0260Y         S2      
317m8673            VIA   -    MD0100PA00X+011962Y+076717X0190Y         S0      
327m8673            R1584 -2          A18X+011364Y+076777X0198Y0197R180 S2      
327m8673            J32   -4          A01X+011517Y+076687X0205Y0590R090 S1      
327m8674            VIA   -    M      A18X+109312Y+076637X0260Y         S2      
317m8674            VIA   -    MD0100PA00X+109586Y+076687X0190Y         S0      
327m8674            R1572 -2          A18X+108991Y+076730X0198Y0197R180 S2      
327m8674            J21   -4          A01X+109131Y+076687X0205Y0590R090 S1      
327m8675            VIA   -    M      A18X+014666Y+076635X0260Y         S2      
317m8675            VIA   -    MD0100PA00X+014942Y+076687X0190Y         S0      
327m8675            R1583 -2          A18X+014347Y+076740X0198Y0197R180 S2      
327m8675            J30   -4          A01X+014487Y+076687X0205Y0590R090 S1      
327m8676            VIA   -    M      A18X+112273Y+076565X0260Y         S2      
317m8676            VIA   -    MD0100PA00X+112556Y+076687X0190Y         S0      
327m8676            R1    -2          A18X+111961Y+076730X0198Y0197R180 S2      
327m8676            J19   -4          A01X+112101Y+076687X0205Y0590R090 S1      
327m8677            VIA   -    M      A18X+017633Y+076662X0260Y         S2      
317m8677            VIA   -    MD0100PA00X+017912Y+076687X0190Y         S0      
327m8677            R1582 -2          A18X+017314Y+076767X0198Y0197R180 S2      
327m8677            J28   -4          A01X+017457Y+076687X0205Y0590R090 S1      
327m8678            R1570 -2          A18X+114931Y+076730X0198Y0197R180 S2      
317m8678            VIA   -    MD0100PA00X+115528Y+076681X0200Y         S2      
327m8678            J17   -4          A01X+115071Y+076687X0205Y0590R090 S1      
327m8679            R1581 -2          A18X+020287Y+076740X0198Y0197R180 S2      
317m8679            VIA   -    MD0100PA00X+020882Y+076687X0200Y         S2      
327m8679            J26   -4          A01X+020427Y+076687X0205Y0590R090 S1      
327m8680            R1569 -2          A18X+117901Y+076730X0198Y0197R180 S2      
317m8680            VIA   -    MD0100PA00X+118496Y+076687X0200Y         S2      
327m8680            J15   -4          A01X+118041Y+076687X0205Y0590R090 S1      
327m8681            R1580 -2          A18X+023544Y+076777X0198Y0197R180 S2      
317m8681            VIA   -    M      A01X+024020Y+076630X0200Y         S2      
017m8681            VIA   -    M      A18X+024020Y+076630X0260Y         S2      
017m8681                  -    MD0100PA00X+024020Y+076630                       
327m8681            J24   -4          A01X+023397Y+076687X0205Y0590R090 S1      
317m8682            VIA   -    MD0100PA00X+121466Y+076687X0190Y         S0      
327m8682            R1568 -2          A18X+121158Y+076766X0198Y0197R180 S2      
327m8682            J1    -4          A01X+121011Y+076687X0205Y0590R090 S1      
327m8683            R1294 -1          A01X+013490Y+068329X0180Y0200R180 S1      
327m8683            R1335 -2   M      A01X+013490Y+068329X0180Y0200R180 S1      
317m8683            VIA   -    M      A01X+013490Y+068607X0200Y         S2      
017m8683            VIA   -    M      A18X+013490Y+068607X0260Y         S2      
017m8683                  -    MD0100PA00X+013490Y+068607                       
317m8683            VIA   -    MD0100PA00X+016999Y+077127X0200Y         S0      
327m8683            R1697 -1          A18X+016999Y+077127X0198Y0197R180 S2      
317m8683            VIA   -    MD0100PA00X+014032Y+077120X0200Y         S0      
327m8683            R1699 -1          A18X+014032Y+077120X0198Y0197R180 S2      
317m8683            VIA   -    MD0100PA00X+011048Y+077137X0200Y    R180 S0      
327m8683            R1701 -1          A18X+011048Y+077137X0198Y0197R180 S2      
317m8683            VIA   -    MD0100PA00X+008078Y+077137X0200Y    R180 S0      
327m8683            R1704 -1          A18X+008078Y+077137X0198Y0197R180 S2      
317m8683            VIA   -    MD0100PA00X+019765Y+076924X0200Y    R180 S0      
327m8683            R1696 -1          A18X+019969Y+077137X0198Y0197R180 S2      
327m8683            R1687 -1          A18X+023229Y+077137X0198Y0197R180 S2      
317m8683            VIA   -    MD0100PA00X+022928Y+076929X0200Y    R180 S0      
327m8684            R1581 -1          A18X+019972Y+076740X0198Y0197R180 S2      
317m8684            VIA   -    MD0100PA00X+019972Y+076740X0200Y    R180 S0      
327m8684            R1582 -1          A18X+016999Y+076767X0198Y0197R180 S2      
317m8684            VIA   -    MD0100PA00X+016999Y+076767X0200Y    R180 S0      
327m8684            R1584 -1   M      A18X+011048Y+076777X0198Y0197R180 S2      
317m8684            VIA   -    MD0100PA00X+011062Y+076740X0200Y    R180 S0      
327m8684            R1293 -1          A01X+013490Y+067129X0180Y0200R180 S1      
327m8684            R1334 -2   M      A01X+013490Y+067129X0180Y0200R180 S1      
317m8684            VIA   -    MD0100PA00X+008092Y+076740X0200Y    R180 S0      
327m8684            R1585 -1   M      A18X+008078Y+076777X0198Y0197R180 S2      
317m8684            VIA   -    M      A01X+013490Y+066851X0200Y         S2      
017m8684            VIA   -    M      A18X+013490Y+066851X0260Y         S2      
017m8684                  -    MD0100PA00X+013490Y+066851                       
327m8684            R1583 -1          A18X+014032Y+076740X0198Y0197R180 S2      
317m8684            VIA   -    MD0100PA00X+014032Y+076740X0200Y    R180 S0      
327m8684            R1580 -1          A18X+023229Y+076777X0198Y0197R180 S2      
317m8684            VIA   -    MD0100PA00X+022926Y+076586X0200Y    R180 S0      
327m8685            R1294 -2          A01X+013805Y+068329X0180Y0200R180 S1      
327m8685            VIA   -    M      A01X+014395Y+067761X0300Y         S1      
327m8685            U107  -7          A01X+015018Y+067807X0100Y0210R270 S1      
327m8685            R5011 -2   M      A01X+013805Y+067929X0198Y0197     S1      
327m8686            R1293 -2          A01X+013805Y+067129X0180Y0200R180 S1      
327m8686            VIA   -    M      A01X+014365Y+067238X0300Y         S1      
327m8686            U107  -8          A01X+015018Y+067610X0100Y0210R270 S1      
327m8686            R5010 -2   M      A01X+013805Y+067529X0198Y0197     S1      
327m8687            R1335 -1          A01X+013175Y+068329X0180Y0200R180 S1      
327m8687            R989  -2          A01X+017272Y+067650X0180Y0200R180 S1      
317m8687            VIA   -    M      A01X+017272Y+067923X0200Y         S2      
017m8687            VIA   -    M      A18X+017272Y+067923X0260Y         S2      
017m8687                  -    MD0100PA00X+017272Y+067923                       
317m8687            VIA   -    MD0100PA00X+013175Y+068607X0200Y         S0      
327m8688            R1334 -1          A01X+013175Y+067129X0180Y0200R180 S1      
327m8688            R988  -2          A01X+017272Y+067050X0180Y0200R180 S1      
317m8688            VIA   -    M      A01X+017272Y+066790X0200Y         S2      
017m8688            VIA   -    M      A18X+017272Y+066790X0260Y         S2      
017m8688                  -    MD0100PA00X+017272Y+066790                       
317m8688            VIA   -    MD0100PA00X+013175Y+066851X0200Y         S0      
327m8689            R1298 -1          A01X+116900Y+059267X0180Y0200     S1      
327m8689            R1331 -2   M      A01X+116900Y+059267X0180Y0200     S1      
317m8689            VIA   -    M      A01X+103887Y+077496X0200Y         S2      
017m8689            VIA   -    M      A18X+103887Y+077496X0260Y         S2      
017m8689                  -    MD0100PA00X+103887Y+077496                       
317m8689            VIA   -    MD0100PA00X+105706Y+077110X0200Y         S0      
327m8689            R1679 -1          A18X+105706Y+077110X0198Y0197R180 S2      
317m8689            VIA   -    MD0100PA00X+108676Y+077110X0200Y         S0      
327m8689            R1678 -1          A18X+108676Y+077110X0198Y0197R180 S2      
317m8689            VIA   -    MD0100PA00X+111646Y+077110X0200Y         S0      
327m8689            R1676 -1          A18X+111646Y+077110X0198Y0197R180 S2      
317m8689            VIA   -    MD0100PA00X+114616Y+077110X0200Y         S0      
327m8689            R1677 -1          A18X+114616Y+077110X0198Y0197R180 S2      
317m8689            VIA   -    MD0100PA00X+117586Y+077110X0200Y         S0      
327m8689            R1675 -1          A18X+117586Y+077110X0198Y0197R180 S2      
327m8689            R1674 -1          A18X+120843Y+077146X0198Y0197R180 S2      
317m8689            VIA   -    MD0100PA00X+120545Y+076991X0190Y         S0      
327m8690            R1568 -1          A18X+120843Y+076766X0198Y0197R180 S2      
317m8690            VIA   -    MD0100PA00X+120563Y+076660X0200Y    R180 S0      
317m8690            VIA   -    MD0100PA00X+114616Y+076730X0200Y    R180 S0      
327m8690            R1570 -1          A18X+114616Y+076730X0198Y0197R180 S2      
327m8690            R1    -1          A18X+111646Y+076730X0198Y0197R180 S2      
317m8690            VIA   -    MD0100PA00X+111646Y+076730X0200Y         S0      
327m8690            R1297 -1          A01X+116896Y+057560X0180Y0200     S1      
327m8690            R1330 -2   M      A01X+116896Y+057560X0180Y0200     S1      
317m8690            VIA   -    M      A01X+103643Y+077053X0200Y         S2      
017m8690            VIA   -    M      A18X+103643Y+077053X0260Y         S2      
017m8690                  -    MD0100PA00X+103643Y+077053                       
317m8690            VIA   -    MD0100PA00X+105706Y+076730X0200Y    R180 S0      
327m8690            R1573 -1          A18X+105706Y+076730X0198Y0197R180 S2      
317m8690            VIA   -    MD0100PA00X+108676Y+076730X0200Y    R180 S0      
327m8690            R1572 -1          A18X+108676Y+076730X0198Y0197R180 S2      
327m8690            R1569 -1          A18X+117586Y+076730X0198Y0197R180 S2      
317m8690            VIA   -    MD0100PA00X+117586Y+076730X0200Y    R180 S0      
327m8691            R1298 -2          A01X+116585Y+059267X0180Y0200     S1      
327m8691            VIA   -    M      A01X+117854Y+058431X0300Y         S1      
327m8691            U105  -7          A01X+118567Y+058331X0100Y0210R270 S1      
327m8691            R5007 -2   M      A01X+117217Y+058462X0198Y0197     S1      
327m8692            R1297 -2          A01X+116581Y+057560X0180Y0200     S1      
327m8692            R5006 -2   M      A01X+117211Y+058060X0198Y0197     S1      
327m8692            VIA   -    M      A01X+117734Y+057741X0300Y         S1      
327m8692            U105  -8          A01X+118567Y+058134X0100Y0210R270 S1      
327m8693            R1331 -1          A01X+117215Y+059267X0180Y0200     S1      
327m8693            R2311 -2          A01X+125678Y+075472X0180Y0200R090 S1      
317m8693            VIA   -    MD0100PA00X+120568Y+059415X0200Y         S0      
317m8693            VIA   -    M      A01X+117800Y+059267X0200Y         S2      
017m8693            VIA   -    M      A18X+117800Y+059267X0260Y         S2      
017m8693                  -    MD0100PA00X+117800Y+059267                       
327m8694            R1330 -1          A01X+117211Y+057560X0180Y0200     S1      
327m8694            R2310 -2          A01X+126371Y+075472X0180Y0200R090 S1      
317m8694            VIA   -    MD0100PA00X+120619Y+058840X0200Y         S0      
317m8694            VIA   -    M      A01X+117800Y+057260X0200Y         S2      
017m8694            VIA   -    M      A18X+117800Y+057260X0260Y         S2      
017m8694                  -    MD0100PA00X+117800Y+057260                       
327m8695            U108  -4          A01X+072308Y+064615X0120Y0210R180 S1      
317m8695            VIA   -    M      A01X+072400Y+063391X0200Y         S2      
017m8695            VIA   -    M      A18X+072400Y+063391X0260Y         S2      
017m8695                  -    MD0100PA00X+072400Y+063391                       
327m8695            R5021 -2   M      A01X+072079Y+063391X0198Y0197R090 S1      
327m8695            R6007 -2          A18X+071995Y+005512X0198Y0197R270 S2      
317m8695            VIA   -    MD0100PA00X+072116Y+005859X0200Y         S0      
327m8696            R6006 -2          A18X+072464Y+005512X0198Y0197R270 S2      
317m8696            VIA   -    MD0100PA00X+072464Y+005836X0200Y         S0      
327m8696            U108  -3          A01X+072111Y+064615X0100Y0210R180 S1      
317m8696            VIA   -    M      A01X+071334Y+063384X0200Y         S2      
017m8696            VIA   -    M      A18X+071334Y+063384X0260Y         S2      
017m8696                  -    MD0100PA00X+071334Y+063384                       
327m8696            R5020 -2   M      A01X+071672Y+063384X0198Y0197R090 S1      
317m8697            VIA   -    MD0100PA00X+072828Y+005814X0200Y         S0      
327m8697            R6005 -2          A18X+072929Y+005512X0198Y0197R270 S2      
317m8697            VIA   -    MD0100PA00X+044132Y+029517X0200Y    R180 S0      
327m8697            R5019 -2          A01X+016629Y+068480X0198Y0197R180 S1      
317m8697            VIA   -    M      A01X+016174Y+068446X0200Y         S2      
017m8697            VIA   -    M      A18X+016174Y+068446X0260Y         S2      
017m8697                  -    MD0100PA00X+016174Y+068446                       
327m8697            U107  -4          A01X+015522Y+068004X0120Y0210R270 S1      
317m8698            VIA   -    MD0100PA00X+073078Y+005807X0200Y         S0      
327m8698            R6004 -2          A18X+073364Y+005512X0198Y0197R270 S2      
317m8698            VIA   -    MD0100PA00X+044132Y+030117X0200Y    R180 S0      
327m8698            R5018 -2          A01X+016629Y+068080X0198Y0197R180 S1      
317m8698            VIA   -    M      A01X+016248Y+067932X0200Y         S2      
017m8698            VIA   -    M      A18X+016248Y+067932X0260Y         S2      
017m8698                  -    MD0100PA00X+016248Y+067932                       
327m8698            U107  -3          A01X+015522Y+067807X0100Y0210R270 S1      
317m8699            VIA   -    MD0100PA00X+086591Y+008925X0200Y         S0      
327m8699            R6003 -2          A18X+073760Y+005512X0198Y0197R270 S2      
317m8699            VIA   -    MD0100PA00X+073859Y+005987X0200Y         S0      
317m8699            VIA   -    MD0100PA00X+121630Y+047568X0200Y         S0      
317m8699            VIA   -    M      A01X+173700Y+067149X0200Y         S2      
017m8699            VIA   -    M      A18X+173700Y+067149X0260Y         S2      
017m8699                  -    MD0100PA00X+173700Y+067149                       
327m8699            U106  -4          A01X+172885Y+066719X0120Y0210R270 S1      
327m8699            R5017 -2   M      A01X+173950Y+066822X0198Y0197R180 S1      
317m8700            VIA   -    MD0100PA00X+086334Y+009002X0200Y         S0      
327m8700            R6002 -2          A18X+074138Y+005512X0198Y0197R270 S2      
317m8700            VIA   -    MD0100PA00X+074082Y+005850X0200Y         S0      
317m8700            VIA   -    MD0100PA00X+121270Y+047571X0200Y         S0      
317m8700            VIA   -    M      A01X+174231Y+066103X0200Y         S2      
017m8700            VIA   -    M      A18X+174231Y+066103X0260Y         S2      
017m8700                  -    MD0100PA00X+174231Y+066103                       
327m8700            U106  -3          A01X+172885Y+066522X0100Y0210R270 S1      
327m8700            R5016 -2   M      A01X+173950Y+066422X0198Y0197R180 S1      
327m8701            R6001 -2          A18X+074548Y+005512X0198Y0197R270 S2      
317m8701            VIA   -    MD0100PA00X+074659Y+005975X0200Y         S0      
317m8701            VIA   -    M      A01X+119534Y+058661X0200Y         S2      
017m8701            VIA   -    M      A18X+119534Y+058661X0260Y         S2      
017m8701                  -    MD0100PA00X+119534Y+058661                       
327m8701            R5015 -2          A01X+119954Y+058744X0198Y0197R180 S1      
327m8701            U105  -4          A01X+119071Y+058528X0120Y0210R270 S1      
317m8701            VIA   -    MD0100PA00X+115058Y+047884X0200Y         S0      
317m8701            VIA   -    MD0100PA00X+091009Y+024602X0200Y         S0      
317m8702            VIA   -    MD0100PA00X+115589Y+047881X0200Y         S0      
317m8702            VIA   -    MD0100PA00X+074948Y+005990X0200Y         S0      
327m8702            R6000 -2          A18X+074948Y+005512X0198Y0197R270 S2      
317m8702            VIA   -    M      A01X+119524Y+058141X0200Y         S2      
017m8702            VIA   -    M      A18X+119524Y+058141X0260Y         S2      
017m8702                  -    MD0100PA00X+119524Y+058141                       
327m8702            U105  -3          A01X+119071Y+058331X0100Y0210R270 S1      
327m8702            R5014 -2          A01X+119954Y+058244X0198Y0197R180 S1      
317m8702            VIA   -    MD0100PA00X+091027Y+024266X0200Y         S0      
327m8703            R139  -1          A18X+091300Y+091558X0198Y0197R090 S2      
327m8703            VIA   -    M      A18X+090901Y+091900X0260Y         S2      
327m8703            U213  -7          A18X+090901Y+092401X0100Y0220R180 S2      
327m8703            C9    -1   M      A18X+090900Y+091558X0198Y0197R090 S2      
327m8704            J41   -A10        A01X+068294Y+005354X0150Y0570R180 S1      
327m8704            R1460 -1          A18X+068229Y+005125X0198Y0197R270 S2      
317m8704            VIA   -    M      A01X+068229Y+004682X0200Y         S2      
017m8704            VIA   -    M      A18X+068229Y+004682X0260Y         S2      
017m8704                  -    MD0100PA00X+068229Y+004682                       
317m8704            VIA   -    MD0100PA00X+084331Y+033555X0200Y         S0      
317m8704            VIA   -    MD0100PA00X+095190Y+080816X0200Y         S0      
327m8704            R3111 -1          A18X+114052Y+167394X0198Y0197R180 S2      
317m8704            VIA   -    MD0100PA00X+113421Y+166923X0200Y         S0      
327m8705            J41   -A9         A01X+068530Y+005354X0150Y0570R180 S1      
327m8705            R332  -1          A18X+068629Y+005261X0198Y0197R270 S2      
317m8705            VIA   -    M      A01X+068461Y+004186X0200Y         S2      
017m8705            VIA   -    M      A18X+068461Y+004186X0260Y         S2      
017m8705                  -    MD0100PA00X+068461Y+004186                       
327m8705            R3112 -1          A18X+067829Y+005211X0198Y0197R270 S2      
327m8706            VIA   -    M      A18X+148299Y+169045X0260Y         S2      
317m8706            VIA   -    MD0100PA00X+142227Y+162895X0200Y         S0      
317m8706            J106  -N2   D0142PA00X+151083Y+167201X0302Y    R180 S3      
327m8706            R2674 -2          A18X+113992Y+167900X0198Y0197     S2      
317m8706            VIA   -    MD0100PA00X+114136Y+167654X0200Y         S0      
327m8707            VIA   -    M      A18X+147642Y+168896X0260Y         S2      
317m8707            J106  -N4   D0142PA00X+152657Y+167201X0302Y    R180 S3      
317m8707            VIA   -    MD0100PA00X+142215Y+162627X0200Y         S0      
327m8707            R2675 -2          A18X+113658Y+167900X0198Y0197R180 S2      
317m8707            VIA   -    MD0100PA00X+113658Y+167624X0200Y         S0      
327m8708            R567  -1          A18X+063495Y+075790X0180Y0200R090 S2      
317m8708            VIA   -    MD0100PA00X+064027Y+076349X0200Y    R180 S0      
317m8708            VIA   -    M      A01X+070516Y+064536X0200Y         S2      
017m8708            VIA   -    M      A18X+070516Y+064536X0260Y         S2      
017m8708                  -    MD0100PA00X+070516Y+064536                       
327m8708            U108  -2          A01X+071914Y+064615X0100Y0210R180 S1      
327m8709            R566  -1          A18X+062841Y+075885X0180Y0200R090 S2      
327m8709            VIA   -    M      A18X+062454Y+076554X0260Y    R180 S2      
317m8709            VIA   -    MD0100PA00X+063156Y+077336X0200Y         S0      
327m8709            U108  -1          A01X+071718Y+064615X0120Y0210R180 S1      
317m8710            VIA   -    MD0080PA00X+056218Y+087325X0160Y    R180 S0      
327m8710            R567  -2          A18X+063495Y+076105X0180Y0200R090 S2      
327m8710            R991  -1   M      A18X+063495Y+076105X0180Y0200R090 S2      
327m8710            R541  -2          A18X+063280Y+075418X0198Y0197R270 S2      
327m8710            U26   -A5         A01X+056035Y+087429X0177Y    R180 S1      
327m8710            VIA   -    M      A18X+062951Y+078905X0260Y    R180 S2      
317m8711            VIA   -    MD0080PA00X+055478Y+087962X0160Y    R180 S0      
327m8711            R566  -2          A18X+062841Y+076200X0180Y0200R090 S2      
327m8711            R990  -1   M      A18X+062841Y+076200X0180Y0200R090 S2      
327m8711            U26   -C7         A01X+055294Y+088067X0177Y    R180 S1      
327m8711            VIA   -    M      A18X+063248Y+078160X0260Y    R180 S2      
327m8711            R542  -2          A18X+062880Y+075418X0198Y0197R270 S2      
327m8712            R429  -1          A18X+150818Y+080591X0180Y0200R090 S2      
317m8712            VIA   -    MD0100PA00X+150818Y+080349X0200Y    R180 S0      
317m8712            VIA   -    M      A01X+173304Y+065709X0200Y         S2      
017m8712            VIA   -    M      A18X+173304Y+065709X0260Y         S2      
017m8712                  -    MD0100PA00X+173304Y+065709                       
327m8712            U106  -2          A01X+172885Y+066325X0100Y0210R270 S1      
327m8713            R428  -1          A18X+149718Y+080591X0180Y0200R090 S2      
317m8713            VIA   -    MD0100PA00X+149653Y+080351X0200Y    R180 S0      
317m8713            VIA   -    M      A01X+172005Y+064914X0200Y         S2      
017m8713            VIA   -    M      A18X+172005Y+064914X0260Y         S2      
017m8713                  -    MD0100PA00X+172005Y+064914                       
327m8713            U106  -1          A01X+172885Y+066128X0120Y0210R270 S1      
327m8714            VIA   -    M      A18X+150400Y+081264X0160Y0041R090 S2      
327m8714            R429  -2          A18X+150818Y+080906X0180Y0200R090 S2      
327m8714            R987  -1   M      A18X+150818Y+080906X0180Y0200R090 S2      
327m8714            U25   -A5         A01X+153649Y+087429X0177Y    R180 S1      
317m8714            VIA   -    MD0100PA00X+151026Y+081461X0200Y         S0      
327m8714            R420  -2   M      A18X+150400Y+080906X0198Y0197R270 S2      
327m8715            R428  -2          A18X+149718Y+080906X0180Y0200R090 S2      
327m8715            R986  -1   M      A18X+149718Y+080906X0180Y0200R090 S2      
317m8715            VIA   -    M      A01X+150050Y+080906X0200Y    R180 S2      
017m8715            VIA   -    M      A18X+150050Y+080906X0260Y    R180 S2      
017m8715                  -    MD0100PA00X+150050Y+080906                       
327m8715            U25   -C7         A01X+152909Y+088067X0177Y    R180 S1      
327m8715            R421  -2          A18X+149318Y+080906X0198Y0197R270 S2      
327m8716            R565  -1          A01X+016642Y+067650X0180Y0200R180 S1      
317m8716            VIA   -    M      A01X+015951Y+067486X0200Y         S2      
017m8716            VIA   -    M      A18X+015951Y+067486X0260Y         S2      
017m8716                  -    MD0100PA00X+015951Y+067486                       
327m8716            U107  -2          A01X+015522Y+067610X0100Y0210R270 S1      
327m8717            R564  -1          A01X+016642Y+067050X0180Y0200R180 S1      
317m8717            VIA   -    M      A01X+016337Y+067086X0200Y         S2      
017m8717            VIA   -    M      A18X+016337Y+067086X0260Y         S2      
017m8717                  -    MD0100PA00X+016337Y+067086                       
327m8717            U107  -1          A01X+015522Y+067414X0120Y0210R270 S1      
327m8718            VIA   -    M      A01X+018470Y+067766X0300Y         S1      
327m8718            R565  -2          A01X+016958Y+067650X0180Y0200R180 S1      
327m8718            R989  -1   M      A01X+016958Y+067650X0180Y0200R180 S1      
327m8718            R543  -2   M      A01X+017642Y+067650X0198Y0197R180 S1      
327m8718            U26   -B71        A01X+031794Y+087748X0177Y    R180 S1      
327m8719            VIA   -    M      A01X+018642Y+067156X0300Y         S1      
327m8719            R564  -2          A01X+016958Y+067050X0180Y0200R180 S1      
327m8719            R988  -1   M      A01X+016958Y+067050X0180Y0200R180 S1      
327m8719            U26   -A71        A01X+031980Y+087429X0177Y    R180 S1      
327m8719            R563  -2   M      A01X+017642Y+067250X0198Y0197R180 S1      
327m8720            R427  -1          A01X+125678Y+076102X0180Y0200R090 S1      
327m8720            U105  -2          A01X+119071Y+058134X0100Y0210R270 S1      
317m8720            VIA   -    M      A01X+119937Y+057815X0200Y         S2      
017m8720            VIA   -    M      A18X+119937Y+057815X0260Y         S2      
017m8720                  -    MD0100PA00X+119937Y+057815                       
317m8720            VIA   -    MD0100PA00X+119939Y+059050X0200Y         S0      
327m8721            R426  -1          A01X+126371Y+076102X0180Y0200R090 S1      
317m8721            VIA   -    M      A01X+120873Y+058599X0200Y         S2      
017m8721            VIA   -    M      A18X+120873Y+058599X0260Y         S2      
017m8721                  -    MD0100PA00X+120873Y+058599                       
327m8721            U105  -1          A01X+119071Y+057937X0120Y0210R270 S1      
317m8721            VIA   -    MD0100PA00X+119109Y+057381X0200Y         S0      
327m8722            R427  -2          A01X+125678Y+075786X0180Y0200R090 S1      
327m8722            R2311 -1   M      A01X+125678Y+075786X0180Y0200R090 S1      
327m8722            U25   -B71        A01X+129409Y+087748X0177Y    R180 S1      
327m8722            VIA   -    M      A01X+125908Y+076900X0300Y    R180 S1      
327m8722            R423  -2   M      A01X+125908Y+076500X0198Y0197     S1      
327m8723            R426  -2          A01X+126371Y+075786X0180Y0200R090 S1      
327m8723            R2310 -1   M      A01X+126371Y+075786X0180Y0200R090 S1      
327m8723            U25   -A71        A01X+129594Y+087429X0177Y    R180 S1      
327m8723            VIA   -    M      A01X+126490Y+076911X0300Y    R180 S1      
327m8723            R425  -2   M      A01X+126292Y+076500X0198Y0197R180 S1      
327m8724            J41   -OB13       A01X+072387Y+006516X0150Y0570R180 S1      
327m8724            VIA   -           A18X+069032Y+048184X0260Y         S2      
327m8724            U18   -D16        A01X+070678Y+046714X0160Y    R090 S1      
317m8724            VIA   -    MD0100PA00X+070524Y+046867X0180Y    R090 S0      
317m8724            VIA   -    MD0100PA00X+072679Y+006056X0200Y         S0      
317HSC_VTEMP        VIA   -    MD0100PA00X+077442Y+158728X0200Y         S0      
327HSC_VTEMP        PU287 -18         A01X+077677Y+158728X0100Y0150R270 S1      
327HSC_VTEMP        PU297 -18         A01X+090277Y+158728X0100Y0150R270 S1      
317HSC_VTEMP        VIA   -    MD0100PA00X+090015Y+158728X0200Y         S0      
317HSC_VTEMP        VIA   -    MD0100PA00X+085815Y+158728X0200Y         S0      
327HSC_VTEMP        PU296 -18         A01X+086077Y+158728X0100Y0150R270 S1      
317HSC_VTEMP        VIA   -    MD0100PA00X+081615Y+158728X0200Y         S0      
327HSC_VTEMP        PU288 -18         A01X+081877Y+158728X0100Y0150R270 S1      
317HSC_VTEMP        VIA   -    M      A01X+071036Y+158930X0200Y    R270 S2      
017HSC_VTEMP        VIA   -    M      A18X+071036Y+158930X0260Y    R270 S2      
017HSC_VTEMP              -    MD0100PA00X+071036Y+158930                       
327HSC_VTEMP        PU289 -15         A01X+071670Y+158679X0090Y0150R270 S1      
327HSC_VTEMP        PC2192-1          A01X+070508Y+159650X0198Y0197R180 S1      
327HSC_VTEMP        PR3935-1   M      A01X+070518Y+159252X0198Y0197R180 S1      
327HSC_VSENSE       PR3926-2          A01X+072518Y+160673X0198Y0197R180 S1      
327HSC_VSENSE       PU289 -9          A01X+072590Y+159117X0090Y0150     S1      
327HSC_VSENSE       PC2189-1   M      A01X+072305Y+159936X0198Y0197R090 S1      
317HSC_VSENSE       VIA   -    M      A01X+072655Y+159936X0200Y         S2      
017HSC_VSENSE       VIA   -    M      A18X+072655Y+159936X0260Y         S2      
017HSC_VSENSE             -    MD0100PA00X+072655Y+159936                       
327HSC_VSENSE       PR3927-1          A18X+072189Y+160166X0198Y0197R270 S2      
327HSC_VOSEN        PR3931-2          A18X+072418Y+156633X0198Y0197     S2      
317HSC_VOSEN        VIA   -    M      A01X+072144Y+157096X0200Y    R270 S2      
017HSC_VOSEN        VIA   -    M      A18X+072144Y+157096X0260Y    R270 S2      
017HSC_VOSEN              -    MD0100PA00X+072144Y+157096                       
327HSC_VOSEN        PC2190-1          A01X+072032Y+156633X0198Y0197R180 S1      
327HSC_VOSEN        PU289 -24         A01X+072236Y+157355X0090Y0150     S1      
327HSC_VOSEN        PR3932-1          A18X+072270Y+157428X0198Y0197     S2      
327HSC_VIN_UVW_N    PR2106-2          A01X+070508Y+160050X0198Y0197     S1      
317HSC_VIN_UVW_N    VIA   -    M      A01X+070984Y+159472X0300Y    R270 S1      
017HSC_VIN_UVW_N    VIA   -    M      A18X+070984Y+159472X0200Y    R270 S1      
017HSC_VIN_UVW_N          -    MD0100PA00X+070984Y+159472                       
327HSC_VIN_UVW_N    PU289 -14         A01X+071670Y+158856X0090Y0150R270 S1      
327HSC_VDD_R_4      PR3981-1          A18X+088945Y+158403X0198Y0197R270 S2      
317HSC_VDD_R_4      VIA   -    M      A01X+089405Y+158403X0200Y         S2      
017HSC_VDD_R_4      VIA   -    M      A18X+089405Y+158403X0260Y         S2      
017HSC_VDD_R_4            -    MD0100PA00X+089405Y+158403                       
327HSC_VDD_R_4      PU297 -21         A01X+090277Y+158138X0100Y0150R270 S1      
327HSC_VDD_R_4      PC2223-1   M      A01X+089675Y+158186X0198Y0197R090 S1      
327HSC_VDD_R_3      PR3980-1          A18X+084745Y+158403X0198Y0197R270 S2      
317HSC_VDD_R_3      VIA   -    M      A01X+085205Y+158403X0200Y         S2      
017HSC_VDD_R_3      VIA   -    M      A18X+085205Y+158403X0260Y         S2      
017HSC_VDD_R_3            -    MD0100PA00X+085205Y+158403                       
327HSC_VDD_R_3      PU296 -21         A01X+086077Y+158138X0100Y0150R270 S1      
327HSC_VDD_R_3      PC3272-1   M      A01X+085475Y+158186X0198Y0197R090 S1      
327HSC_VDD_R_2      PR3911-1          A18X+080545Y+158403X0198Y0197R270 S2      
317HSC_VDD_R_2      VIA   -    M      A01X+081005Y+158403X0200Y         S2      
017HSC_VDD_R_2      VIA   -    M      A18X+081005Y+158403X0260Y         S2      
017HSC_VDD_R_2            -    MD0100PA00X+081005Y+158403                       
327HSC_VDD_R_2      PU288 -21         A01X+081877Y+158138X0100Y0150R270 S1      
327HSC_VDD_R_2      PC2181-1   M      A01X+081275Y+158186X0198Y0197R090 S1      
327HSC_VDD_R_1      PR3910-1          A18X+076235Y+158123X0198Y0197R270 S2      
317HSC_VDD_R_1      VIA   -    M      A01X+076695Y+158123X0200Y         S2      
017HSC_VDD_R_1      VIA   -    M      A18X+076695Y+158123X0260Y         S2      
017HSC_VDD_R_1            -    MD0100PA00X+076695Y+158123                       
327HSC_VDD_R_1      PU287 -21         A01X+077677Y+158138X0100Y0150R270 S1      
327HSC_VDD_R_1      PC1525-1   M      A01X+077045Y+158096X0198Y0197R090 S1      
327HSC_VDD_R        PR2149-1          A01X+070518Y+158852X0198Y0197R180 S1      
327HSC_VDD_R        PC2186-1   M      A18X+072195Y+158078X0198Y0197R270 S2      
327HSC_VDD_R        PU289 -45  M      A01X+072196Y+157793X0460Y0630R270 S1      
317HSC_VDD_R        VIA   -    MD0100PA00X+072396Y+157893X0200Y    R270 S0      
317HSC_VDD_R        VIA   -    MD0100PA00X+071996Y+157893X0200Y    R270 S0      
317HSC_VDD_R        VIA   -    MD0100PA00X+072196Y+157693X0200Y    R270 S0      
317HSC_VDD_R        VIA   -    M      A01X+071008Y+158168X0200Y    R270 S2      
017HSC_VDD_R        VIA   -    M      A18X+071008Y+158168X0260Y    R270 S2      
017HSC_VDD_R              -    MD0100PA00X+071008Y+158168                       
327HSC_VDD_R        PC2187-1   M      A01X+070518Y+158452X0198Y0197R180 S1      
327HSC_VDD_R        PU289 -17         A01X+071670Y+158325X0090Y0150R270 S1      
317HSC_VDD18        VIA   -    M      A01X+071055Y+157652X0300Y    R270 S1      
017HSC_VDD18        VIA   -    M      A18X+071055Y+157652X0200Y    R270 S1      
017HSC_VDD18              -    MD0100PA00X+071055Y+157652                       
327HSC_VDD18        PC2103-1          A01X+070518Y+157652X0198Y0197R180 S1      
327HSC_VDD18        PU289 -19         A01X+071670Y+157970X0090Y0150R270 S1      
327HSC_VDD18        PR3929-2          A01X+070192Y+155650X0198Y0197R180 S1      
317HSC_VDD18        VIA   -    MD0100PA00X+069950Y+155900X0200Y         S0      
327HSC_VDD          R2587 -2          A18X+075301Y+158402X0198Y0197R090 S2      
327HSC_VDD          R3936 -1   M      A18X+075301Y+157917X0198Y0197R090 S2      
327HSC_VDD          PR2149-2          A01X+070204Y+158852X0198Y0197R180 S1      
327HSC_VDD          PR3981-2          A18X+088945Y+158718X0198Y0197R270 S2      
317HSC_VDD          VIA   -    MD0100PA00X+088670Y+158718X0200Y         S0      
327HSC_VDD          PR3980-2          A18X+084745Y+158718X0198Y0197R270 S2      
317HSC_VDD          VIA   -    MD0100PA00X+084470Y+158718X0200Y         S0      
317HSC_VDD          VIA   -    MD0100PA00X+080270Y+158718X0200Y         S0      
327HSC_VDD          PR3911-2          A18X+080545Y+158718X0198Y0197R270 S2      
317HSC_VDD          VIA   -    M      A01X+075464Y+159257X0200Y         S2      
017HSC_VDD          VIA   -    M      A18X+075464Y+159257X0260Y         S2      
017HSC_VDD                -    MD0100PA00X+075464Y+159257                       
327HSC_VDD          PR3910-2          A18X+076235Y+158438X0198Y0197R270 S2      
317HSC_VDD          VIA   -    MD0100PA00X+069950Y+158850X0200Y         S0      
327HSC_VDD          PR2106-1          A01X+070192Y+160050X0198Y0197     S1      
317HSC_VDD          VIA   -    MD0100PA00X+069950Y+159950X0200Y         S0      
327HSC_SS           PC2184-1          A01X+076622Y+158773X0198Y0197R180 S1      
327HSC_SS           PU287 -19         A01X+077677Y+158532X0100Y0150R270 S1      
317HSC_SS           VIA   -    MD0100PA00X+077155Y+158713X0200Y         S0      
327HSC_SS           PC2185-1          A01X+080772Y+159463X0198Y0197R180 S1      
327HSC_SS           PU288 -19         A01X+081877Y+158532X0100Y0150R270 S1      
317HSC_SS           VIA   -    MD0100PA00X+081305Y+159063X0200Y         S0      
327HSC_SS           PC2226-1          A01X+084972Y+159463X0198Y0197R180 S1      
327HSC_SS           PU296 -19         A01X+086077Y+158532X0100Y0150R270 S1      
317HSC_SS           VIA   -    MD0100PA00X+085505Y+159063X0200Y         S0      
327HSC_SS           PC2227-1          A01X+089172Y+159463X0198Y0197R180 S1      
327HSC_SS           PU297 -19         A01X+090277Y+158532X0100Y0150R270 S1      
317HSC_SS           VIA   -    MD0100PA00X+089705Y+159063X0200Y         S0      
317HSC_SS           VIA   -    M      A01X+071042Y+158517X0300Y    R270 S1      
017HSC_SS           VIA   -    M      A18X+071042Y+158517X0200Y    R270 S1      
017HSC_SS                 -    MD0100PA00X+071042Y+158517                       
327HSC_SS           PU289 -16         A01X+071670Y+158502X0090Y0150R270 S1      
327HSC_SS           PC2191-1          A01X+069850Y+159092X0198Y0197R090 S1      
327HSC_SCREF_4      VIA   -    M      A01X+089806Y+159632X0300Y         S1      
327HSC_SCREF_4      PR3989-2          A01X+089172Y+160663X0198Y0197     S1      
327HSC_SCREF_4      PU297 -17         A01X+090272Y+158925X0100Y0140R270 S1      
327HSC_SCREF_3      VIA   -    M      A01X+085602Y+159692X0300Y         S1      
327HSC_SCREF_3      PR3988-2          A01X+084972Y+160663X0198Y0197     S1      
327HSC_SCREF_3      PU296 -17         A01X+086072Y+158925X0100Y0140R270 S1      
327HSC_SCREF_2      VIA   -    M      A01X+081357Y+159753X0300Y         S1      
327HSC_SCREF_2      PR3917-2          A01X+080772Y+160663X0198Y0197     S1      
327HSC_SCREF_2      PU288 -17         A01X+081872Y+158925X0100Y0140R270 S1      
327HSC_SCREF_1      VIA   -    M      A01X+077165Y+159173X0300Y         S1      
327HSC_SCREF_1      PR3916-2          A01X+076622Y+159173X0198Y0197     S1      
327HSC_SCREF_1      PU287 -17         A01X+077672Y+158925X0100Y0140R270 S1      
317HSC_SCREF        VIA   -    MD0100PA00X+084415Y+160663X0200Y         S0      
327HSC_SCREF        PR3988-1          A01X+084658Y+160663X0198Y0197     S1      
317HSC_SCREF        VIA   -    MD0100PA00X+080215Y+160663X0200Y         S0      
327HSC_SCREF        PR3917-1          A01X+080458Y+160663X0198Y0197     S1      
317HSC_SCREF        VIA   -    MD0100PA00X+076052Y+159550X0200Y         S0      
327HSC_SCREF        PR3916-1          A01X+076308Y+159173X0198Y0197     S1      
317HSC_SCREF        VIA   -    MD0100PA00X+088615Y+160663X0200Y         S0      
327HSC_SCREF        PR3989-1          A01X+088858Y+160663X0198Y0197     S1      
327HSC_SCREF        PU289 -25         A01X+072413Y+157355X0090Y0150     S1      
317HSC_SCREF        VIA   -    M      A01X+072411Y+156182X0200Y    R270 S2      
017HSC_SCREF        VIA   -    M      A18X+072411Y+156182X0260Y    R270 S2      
017HSC_SCREF              -    MD0100PA00X+072411Y+156182                       
317HSC_ON_R         VIA   -    M      A01X+074711Y+157986X0300Y    R270 S1      
017HSC_ON_R         VIA   -    M      A18X+074711Y+157986X0200Y    R270 S1      
017HSC_ON_R               -    MD0100PA00X+074711Y+157986                       
327HSC_ON_R         PR3928-2          A01X+075204Y+158002X0198Y0197R180 S1      
327HSC_ON_R         PU289 -38         A01X+074219Y+158148X0090Y0150R270 S1      
317HSC_ON           VIA   -    MD0100PA00X+092565Y+158138X0200Y         S0      
327HSC_ON           PC2225-1          A01X+093058Y+158223X0198Y0197     S1      
327HSC_ON           PU297 -4          A01X+092039Y+158138X0100Y0150R270 S1      
317HSC_ON           VIA   -    MD0100PA00X+088315Y+158138X0200Y         S0      
327HSC_ON           PC2224-1          A01X+088858Y+159063X0198Y0197     S1      
327HSC_ON           PU296 -4          A01X+087839Y+158138X0100Y0150R270 S1      
327HSC_ON           PC2183-1          A01X+084658Y+159063X0198Y0197     S1      
327HSC_ON           PU288 -4          A01X+083639Y+158138X0100Y0150R270 S1      
317HSC_ON           VIA   -    MD0100PA00X+084115Y+158138X0200Y         S0      
327HSC_ON           PC2182-1          A01X+080458Y+159063X0198Y0197     S1      
327HSC_ON           PU287 -4          A01X+079439Y+158138X0100Y0150R270 S1      
317HSC_ON           VIA   -    M      A01X+079915Y+158138X0200Y         S2      
017HSC_ON           VIA   -    M      A18X+079915Y+158138X0260Y         S2      
017HSC_ON                 -    MD0100PA00X+079915Y+158138                       
327HSC_ON           PR3928-1          A01X+075518Y+158002X0198Y0197R180 S1      
317HSC_ON           VIA   -    MD0100PA00X+075765Y+158002X0200Y         S0      
317HSC_OCREF        VIA   -    MD0100PA00X+076621Y+156804X0200Y         S0      
327HSC_OCREF        PC2347-1          A01X+076621Y+157063X0198Y0197R180 S1      
327HSC_OCREF        PU287 -24         A01X+077672Y+157547X0100Y0140R270 S1      
317HSC_OCREF        VIA   -    M      A01X+071490Y+157127X0200Y    R270 S2      
017HSC_OCREF        VIA   -    M      A18X+071490Y+157127X0260Y    R270 S2      
017HSC_OCREF              -    MD0100PA00X+071490Y+157127                       
327HSC_OCREF        PU289 -22         A01X+071881Y+157355X0090Y0150     S1      
327HSC_OCREF        PU288 -24         A01X+081872Y+157547X0100Y0140R270 S1      
327HSC_OCREF        PC2348-1          A01X+080772Y+157063X0198Y0197R180 S1      
317HSC_OCREF        VIA   -    MD0100PA00X+081315Y+157063X0200Y         S0      
327HSC_OCREF        PC2350-1          A01X+084972Y+157063X0198Y0197R180 S1      
327HSC_OCREF        PU296 -24         A01X+086072Y+157547X0100Y0140R270 S1      
317HSC_OCREF        VIA   -    MD0100PA00X+085515Y+157063X0200Y         S0      
317HSC_OCREF        VIA   -    MD0100PA00X+089715Y+157063X0200Y         S0      
327HSC_OCREF        PU297 -24         A01X+090272Y+157547X0100Y0140R270 S1      
327HSC_OCREF        PC2349-1          A01X+089172Y+157063X0198Y0197R180 S1      
327HSC_NC1_4        VIA   -           A01X+093776Y+159488X0300Y         S1      
327HSC_NC1_4        PU297 -7          A01X+092039Y+158728X0100Y0150R270 S1      
327HSC_NC1_3        VIA   -           A01X+088383Y+159872X0300Y         S1      
327HSC_NC1_3        PU296 -7          A01X+087839Y+158728X0100Y0150R270 S1      
327HSC_NC1_2        VIA   -           A01X+084185Y+159875X0300Y         S1      
327HSC_NC1_2        PU288 -7          A01X+083639Y+158728X0100Y0150R270 S1      
327HSC_NC1_1        VIA   -           A01X+079978Y+159872X0300Y         S1      
327HSC_NC1_1        PU287 -7          A01X+079439Y+158728X0100Y0150R270 S1      
327HSC_MODE_4       VIA   -    M      A01X+092573Y+159226X0300Y         S1      
327HSC_MODE_4       PU297 -8          A01X+092044Y+158925X0100Y0140R270 S1      
327HSC_MODE_4       PR3984-2          A01X+093058Y+159023X0198Y0197R180 S1      
327HSC_MODE_3       VIA   -    M      A01X+088390Y+160386X0300Y         S1      
327HSC_MODE_3       PR3982-2          A01X+088858Y+160263X0198Y0197R180 S1      
327HSC_MODE_3       PU296 -8          A01X+087844Y+158925X0100Y0140R270 S1      
327HSC_MODE_2       VIA   -    M      A01X+084192Y+160388X0300Y         S1      
327HSC_MODE_2       PR3912-2          A01X+084658Y+160263X0198Y0197R180 S1      
327HSC_MODE_2       PU288 -8          A01X+083644Y+158925X0100Y0140R270 S1      
327HSC_MODE_1       VIA   -    M      A01X+079989Y+160383X0300Y         S1      
327HSC_MODE_1       PU287 -8          A01X+079444Y+158925X0100Y0140R270 S1      
327HSC_MODE_1       PR1134-2          A01X+080458Y+160263X0198Y0197R180 S1      
317HSC_MODE         VIA   -    M      A01X+074917Y+159197X0200Y    R270 S2      
017HSC_MODE         VIA   -    M      A18X+074917Y+159197X0260Y    R270 S2      
017HSC_MODE               -    MD0100PA00X+074917Y+159197                       
327HSC_MODE         PR3937-1          A01X+075204Y+158902X0198Y0197     S1      
327HSC_MODE         PU289 -41         A01X+074219Y+158679X0090Y0150R270 S1      
317HSC_IMON         VIA   -    M      A01X+070899Y+156851X0300Y    R270 S1      
017HSC_IMON         VIA   -    M      A18X+070899Y+156851X0200Y    R270 S1      
017HSC_IMON               -    MD0100PA00X+070899Y+156851                       
327HSC_IMON         PC2193-1          A01X+070518Y+156452X0198Y0197R180 S1      
327HSC_IMON         PR1133-1   M      A01X+070518Y+156852X0198Y0197R180 S1      
327HSC_IMON         PU289 -21         A01X+071670Y+157616X0090Y0150R270 S1      
317HSC_IMON         VIA   -    MD0100PA00X+077145Y+157733X0200Y         S0      
327HSC_IMON         PU287 -22         A01X+077677Y+157941X0100Y0150R270 S1      
327HSC_IMON         PR3918-1          A01X+076622Y+157873X0198Y0197R180 S1      
317HSC_IMON         VIA   -    MD0100PA00X+081315Y+157941X0200Y         S0      
327HSC_IMON         PU288 -22         A01X+081877Y+157941X0100Y0150R270 S1      
327HSC_IMON         PR1101-1          A01X+080772Y+158263X0198Y0197R180 S1      
327HSC_IMON         PU297 -22         A01X+090277Y+157941X0100Y0150R270 S1      
327HSC_IMON         PR3991-1          A01X+089172Y+158263X0198Y0197R180 S1      
317HSC_IMON         VIA   -    MD0100PA00X+089715Y+157941X0200Y         S0      
317HSC_IMON         VIA   -    MD0100PA00X+085515Y+157941X0200Y         S0      
327HSC_IMON         PR3990-1          A01X+084972Y+158263X0198Y0197R180 S1      
327HSC_IMON         PU296 -22         A01X+086077Y+157941X0100Y0150R270 S1      
327HSC_FLT_TYPE_4   VIA   -    M      A01X+092565Y+158673X0300Y         S1      
327HSC_FLT_TYPE_4   PU297 -6          A01X+092039Y+158532X0100Y0150R270 S1      
327HSC_FLT_TYPE_4   PR3995-1          A01X+093058Y+158623X0198Y0197     S1      
327HSC_FLT_TYPE_3   VIA   -    M      A01X+088387Y+159163X0300Y         S1      
327HSC_FLT_TYPE_3   PR3993-1          A01X+088858Y+159863X0198Y0197     S1      
327HSC_FLT_TYPE_3   PU296 -6          A01X+087839Y+158532X0100Y0150R270 S1      
327HSC_FLT_TYPE_2   VIA   -    M      A01X+084178Y+159157X0300Y         S1      
327HSC_FLT_TYPE_2   PR3922-1          A01X+084658Y+159863X0198Y0197     S1      
327HSC_FLT_TYPE_2   PU288 -6          A01X+083639Y+158532X0100Y0150R270 S1      
327HSC_FLT_TYPE_1   VIA   -    M      A01X+079978Y+159150X0300Y         S1      
327HSC_FLT_TYPE_1   PU287 -6          A01X+079439Y+158532X0100Y0150R270 S1      
327HSC_FLT_TYPE_1   PR3920-1          A01X+080458Y+159863X0198Y0197     S1      
327HSC_FLT_TYPE     PR3993-2          A01X+089172Y+159863X0198Y0197     S1      
317HSC_FLT_TYPE     VIA   -    MD0100PA00X+089415Y+159863X0200Y         S0      
327HSC_FLT_TYPE     PR3995-2          A01X+093372Y+158623X0198Y0197     S1      
317HSC_FLT_TYPE     VIA   -    MD0100PA00X+093615Y+158623X0200Y         S0      
327HSC_FLT_TYPE     PR3922-2          A01X+084972Y+159863X0198Y0197     S1      
317HSC_FLT_TYPE     VIA   -    MD0100PA00X+085215Y+159863X0200Y         S0      
327HSC_FLT_TYPE     PR3920-2          A01X+080772Y+159863X0198Y0197     S1      
317HSC_FLT_TYPE     VIA   -    MD0100PA00X+081015Y+159863X0200Y         S0      
327HSC_FLT_TYPE     PU289 -40         A01X+074219Y+158502X0090Y0150R270 S1      
317HSC_FLT_TYPE     VIA   -    M      A01X+074716Y+158777X0300Y         S1      
017HSC_FLT_TYPE     VIA   -    M      A18X+074716Y+158777X0200Y         S1      
017HSC_FLT_TYPE           -    MD0100PA00X+074716Y+158777                       
327HSC_FAULT        PU297 -5          A01X+092039Y+158335X0100Y0150R270 S1      
317HSC_FAULT        VIA   -    MD0100PA00X+092265Y+158335X0200Y         S0      
327HSC_FAULT        PU296 -5          A01X+087839Y+158335X0100Y0150R270 S1      
317HSC_FAULT        VIA   -    MD0100PA00X+088065Y+158335X0200Y         S0      
327HSC_FAULT        PU288 -5          A01X+083639Y+158335X0100Y0150R270 S1      
317HSC_FAULT        VIA   -    MD0100PA00X+083865Y+158335X0200Y         S0      
327HSC_FAULT        PU287 -5          A01X+079439Y+158335X0100Y0150R270 S1      
317HSC_FAULT        VIA   -    MD0100PA00X+079665Y+158335X0200Y         S0      
317HSC_FAULT        VIA   -    M      A01X+074715Y+158325X0200Y    R270 S2      
017HSC_FAULT        VIA   -    M      A18X+074715Y+158325X0260Y    R270 S2      
017HSC_FAULT              -    MD0100PA00X+074715Y+158325                       
327HSC_FAULT        PU289 -39         A01X+074219Y+158325X0090Y0150R270 S1      
327HSC_FAULT        R2588 -1          A01X+075204Y+158402X0198Y0197     S1      
317HSC_EN_R         VIA   -    M      A01X+072648Y+157129X0200Y    R270 S2      
017HSC_EN_R         VIA   -    M      A18X+072648Y+157129X0260Y    R270 S2      
017HSC_EN_R               -    MD0100PA00X+072648Y+157129                       
327HSC_EN_R         PU289 -26         A01X+072590Y+157355X0090Y0150     S1      
327HSC_EN_R         R2586 -2          A01X+072418Y+156633X0198Y0197R180 S1      
327HSC_EN           PJ38  -14         A01X+076291Y+149866X0240Y0650R090 S1      
317HSC_EN           VIA   -    MD0100PA00X+075816Y+149866X0200Y    R090 S0      
317HSC_EN           VIA   -    M      A01X+111170Y+155864X0200Y         S2      
017HSC_EN           VIA   -    M      A18X+111170Y+155864X0260Y         S2      
017HSC_EN                 -    MD0100PA00X+111170Y+155864                       
317HSC_EN           VIA   -    MD0100PA00X+107213Y+164792X0200Y         S0      
327HSC_EN           C2179 -1   M      A01X+106375Y+164792X0198Y0197R090 S1      
327HSC_EN           R2585 -1   M      A01X+106809Y+164792X0198Y0197R090 S1      
327HSC_EN           R4901 -2          A01X+104568Y+164620X0198Y0197     S1      
327HSC_EN           U290  -D   M      A01X+105461Y+164822X0320Y0360R180 S1      
327HSC_EN           R2586 -1          A01X+072732Y+156633X0198Y0197R180 S1      
317HSC_EN           VIA   -    MD0100PA00X+072732Y+156340X0200Y         S0      
327HSC_D_OC_R       PR3994-2          A01X+093372Y+157823X0198Y0197     S1      
317HSC_D_OC_R       VIA   -    MD0100PA00X+093615Y+157823X0200Y         S0      
327HSC_D_OC_R       PR3992-2          A01X+089172Y+157463X0198Y0197     S1      
317HSC_D_OC_R       VIA   -    MD0100PA00X+089415Y+157463X0200Y         S0      
327HSC_D_OC_R       PR3921-2          A01X+084972Y+157463X0198Y0197     S1      
317HSC_D_OC_R       VIA   -    MD0100PA00X+085215Y+157463X0200Y         S0      
327HSC_D_OC_R       PR3919-2          A01X+080772Y+157463X0198Y0197     S1      
317HSC_D_OC_R       VIA   -    M      A01X+081015Y+157463X0200Y         S2      
017HSC_D_OC_R       VIA   -    M      A18X+081015Y+157463X0260Y         S2      
017HSC_D_OC_R             -    MD0100PA00X+081015Y+157463                       
327HSC_D_OC_R       PU289 -37         A01X+074219Y+157970X0090Y0150R270 S1      
327HSC_D_OC_R       R3934 -1          A01X+075204Y+157602X0198Y0197     S1      
317HSC_D_OC_R       VIA   -    MD0100PA00X+074711Y+157586X0200Y    R270 S0      
327HSC_D_OC_4       VIA   -    M      A01X+092565Y+157623X0300Y         S1      
327HSC_D_OC_4       PU297 -3          A01X+092039Y+157941X0100Y0150R270 S1      
327HSC_D_OC_4       PR3994-1          A01X+093058Y+157823X0198Y0197     S1      
327HSC_D_OC_3       VIA   -    M      A01X+088315Y+157523X0300Y         S1      
327HSC_D_OC_3       PR3992-1          A01X+088858Y+157463X0198Y0197     S1      
327HSC_D_OC_3       PU296 -3          A01X+087839Y+157941X0100Y0150R270 S1      
327HSC_D_OC_2       VIA   -    M      A01X+084115Y+157523X0300Y         S1      
327HSC_D_OC_2       PU288 -3          A01X+083639Y+157941X0100Y0150R270 S1      
327HSC_D_OC_2       PR3921-1          A01X+084658Y+157463X0198Y0197     S1      
327HSC_D_OC_1       VIA   -    M      A01X+079915Y+157523X0300Y         S1      
327HSC_D_OC_1       PU287 -3          A01X+079439Y+157941X0100Y0150R270 S1      
327HSC_D_OC_1       PR3919-1          A01X+080458Y+157463X0198Y0197     S1      
317HSC_D_OC         VIA   -    MD0100PA00X+075761Y+157602X0200Y    R090 S0      
317HSC_D_OC         VIA   -    MD0100PA00X+069750Y+166133X0200Y         S0      
317HSC_D_OC         VIA   -    MD0100PA00X+079696Y+148747X0200Y         S0      
317HSC_D_OC         VIA   -    MD0100PA00X+082258Y+076017X0200Y         S0      
327HSC_D_OC         R6039 -2          A01X+064292Y+044986X0198Y0197R180 S1      
317HSC_D_OC         VIA   -    MD0100PA00X+063900Y+044986X0200Y         S0      
317HSC_D_OC         VIA   -    MD0100PA00X+064758Y+049796X0200Y         S0      
317HSC_D_OC         VIA   -    MD0100PA00X+074258Y+067609X0200Y         S0      
327HSC_D_OC         R3936 -2          A18X+075301Y+157602X0198Y0197R090 S2      
327HSC_D_OC         R3934 -2          A01X+075518Y+157602X0198Y0197     S1      
317HSC_D_OC         VIA   -    MD0100PA00X+069942Y+161663X0200Y         S0      
327HSC_D_OC         R6210 -2   M      A18X+069637Y+165834X0198Y0197     S2      
327HSC_D_OC         VIA   -    M      A18X+069634Y+166818X0260Y         S2      
327HSC_D_OC         R6239 -2   M      A18X+069255Y+165833X0198Y0197R180 S2      
327HSC_D_OC         R6238 -2   M      A18X+069254Y+166234X0198Y0197R180 S2      
327HSC_D_OC         U142  -6          A18X+070163Y+166963X0250Y0480     S2      
327HSC_CS_4         VIA   -    M      A01X+089738Y+157479X0300Y         S1      
327HSC_CS_4         PR3987-1          A01X+089172Y+157863X0198Y0197R180 S1      
327HSC_CS_4         PU297 -23         A01X+090277Y+157744X0100Y0150R270 S1      
327HSC_CS_3         VIA   -    M      A01X+085540Y+157548X0300Y         S1      
327HSC_CS_3         PU296 -23         A01X+086077Y+157744X0100Y0150R270 S1      
327HSC_CS_3         PR3986-1          A01X+084972Y+157863X0198Y0197R180 S1      
327HSC_CS_2         VIA   -    M      A01X+081340Y+157548X0300Y         S1      
327HSC_CS_2         PR3915-1          A01X+080772Y+157863X0198Y0197R180 S1      
327HSC_CS_2         PU288 -23         A01X+081877Y+157744X0100Y0150R270 S1      
327HSC_CS_1         VIA   -    M      A01X+077159Y+157272X0300Y         S1      
327HSC_CS_1         PR3914-1          A01X+076622Y+157473X0198Y0197R180 S1      
327HSC_CS_1         PU287 -23         A01X+077677Y+157744X0100Y0150R270 S1      
317HSC_CS           VIA   -    M      A01X+070860Y+157252X0200Y    R270 S2      
017HSC_CS           VIA   -    M      A18X+070860Y+157252X0260Y    R270 S2      
017HSC_CS                 -    MD0100PA00X+070860Y+157252                       
327HSC_CS           PR1131-1          A01X+070518Y+157252X0198Y0197R180 S1      
327HSC_CS           PU289 -20         A01X+071670Y+157793X0090Y0150R270 S1      
327HSC_ADDR         PR3929-1          A01X+070508Y+155650X0198Y0197R180 S1      
317HSC_ADDR         VIA   -    M      A01X+070850Y+156050X0200Y    R270 S2      
017HSC_ADDR         VIA   -    M      A18X+070850Y+156050X0260Y    R270 S2      
017HSC_ADDR               -    MD0100PA00X+070850Y+156050                       
327HSC_ADDR         PR3930-2   M      A01X+070522Y+156057X0198Y0197     S1      
327HSC_ADDR         PU289 -23         A01X+072058Y+157355X0090Y0150     S1      
327m8725            R1191 -1          A01X+005965Y+026822X0198Y0197     S1      
327m8725            U58   -4   M      A01X+005474Y+030854X0170Y0240R270 S1      
327m8725            U58   -6          A01X+005474Y+031366X0170Y0240R270 S1      
327m8725            VIA   -    M      A01X+006400Y+030600X0300Y         S1      
327m8725            U59   -6   M      A01X+005478Y+028292X0170Y0240R270 S1      
327m8725            R3142 -1   M      A01X+005978Y+027636X0198Y0197     S1      
327m8725            U59   -4   M      A01X+005478Y+027780X0170Y0240R270 S1      
327m8726            R6117 -1          A18X+067245Y+047336X0198Y0197R180 S2      
317m8726            VIA   -    M      A01X+022369Y+052245X0200Y         S2      
017m8726            VIA   -    M      A18X+022369Y+052245X0260Y         S2      
017m8726                  -    MD0100PA00X+022369Y+052245                       
327m8726            R3142 -2          A01X+006293Y+027636X0198Y0197     S1      
327m8726            R3147 -2   M      A01X+006293Y+027236X0198Y0197     S1      
327m8727            R1163 -1          A01X+035792Y+030750X0198Y0197     S1      
317m8727            VIA   -    MD0100PA00X+035792Y+030408X0200Y         S0      
317m8727            VIA   -    MD0100PA00X+039131Y+022787X0200Y         S0      
327m8727            R1182 -1          A01X+022952Y+015198X0198Y0197R090 S1      
317m8727            VIA   -    MD0100PA00X+023400Y+014800X0200Y         S0      
327m8727            R1196 -1          A18X+025037Y+011174X0198Y0197     S2      
327m8727            R1180 -2          A01X+060334Y+013641X0198Y0197     S1      
317m8727            VIA   -    M      A01X+032304Y+007312X0200Y         S2      
017m8727            VIA   -    M      A18X+032304Y+007312X0260Y         S2      
017m8727                  -    MD0100PA00X+032304Y+007312                       
327m8727            R3831 -2          A01X+032562Y+006986X0198Y0197     S1      
327m8727            R3825 -2   M      A01X+032562Y+007379X0198Y0197R270 S1      
327m8727            PU206 -10         A01X+025698Y+011177X0100Y0320R270 S1      
317m8727            VIA   -    MD0100PA00X+025387Y+011177X0200Y         S0      
327m8727            R3848 -2          A01X+025037Y+011174X0198Y0197     S1      
317m8727            VIA   -    MD0100PA00X+034108Y+005631X0200Y         S0      
317m8727            VIA   -    MD0100PA00X+061924Y+012323X0200Y         S0      
317m8727            VIA   -    MD0100PA00X+024835Y+016570X0200Y         S0      
327m8727            R1523 -1          A01X+022444Y+020682X0198Y0197     S1      
327m8728            R576  -1          A01X+181572Y+043168X0198Y0197     S1      
327m8728            VIA   -    M      A01X+181092Y+042743X0300Y         S1      
327m8728            U8    -6   M      A01X+180566Y+041062X0170Y0240R270 S1      
327m8728            U8    -4          A01X+180566Y+040550X0170Y0240R270 S1      
327m8728            R1148 -1   M      A01X+181572Y+042743X0198Y0197     S1      
327m8728            U211  -6   M      A01X+180565Y+042389X0170Y0240R270 S1      
327m8728            U211  -4   M      A01X+180565Y+041878X0170Y0240R270 S1      
317m8729            VIA   -    MD0100PA00X+085572Y+041661X0200Y         S0      
317m8729            VIA   -    M      A01X+123347Y+041974X0200Y         S2      
017m8729            VIA   -    M      A18X+123347Y+041974X0260Y         S2      
017m8729                  -    MD0100PA00X+123347Y+041974                       
317m8729            VIA   -    MD0100PA00X+182272Y+042495X0200Y         S0      
327m8729            R1148 -2          A01X+181887Y+042743X0198Y0197     S1      
327m8729            R1150 -2   M      A01X+182272Y+042743X0198Y0197R180 S1      
327m8729            R6046 -1          A01X+082399Y+042734X0198Y0197R180 S1      
317m8730            VIA   -    MD0100PA00X+087119Y+038223X0200Y         S0      
327m8730            R1509 -1          A01X+087119Y+038468X0198Y0197R090 S1      
327m8730            R1129 -1          A01X+078146Y+037804X0198Y0197R090 S1      
327m8730            R1135 -2          A01X+162552Y+028273X0198Y0197     S1      
327m8730            R1136 -1          A01X+178413Y+016282X0198Y0197R090 S1      
327m8730            R1137 -1          A01X+165754Y+043162X0198Y0197R270 S1      
317m8730            VIA   -    MD0100PA00X+165754Y+043451X0200Y         S0      
317m8730            VIA   -    MD0100PA00X+162799Y+028273X0200Y         S0      
317m8730            VIA   -    MD0100PA00X+178137Y+016282X0200Y         S0      
327m8730            PU204 -10         A01X+173210Y+011290X0100Y0320R270 S1      
317m8730            VIA   -    M      A01X+172896Y+011294X0200Y         S2      
017m8730            VIA   -    M      A18X+172896Y+011294X0260Y         S2      
017m8730                  -    MD0100PA00X+172896Y+011294                       
327m8730            R4532 -2          A01X+172549Y+011287X0198Y0197     S1      
317m8730            VIA   -    MD0100PA00X+178820Y+007496X0200Y         S0      
327m8730            R3144 -2          A01X+179074Y+007099X0198Y0197     S1      
327m8730            R3797 -2   M      A01X+179074Y+007491X0198Y0197R270 S1      
317m8730            VIA   -    MD0100PA00X+082980Y+033101X0200Y         S0      
317m8730            VIA   -    MD0100PA00X+082378Y+037638X0200Y         S0      
327m8731            R3263 -2          A01X+162548Y+028674X0198Y0197     S1      
317m8731            VIA   -    MD0100PA00X+162791Y+028674X0200Y    R090 S0      
317m8731            VIA   -    M      A01X+165411Y+043418X0200Y         S2      
017m8731            VIA   -    M      A18X+165411Y+043418X0260Y         S2      
017m8731                  -    MD0100PA00X+165411Y+043418                       
317m8731            VIA   -    MD0100PA00X+067000Y+044236X0200Y    R270 S0      
327m8731            R23   -2          A01X+067242Y+044236X0198Y0197R180 S1      
327m8731            R1071 -1          A01X+064608Y+044236X0198Y0197R180 S1      
317m8731            VIA   -    MD0100PA00X+178739Y+016583X0200Y    R270 S0      
327m8731            R5487 -1          A01X+178982Y+016583X0198Y0197     S1      
327m8731            R3845 -1          A01X+165379Y+043162X0198Y0197R270 S1      
327m8732            R6048 -1          A18X+078397Y+045580X0198Y0197R270 S2      
317m8732            VIA   -    MD0100PA00X+078338Y+045134X0200Y    R180 S0      
317m8732            VIA   -    MD0100PA00X+095816Y+044902X0200Y         S0      
317m8732            VIA   -    M      A01X+099058Y+015525X0200Y    R270 S2      
017m8732            VIA   -    M      A18X+099058Y+015525X0260Y    R270 S2      
017m8732                  -    MD0100PA00X+099058Y+015525                       
327m8732            R3972 -2          A01X+098550Y+015222X0198Y0197R270 S1      
327m8732            R3978 -2   M      A01X+099142Y+015230X0198Y0197R180 S1      
327m8732            R3948 -2          A01X+100140Y+021835X0198Y0197R270 S1      
317m8732            VIA   -    MD0100PA00X+100061Y+021504X0200Y    R270 S0      
327m8732            PU292 -10         A01X+100142Y+021174X0100Y0320R180 S1      
327RST_MB_STBY_N    R6033 -1          A18X+056820Y+005577X0198Y0197R090 S2      
327RST_MB_STBY_N    VIA   -    M      A18X+057193Y+006659X0260Y    R090 S2      
317RST_MB_STBY_N    VIA   -    MD0100PA00X+058639Y+006929X0200Y         S0      
327RST_MB_STBY_N    R1546 -2   M      A18X+056733Y+006659X0198Y0197R090 S2      
317RST_MB_STBY_N    VIA   -    MD0100PA00X+065404Y+009324X0200Y         S0      
327RST_MB_STBY_N    U18   -D13        A01X+070678Y+045769X0160Y    R090 S1      
317RST_MB_STBY_N    VIA   -    MD0100PA00X+070524Y+045922X0180Y    R090 S0      
317FW_RECOVERY_R    VIA   -    M      A01X+122780Y+009421X0200Y    R270 S2      
017FW_RECOVERY_R    VIA   -    M      A18X+122780Y+009421X0260Y    R270 S2      
017FW_RECOVERY_R          -    MD0100PA00X+122780Y+009421                       
327FW_RECOVERY_R    U99   -2          A01X+123691Y+009421X0220Y0530R270 S1      
327FW_RECOVERY_R    R1342 -1   M      A01X+123031Y+009421X0198Y0197R270 S1      
317FW_RECOVERY_R    VIA   -    MD0100PA00X+057648Y+005856X0200Y         S0      
327FW_RECOVERY_R    R4087 -1          A18X+057620Y+005580X0198Y0197R090 S2      
317m8733            VIA   -    MD0100PA00X+043166Y+162434X0200Y         S0      
317m8733            J112  -A3   D0142PA00X+024665Y+173421X0302Y    R180 S3      
327m8733            VIA   -    M      A18X+042372Y+162573X0260Y         S2      
327m8733            Q148  -3   M      A18X+042744Y+163026X0170Y0200R180 S2      
327m8733            R4546 -2          A18X+041164Y+162375X0198Y0197R090 S2      
327m8733            C6    -1   M      A18X+042083Y+162373X0198Y0197R090 S2      
327m8733            R2656 -1   M      A18X+041612Y+162376X0198Y0197R090 S2      
317HGX_DETECT_N     VIA   -    MD0100PA00X+039452Y+157589X0200Y         S0      
327HGX_DETECT_N     Q148  -2          A18X+043000Y+163026X0170Y0200R180 S2      
327HGX_DETECT_N     R4543 -2   M      A18X+041200Y+163592X0198Y0197R090 S2      
327HGX_DETECT_N     R4544 -1   M      A18X+040800Y+163592X0198Y0197R270 S2      
317HGX_DETECT_N     VIA   -    M      A01X+040464Y+163742X0200Y         S2      
017HGX_DETECT_N     VIA   -    M      A18X+040464Y+163742X0260Y         S2      
017HGX_DETECT_N           -    MD0100PA00X+040464Y+163742                       
317HGX_DETECT_N     VIA   -    MD0100PA00X+013554Y+163706X0200Y         S0      
317HGX_DETECT_N     VIA   -    MD0100PA00X+081449Y+055808X0200Y         S0      
327HGX_DETECT_N     R4556 -2          A01X+080929Y+044980X0198Y0197     S1      
317HGX_DETECT_N     VIA   -    MD0100PA00X+081290Y+044980X0200Y    R180 S0      
327HGX_DETECT       Q148  -5          A18X+043000Y+163774X0170Y0200R180 S2      
327HGX_DETECT       R4545 -2          A18X+044008Y+164150X0198Y0197R180 S2      
327HGX_DETECT       VIA   -    M      A18X+043791Y+163809X0260Y         S2      
327HGX_DETECT       Q148  -6   M      A18X+043256Y+163774X0170Y0200R180 S2      
327m8734            J54   -9          A01X+156420Y+022925X0340Y0960R090 S1      
327m8734            R1620 -2          A01X+158773Y+022525X0198Y0197R180 S1      
327m8734            R1621 -2   M      A01X+158773Y+022925X0198Y0197R180 S1      
327m8734            VIA   -    M      A01X+158293Y+022925X0300Y    R270 S1      
317HDT_HDR_TRST_N   VIA   -    M      A01X+108671Y+035352X0200Y         S2      
017HDT_HDR_TRST_N   VIA   -    M      A18X+108671Y+035352X0260Y         S2      
017HDT_HDR_TRST_N         -    MD0100PA00X+108671Y+035352                       
317HDT_HDR_TRST_N   VIA   -    MD0100PA00X+159830Y+023425X0200Y    R090 S0      
327HDT_HDR_TRST_N   C85   -1   M      A01X+159588Y+022525X0198Y0197     S1      
327HDT_HDR_TRST_N   R1620 -1          A01X+159088Y+022525X0198Y0197R180 S1      
327HDT_HDR_TRST_N   U149  -5          A01X+106209Y+038624X0140Y0630R090 S1      
327HDT_HDR_TMS      R1353 -2          A01X+151894Y+021325X0198Y0197R180 S1      
327HDT_HDR_TMS      R1626 -2   M      A01X+151364Y+021325X0198Y0197R270 S1      
317HDT_HDR_TMS      VIA   -    MD0100PA00X+105461Y+026159X0200Y         S0      
327HDT_HDR_TMS      U149  -4          A01X+106209Y+038368X0140Y0630R090 S1      
317HDT_HDR_TMS      VIA   -    M      A01X+105593Y+038199X0200Y         S2      
017HDT_HDR_TMS      VIA   -    M      A18X+105593Y+038199X0260Y         S2      
017HDT_HDR_TMS            -    MD0100PA00X+105593Y+038199                       
327HDT_HDR_TDO      J54   -8          A01X+154562Y+022425X0340Y0960R090 S1      
327HDT_HDR_TDO      R1628 -2   M      A01X+151894Y+023125X0198Y0197R180 S1      
317HDT_HDR_TDO      VIA   -    MD0100PA00X+104945Y+026675X0200Y         S0      
327HDT_HDR_TDO      R6108 -1          A01X+047544Y+020656X0198Y0197R090 S1      
317HDT_HDR_TDO      VIA   -    M      A01X+047987Y+027040X0200Y         S2      
017HDT_HDR_TDO      VIA   -    M      A18X+047987Y+027040X0260Y         S2      
017HDT_HDR_TDO            -    MD0100PA00X+047987Y+027040                       
327HDT_HDR_TDI      U146  -8          A01X+048121Y+021723X0070Y0320R090 S1      
317HDT_HDR_TDI      VIA   -    M      A01X+048762Y+027040X0200Y         S2      
017HDT_HDR_TDI      VIA   -    M      A18X+048762Y+027040X0260Y         S2      
017HDT_HDR_TDI            -    MD0100PA00X+048762Y+027040                       
327HDT_HDR_TDI      C605  -1   M      A01X+151364Y+022525X0198Y0197R270 S1      
327HDT_HDR_TDI      R1354 -2          A01X+151894Y+022125X0198Y0197R180 S1      
327HDT_HDR_TDI      R1627 -2   M      A01X+151894Y+022525X0198Y0197R180 S1      
317HDT_HDR_TDI      VIA   -    MD0100PA00X+104638Y+026981X0200Y         S0      
327HDT_HDR_TCK      R1624 -2          A01X+106851Y+036979X0198Y0197R180 S1      
327HDT_HDR_TCK      C604  -1   M      A01X+152374Y+020125X0198Y0197     S1      
327HDT_HDR_TCK      R1352 -2          A01X+151894Y+020925X0198Y0197R180 S1      
327HDT_HDR_TCK      U149  -3          A01X+106209Y+038112X0140Y0630R090 S1      
317HDT_HDR_TCK      VIA   -    M      A01X+106814Y+038019X0200Y         S2      
017HDT_HDR_TCK      VIA   -    M      A18X+106814Y+038019X0260Y         S2      
017HDT_HDR_TCK            -    MD0100PA00X+106814Y+038019                       
317HDT_HDR_TCK      VIA   -    MD0100PA00X+105694Y+025918X0200Y         S0      
327HDT_HDR_R_TMS    R1353 -1          A01X+152209Y+021325X0198Y0197R180 S1      
327HDT_HDR_R_TMS    J54   -4          A01X+154562Y+021425X0340Y0960R090 S1      
327HDT_HDR_R_TMS    VIA   -    M      A01X+152689Y+021425X0300Y    R090 S1      
327HDT_HDR_R_TDI    R1354 -1          A01X+152209Y+022125X0198Y0197R180 S1      
327HDT_HDR_R_TDI    J54   -6          A01X+154562Y+021925X0340Y0960R090 S1      
327HDT_HDR_R_TDI    VIA   -    M      A01X+152689Y+022125X0300Y    R090 S1      
327HDT_HDR_R_TCK    R1352 -1          A01X+152209Y+020925X0198Y0197R180 S1      
327HDT_HDR_R_TCK    J54   -2          A01X+154562Y+020925X0340Y0960R090 S1      
327HDT_HDR_R_TCK    VIA   -    M      A01X+152689Y+020925X0300Y    R090 S1      
327m8735            R856  -2          A01X+074450Y+052744X0198Y0197R090 S1      
317m8735            VIA   -    MD0100PA00X+074492Y+053027X0200Y         S0      
327m8735            J54   -12         A01X+154562Y+023425X0340Y0960R090 S1      
317m8735            VIA   -    M      A01X+106072Y+051606X0300Y    R270 S1      
017m8735            VIA   -    M      A18X+106072Y+051606X0200Y    R270 S1      
017m8735                  -    MD0100PA00X+106072Y+051606                       
327HDT_HDR_PWROK    R708  -2          A01X+074850Y+052744X0198Y0197R090 S1      
317HDT_HDR_PWROK    VIA   -    MD0100PA00X+074814Y+053027X0200Y         S0      
327HDT_HDR_PWROK    J54   -10         A01X+154562Y+022925X0340Y0960R090 S1      
317HDT_HDR_PWROK    VIA   -    M      A01X+106072Y+051236X0200Y    R270 S2      
017HDT_HDR_PWROK    VIA   -    M      A18X+106072Y+051236X0260Y    R270 S2      
017HDT_HDR_PWROK          -    MD0100PA00X+106072Y+051236                       
327m8736            R1630 -2          A01X+151894Y+023802X0198Y0197R180 S1      
327m8736            J54   -16         A01X+154562Y+024425X0340Y0960R090 S1      
327m8736            VIA   -    M      A01X+152689Y+024425X0300Y    R090 S1      
327m8736            R1631 -1   M      A01X+152209Y+024425X0198Y0197R180 S1      
327m8737            U149  -6          A01X+106209Y+038880X0140Y0630R090 S1      
317m8737            VIA   -    M      A01X+105593Y+038899X0200Y         S2      
017m8737            VIA   -    M      A18X+105593Y+038899X0260Y         S2      
017m8737                  -    MD0100PA00X+105593Y+038899                       
327m8737            C87   -1   M      A01X+151364Y+024635X0198Y0197R090 S1      
327m8737            R1631 -2          A01X+151894Y+024425X0198Y0197R180 S1      
317m8737            VIA   -    MD0100PA00X+106270Y+027088X0200Y         S0      
327m8738            J54   -13         A01X+156420Y+023925X0340Y0960R090 S1      
327m8738            R477  -2          A01X+158773Y+023925X0198Y0197R180 S1      
327m8738            VIA   -    M      A01X+158293Y+023925X0300Y    R270 S1      
327m8739            J54   -11         A01X+156420Y+023425X0340Y0960R090 S1      
327m8739            R476  -2          A01X+158773Y+023425X0198Y0197R180 S1      
327m8739            VIA   -    M      A01X+158293Y+023425X0300Y    R270 S1      
327m8740            J54   -15         A01X+156420Y+024425X0340Y0960R090 S1      
327m8740            R478  -2          A01X+158773Y+024425X0198Y0197R180 S1      
327m8740            VIA   -    M      A01X+158293Y+024425X0300Y    R270 S1      
327m8741            R1632 -1          A01X+152209Y+025325X0198Y0197R180 S1      
327m8741            R1629 -1   M      A01X+152209Y+024925X0198Y0197R180 S1      
327m8741            J54   -18         A01X+154562Y+024925X0340Y0960R090 S1      
327m8741            VIA   -    M      A01X+152689Y+024925X0300Y    R090 S1      
327m8742            R5377 -1          A01X+058305Y+041185X0198Y0197     S1      
327m8742            R3298 -2   M      A01X+058305Y+041585X0198Y0197R180 S1      
327m8742            VIA   -    M      A01X+057825Y+041585X0300Y    R180 S1      
327m8742            Q95   -6          A01X+057339Y+041585X0170Y0200R090 S1      
327m8743            U259  -6          A01X+057378Y+040372X0140Y0440R270 S1      
327m8743            R3296 -2          A01X+055625Y+041427X0198Y0197     S1      
327m8743            VIA   -    M      A01X+056105Y+041277X0300Y         S1      
327m8743            Q95   -2   M      A01X+056591Y+041329X0170Y0200R090 S1      
327m8744            R3485 -2          A18X+078093Y+048334X0198Y0197R180 S2      
317m8744            VIA   -    MD0100PA00X+078088Y+048334X0200Y    R180 S0      
317m8744            VIA   -    MD0100PA00X+083856Y+048407X0200Y         S0      
327m8744            Q106  -2          A01X+173714Y+171082X0170Y0200R090 S1      
327m8744            R3470 -2   M      A01X+172863Y+171212X0198Y0197R270 S1      
317m8744            VIA   -    M      A01X+172117Y+171212X0200Y         S2      
017m8744            VIA   -    M      A18X+172117Y+171212X0260Y         S2      
017m8744                  -    MD0100PA00X+172117Y+171212                       
327m8744            R3471 -1   M      A01X+172463Y+171212X0198Y0197R090 S1      
327m8745            R9043 -2          A01X+175038Y+171338X0198Y0197R090 S1      
317m8745            VIA   -    M      A01X+174462Y+171602X0200Y         S2      
017m8745            VIA   -    M      A18X+174462Y+171602X0260Y         S2      
017m8745                  -    MD0100PA00X+174462Y+171602                       
327m8745            Q106  -5          A01X+174462Y+171082X0170Y0200R090 S1      
327m8745            Q106  -6   M      A01X+174462Y+171338X0170Y0200R090 S1      
317m8746            VIA   -    MD0100PA00X+015507Y+154360X0200Y         S0      
327m8746            C1978 -1   M      A18X+020381Y+168687X0198Y0197R090 S2      
327m8746            R3475 -2          A18X+020781Y+168687X0198Y0197R270 S2      
327m8746            Q107  -3          A18X+019530Y+168687X0170Y0200R270 S2      
317m8746            VIA   -    MD0100PA00X+020042Y+168687X0200Y         S0      
317m8746            VIA   -    M      A01X+171918Y+170671X0200Y         S2      
017m8746            VIA   -    M      A18X+171918Y+170671X0260Y         S2      
017m8746                  -    MD0100PA00X+171918Y+170671                       
317m8746            VIA   -    MD0100PA00X+091351Y+048674X0200Y         S0      
317m8746            VIA   -    MD0100PA00X+065107Y+046594X0200Y         S0      
327m8746            R3486 -2          A01X+064307Y+046986X0198Y0197R180 S1      
317m8746            VIA   -    MD0100PA00X+066172Y+057993X0200Y         S0      
317m8746            VIA   -    MD0100PA00X+066172Y+049806X0200Y         S0      
317m8746            VIA   -    MD0100PA00X+092375Y+058494X0200Y         S0      
317m8746            VIA   -    MD0100PA00X+075716Y+169642X0200Y         S0      
317m8746            VIA   -    MD0100PA00X+073065Y+162363X0200Y         S0      
327m8746            R9001 -1          A01X+073272Y+162694X0198Y0197R090 S1      
317m8746            VIA   -    MD0100PA00X+066813Y+162583X0200Y         S0      
317GPU_PRSNT_N      J111  -N2   D0142PA00X+030571Y+167201X0302Y    R180 S3      
317GPU_PRSNT_N      VIA   -    M      A01X+020045Y+169077X0200Y         S2      
017GPU_PRSNT_N      VIA   -    M      A18X+020045Y+169077X0260Y         S2      
017GPU_PRSNT_N            -    MD0100PA00X+020045Y+169077                       
327GPU_PRSNT_N      Q107  -2          A18X+019530Y+168943X0170Y0200R270 S2      
327GPU_PRSNT_N      R3473 -1   M      A18X+020381Y+169072X0198Y0197R270 S2      
327GPU_PRSNT_N      R3487 -2          A18X+020781Y+169072X0198Y0197R090 S2      
317GPU_PRSNT_N      VIA   -    MD0100PA00X+038171Y+159384X0200Y         S0      
327GPU_PRSNT        R3770 -1          A01X+076177Y+162821X0198Y0197R090 S1      
317GPU_PRSNT        VIA   -    MD0100PA00X+075972Y+162616X0200Y         S0      
317GPU_PRSNT        VIA   -    M      A01X+018508Y+169199X0300Y         S1      
017GPU_PRSNT        VIA   -    M      A18X+018508Y+169199X0200Y         S1      
017GPU_PRSNT              -    MD0100PA00X+018508Y+169199                       
327GPU_PRSNT        Q107  -5          A18X+018782Y+168943X0170Y0200R270 S2      
327GPU_PRSNT        Q107  -6   M      A18X+018782Y+169199X0170Y0200R270 S2      
327GPU_PRSNT        R3474 -2          A18X+018252Y+169199X0198Y0197R090 S2      
317GPU_PRSNT        VIA   -    MD0100PA00X+040300Y+158246X0200Y         S0      
317GPU_PRSNT        VIA   -    MD0100PA00X+065097Y+161893X0200Y         S0      
317GPU_PEX_STRAP1   VIA   -    M      A01X+040316Y+157936X0200Y         S2      
017GPU_PEX_STRAP1   VIA   -    M      A18X+040316Y+157936X0260Y         S2      
017GPU_PEX_STRAP1         -    MD0100PA00X+040316Y+157936                       
317GPU_PEX_STRAP1   J111  -A1   D0142PA00X+029784Y+173421X0302Y0302R180 S3      
327GPU_PEX_STRAP1   R3443 -1          A01X+072845Y+168493X0198Y0197R090 S1      
317GPU_PEX_STRAP1   VIA   -    MD0100PA00X+072564Y+168289X0200Y         S0      
327GPU_PEX_STRAP1   R3517 -1          A01X+072563Y+168034X0198Y0197R270 S1      
317GPU_PEX_STRAP1   VIA   -    MD0100PA00X+066116Y+162653X0200Y         S0      
317GPU_PEX_STRAP1   VIA   -    MD0100PA00X+036549Y+165511X0200Y         S0      
317GPU_PEX_STRAP0   VIA   -    M      A01X+040384Y+166577X0200Y         S2      
017GPU_PEX_STRAP0   VIA   -    M      A18X+040384Y+166577X0260Y         S2      
017GPU_PEX_STRAP0         -    MD0100PA00X+040384Y+166577                       
327GPU_PEX_STRAP0   R3442 -1          A01X+073243Y+168510X0198Y0197R090 S1      
317GPU_PEX_STRAP0   J111  -A5   D0142PA00X+032933Y+173421X0302Y    R180 S3      
317GPU_PEX_STRAP0   VIA   -    MD0100PA00X+073035Y+168290X0200Y         S0      
327GPU_PEX_STRAP0   R3518 -1          A01X+072962Y+168034X0198Y0197R270 S1      
327m8747            VIA   -    M      A01X+041700Y+166100X0300Y    R090 S1      
327m8747            U255  -6          A01X+041156Y+166226X0170Y0240R180 S1      
327m8747            R3397 -1          A01X+041708Y+164950X0198Y0197R180 S1      
327m8747            R3461 -2   M      A01X+041708Y+165750X0198Y0197     S1      
327m8747            R3462 -1   M      A01X+041708Y+165350X0198Y0197R180 S1      
317m8748            J112  -T4   D0142PA00X+025453Y+164366X0302Y    R180 S3      
317m8748            VIA   -    M      A01X+041200Y+164718X0200Y         S2      
017m8748            VIA   -    M      A18X+041200Y+164718X0260Y         S2      
017m8748                  -    MD0100PA00X+041200Y+164718                       
327m8748            R3397 -2          A01X+041392Y+164950X0198Y0197R180 S1      
317m8749            VIA   -    MD0100PA00X+066661Y+157158X0200Y         S0      
317m8749            VIA   -    M      A01X+077539Y+039086X0200Y         S2      
017m8749            VIA   -    M      A18X+077539Y+039086X0260Y         S2      
017m8749                  -    MD0100PA00X+077539Y+039086                       
327m8749            R3477 -1          A01X+077550Y+039329X0198Y0197R090 S1      
317m8749            VIA   -    MD0100PA00X+087083Y+042342X0200Y         S0      
317m8749            VIA   -    MD0100PA00X+083739Y+065982X0200Y         S0      
317m8749            VIA   -    MD0100PA00X+086547Y+078808X0200Y         S0      
317m8749            VIA   -    MD0100PA00X+067107Y+165082X0200Y         S0      
327m8749            R3460 -1   M      A01X+041700Y+167742X0198Y0197R090 S1      
327m8749            R3459 -2   M      A01X+041300Y+167742X0198Y0197R270 S1      
317m8749            VIA   -    MD0100PA00X+041700Y+167500X0200Y         S0      
327m8749            U255  -1          A01X+041156Y+166974X0170Y0240R180 S1      
327m8750            Q103  -2          A01X+047300Y+165074X0170Y0200     S1      
317m8750            VIA   -    M      A01X+047350Y+166250X0200Y         S2      
017m8750            VIA   -    M      A18X+047350Y+166250X0260Y         S2      
017m8750                  -    MD0100PA00X+047350Y+166250                       
317m8750            J110  -A3   D0142PA00X+051083Y+173421X0302Y    R180 S3      
327m8750            R3465 -2   M      A01X+047242Y+165950X0198Y0197R180 S1      
327m8750            R3431 -1   M      A01X+047242Y+165550X0198Y0197     S1      
317m8751            VIA   -    MD0100PA00X+086547Y+079808X0200Y         S0      
317m8751            VIA   -    MD0100PA00X+081790Y+064901X0200Y         S0      
317m8751            VIA   -    MD0100PA00X+082875Y+046358X0200Y         S0      
327m8751            R3481 -2          A01X+082393Y+046358X0198Y0197     S1      
327m8751            C1975 -1   M      A01X+046808Y+165550X0198Y0197R180 S1      
327m8751            R3436 -2   M      A01X+046808Y+165950X0198Y0197     S1      
317m8751            VIA   -    M      A01X+046808Y+166250X0200Y         S2      
017m8751            VIA   -    M      A18X+046808Y+166250X0260Y         S2      
017m8751                  -    MD0100PA00X+046808Y+166250                       
327m8751            Q103  -3          A01X+047044Y+165074X0170Y0200     S1      
317m8751            VIA   -    MD0100PA00X+070053Y+166147X0200Y         S0      
327GPU_HMC_PRSNT    VIA   -           A01X+046500Y+164400X0300Y         S1      
327GPU_HMC_PRSNT    R3434 -2   M      A01X+046500Y+164742X0198Y0197R270 S1      
327GPU_HMC_PRSNT    Q103  -6          A01X+047556Y+164326X0170Y0200     S1      
327GPU_HMC_PRSNT    Q103  -5          A01X+047300Y+164326X0170Y0200     S1      
317m8752            J112  -T6   D0142PA00X+027028Y+164366X0302Y    R180 S3      
327m8752            Q101  -2          A18X+019530Y+170455X0170Y0200R270 S2      
317m8752            VIA   -    M      A01X+020048Y+170176X0200Y         S2      
017m8752            VIA   -    M      A18X+020048Y+170176X0260Y         S2      
017m8752                  -    MD0100PA00X+020048Y+170176                       
327m8752            R3498 -2   M      A18X+020381Y+170584X0198Y0197R090 S2      
327m8752            R3428 -1   M      A18X+020781Y+170584X0198Y0197R270 S2      
317m8753            VIA   -    MD0100PA00X+078076Y+047934X0200Y    R180 S0      
327m8753            R3476 -2          A18X+077823Y+047934X0198Y0197R180 S2      
317m8753            VIA   -    MD0100PA00X+078592Y+055966X0200Y         S0      
327m8753            C1974 -1   M      A18X+020381Y+170199X0198Y0197R090 S2      
327m8753            Q101  -3          A18X+019530Y+170199X0170Y0200R270 S2      
327m8753            R3439 -2          A18X+020781Y+170199X0198Y0197R270 S2      
317m8753            VIA   -    M      A01X+019778Y+169697X0200Y         S2      
017m8753            VIA   -    M      A18X+019778Y+169697X0260Y         S2      
017m8753                  -    MD0100PA00X+019778Y+169697                       
317m8754            VIA   -    M      A01X+018512Y+170185X0300Y         S1      
017m8754            VIA   -    M      A18X+018512Y+170185X0200Y         S1      
017m8754                  -    MD0100PA00X+018512Y+170185                       
327m8754            R3432 -2          A18X+018252Y+170231X0198Y0197R270 S2      
327m8754            Q101  -6          A18X+018782Y+170711X0170Y0200R270 S2      
327m8754            Q101  -5   M      A18X+018782Y+170455X0170Y0200R270 S2      
317m8755            VIA   -    MD0100PA00X+082898Y+044980X0200Y         S0      
317m8755            VIA   -    MD0100PA00X+082437Y+055244X0200Y         S0      
327m8755            R4608 -1          A01X+082399Y+044980X0198Y0197R180 S1      
327m8755            R3507 -1          A01X+017508Y+171100X0198Y0197R180 S1      
327m8755            R3506 -2   M      A01X+017508Y+171500X0198Y0197     S1      
327m8755            U196  -3          A01X+018176Y+171544X0160Y0200R270 S1      
317m8755            VIA   -    M      A01X+017838Y+171544X0200Y         S2      
017m8755            VIA   -    M      A18X+017838Y+171544X0260Y         S2      
017m8755                  -    MD0100PA00X+017838Y+171544                       
317m8756            VIA   -    M      A01X+039300Y+159230X0200Y         S2      
017m8756            VIA   -    M      A18X+039300Y+159230X0260Y         S2      
017m8756                  -    MD0100PA00X+039300Y+159230                       
317m8756            J111  -A7   D0142PA00X+034508Y+173421X0302Y    R180 S3      
327m8756            R3315 -2          A01X+018976Y+170731X0198Y0197R270 S1      
317m8756            VIA   -    MD0100PA00X+019327Y+170977X0200Y         S0      
317m8757            VIA   -    M      A01X+018976Y+171306X0200Y         S2      
017m8757            VIA   -    M      A18X+018976Y+171306X0260Y         S2      
017m8757                  -    MD0100PA00X+018976Y+171306                       
327m8757            U196  -4          A01X+018924Y+171544X0160Y0200R270 S1      
327m8757            R3315 -1   M      A01X+018976Y+171046X0198Y0197R270 S1      
327m8757            R3317 -2   M      A01X+018576Y+171046X0198Y0197R090 S1      
327m8757            R3509 -1          A01X+018176Y+171046X0198Y0197R270 S1      
327m8758            R3320 -2   M      A18X+018281Y+166192X0198Y0197R090 S2      
317m8758            VIA   -    M      A01X+014934Y+170560X0200Y         S2      
017m8758            VIA   -    M      A18X+014934Y+170560X0260Y         S2      
017m8758                  -    MD0100PA00X+014934Y+170560                       
317m8758            VIA   -    MD0100PA00X+014698Y+052200X0200Y    R090 S0      
327m8758            R3326 -1          A01X+014457Y+052200X0198Y0197R180 S1      
327m8758            Q96   -5          A18X+018767Y+165929X0170Y0200R270 S2      
327m8758            Q96   -6   M      A18X+018767Y+166185X0170Y0200R270 S2      
317m8759            VIA   -    MD0100PA00X+020679Y+166096X0200Y         S0      
317m8759            VIA   -    M      A01X+013739Y+162641X0200Y         S2      
017m8759            VIA   -    M      A18X+013739Y+162641X0260Y         S2      
017m8759                  -    MD0100PA00X+013739Y+162641                       
317m8759            VIA   -    MD0100PA00X+081300Y+048486X0200Y         S0      
317m8759            VIA   -    MD0100PA00X+028402Y+052230X0200Y    R090 S0      
327m8759            R3324 -2          A01X+079324Y+048346X0198Y0197     S1      
327m8759            C1881 -1   M      A18X+020400Y+165817X0198Y0197     S2      
327m8759            Q96   -3          A18X+019515Y+165674X0170Y0200R270 S2      
327m8759            R3321 -2   M      A18X+020768Y+165819X0198Y0197     S2      
317GPU_FPGA_READY   VIA   -    M      A01X+019870Y+166222X0300Y         S1      
017GPU_FPGA_READY   VIA   -    M      A18X+019870Y+166222X0200Y         S1      
017GPU_FPGA_READY         -    MD0100PA00X+019870Y+166222                       
317GPU_FPGA_READY   J112  -T2   D0142PA00X+023878Y+164366X0302Y    R180 S3      
327GPU_FPGA_READY   Q96   -2          A18X+019515Y+165929X0170Y0200R270 S2      
327GPU_FPGA_READY   R3511 -1   M      A18X+020366Y+166448X0198Y0197     S2      
327GPU_FPGA_READY   R3318 -2          A18X+020746Y+166448X0198Y0197     S2      
317m8760            J108  -A7   D0142PA00X+128602Y+173421X0302Y    R180 S3      
317m8760            VIA   -    M      A01X+121974Y+170886X0200Y         S2      
017m8760            VIA   -    M      A18X+121974Y+170886X0260Y         S2      
017m8760                  -    MD0100PA00X+121974Y+170886                       
327m8760            R3464 -2   M      A01X+121025Y+171001X0198Y0197R090 S1      
327m8760            R3430 -1   M      A01X+121425Y+171001X0198Y0197R270 S1      
327m8760            Q104  -2          A01X+120175Y+170970X0170Y0200R270 S1      
327m8761            R3437 -2   M      A01X+121425Y+171386X0198Y0197R270 S1      
327m8761            C1976 -1   M      A01X+121025Y+171386X0198Y0197R090 S1      
327m8761            Q104  -3          A01X+120175Y+171226X0170Y0200R270 S1      
317m8761            VIA   -    M      A01X+121974Y+171386X0200Y         S2      
017m8761            VIA   -    M      A18X+121974Y+171386X0260Y         S2      
017m8761                  -    MD0100PA00X+121974Y+171386                       
317m8761            VIA   -    MD0100PA00X+115372Y+146270X0200Y         S0      
317m8761            VIA   -    MD0100PA00X+159572Y+143186X0200Y         S0      
327m8761            R3484 -2          A18X+079273Y+048334X0198Y0197R180 S2      
317m8761            VIA   -    MD0100PA00X+079733Y+048334X0200Y    R180 S0      
327GPU_FPGA_OVERT   R3435 -2          A01X+118941Y+171194X0198Y0197R270 S1      
327GPU_FPGA_OVERT   VIA   -    M      A01X+118941Y+170714X0300Y    R090 S1      
327GPU_FPGA_OVERT   Q104  -5          A01X+119427Y+170970X0170Y0200R270 S1      
327GPU_FPGA_OVERT   Q104  -6   M      A01X+119427Y+170714X0170Y0200R270 S1      
317m8762            VIA   -    MD0100PA00X+067835Y+156740X0200Y         S0      
327m8762            R3478 -1          A01X+079273Y+043534X0198Y0197R180 S1      
317m8762            VIA   -    MD0100PA00X+086547Y+078558X0200Y         S0      
317m8762            VIA   -    M      A01X+080515Y+062384X0200Y         S2      
017m8762            VIA   -    M      A18X+080515Y+062384X0260Y         S2      
017m8762                  -    MD0100PA00X+080515Y+062384                       
317m8762            VIA   -    MD0100PA00X+079633Y+043534X0200Y    R180 S0      
327m8762            R3488 -2   M      A01X+040900Y+167742X0198Y0197R270 S1      
327m8762            R3489 -1   M      A01X+040500Y+167742X0198Y0197R090 S1      
317m8762            VIA   -    MD0100PA00X+040500Y+167500X0200Y         S0      
327m8762            U255  -3          A01X+040644Y+166974X0170Y0240R180 S1      
317m8762            VIA   -    MD0100PA00X+067080Y+165461X0200Y         S0      
327m8763            VIA   -    M      A01X+040644Y+165700X0300Y    R090 S1      
327m8763            U255  -4          A01X+040644Y+166226X0170Y0240R180 S1      
327m8763            R3493 -1   M      A01X+040592Y+165350X0198Y0197     S1      
327m8763            R3492 -2   M      A01X+040592Y+164950X0198Y0197R180 S1      
327m8763            R3496 -1          A01X+040592Y+164550X0198Y0197     S1      
327m8764            R3496 -2          A01X+040908Y+164550X0198Y0197     S1      
317m8764            VIA   -    M      A01X+042350Y+165250X0200Y         S2      
017m8764            VIA   -    M      A18X+042350Y+165250X0260Y         S2      
017m8764                  -    MD0100PA00X+042350Y+165250                       
317m8764            J110  -N8   D0142PA00X+055020Y+167201X0302Y    R180 S3      
317m8765            VIA   -    MD0100PA00X+067281Y+157156X0200Y         S0      
327m8765            R3483 -1          A01X+080958Y+043563X0198Y0197R180 S1      
317m8765            VIA   -    MD0100PA00X+081321Y+043534X0200Y         S0      
317m8765            VIA   -    MD0100PA00X+082062Y+064127X0200Y         S0      
317m8765            VIA   -    MD0100PA00X+086547Y+079058X0200Y         S0      
327m8765            R3491 -1   M      A01X+046858Y+173350X0198Y0197R180 S1      
317m8765            VIA   -    M      A01X+046858Y+173100X0200Y         S2      
017m8765            VIA   -    M      A18X+046858Y+173100X0260Y         S2      
017m8765                  -    MD0100PA00X+046858Y+173100                       
327m8765            R3490 -2   M      A01X+047242Y+173350X0198Y0197R180 S1      
327m8765            U257  -1          A01X+047253Y+172753X0170Y0240R180 S1      
317m8765            VIA   -    MD0100PA00X+068575Y+166930X0200Y         S0      
327m8766            VIA   -           A01X+046500Y+170550X0300Y    R090 S1      
327m8766            R3497 -1   M      A01X+047242Y+170650X0198Y0197     S1      
327m8766            R3494 -2   M      A01X+047242Y+171050X0198Y0197R180 S1      
327m8766            U257  -6          A01X+047253Y+172005X0170Y0240R180 S1      
327m8766            R3495 -1   M      A01X+047242Y+171450X0198Y0197     S1      
327m8767            VIA   -    M      A01X+047900Y+170650X0300Y         S1      
327m8767            R3497 -2          A01X+047558Y+170650X0198Y0197     S1      
317m8767            J110  -A1   D0142PA00X+049508Y+173421X0302Y0302R180 S3      
327m8768            VIA   -    M      A18X+054400Y+165450X0260Y         S2      
317m8768            J109  -N2   D0142PA00X+056988Y+167201X0302Y    R180 S3      
327m8768            R3502 -1   M      A18X+046100Y+164392X0198Y0197R270 S2      
327m8768            Q108  -2          A18X+045224Y+164400X0170Y0200R270 S2      
327m8768            R3525 -2   M      A18X+045700Y+164392X0198Y0197R090 S2      
317m8769            VIA   -    M      A01X+044618Y+162556X0200Y         S2      
017m8769            VIA   -    M      A18X+044618Y+162556X0260Y         S2      
017m8769                  -    MD0100PA00X+044618Y+162556                       
317m8769            VIA   -    MD0100PA00X+013980Y+155613X0200Y         S0      
317m8769            VIA   -    MD0100PA00X+015562Y+154933X0200Y         S0      
327m8769            R3504 -2   M      A18X+046119Y+163902X0198Y0197R270 S2      
327m8769            C1988 -1   M      A18X+045715Y+163902X0198Y0197R090 S2      
327m8769            Q108  -3          A18X+045224Y+164144X0170Y0200R270 S2      
327m8769            R3505 -2          A01X+082393Y+046757X0198Y0197     S1      
317m8769            VIA   -    MD0100PA00X+082875Y+046757X0200Y         S0      
317m8769            VIA   -    MD0100PA00X+082062Y+055085X0200Y         S0      
327m8770            VIA   -    M      A18X+044008Y+165007X0260Y         S2      
327m8770            Q108  -5          A18X+044476Y+164400X0170Y0200R270 S2      
327m8770            R3503 -2          A18X+044008Y+164650X0198Y0197R180 S2      
327m8770            Q108  -6   M      A18X+044476Y+164656X0170Y0200R270 S2      
327m8771            VIA   -    M      A01X+047786Y+168274X0300Y    R090 S1      
327m8771            U253  -6          A01X+047287Y+168474X0160Y0200R180 S1      
327m8771            R3390 -1          A01X+047558Y+166800X0198Y0197R180 S1      
327m8771            R3454 -1   M      A01X+047558Y+167600X0198Y0197R180 S1      
327m8771            R3453 -2   M      A01X+047558Y+167200X0198Y0197     S1      
317m8772            VIA   -    M      A01X+047950Y+166650X0200Y         S2      
017m8772            VIA   -    M      A18X+047950Y+166650X0260Y         S2      
017m8772                  -    MD0100PA00X+047950Y+166650                       
327m8772            R3390 -2          A01X+047242Y+166800X0198Y0197R180 S1      
317m8772            J110  -N2   D0142PA00X+050295Y+167201X0302Y    R180 S3      
317m8773            VIA   -    MD0100PA00X+068408Y+157650X0200Y         S0      
317m8773            VIA   -    MD0100PA00X+086547Y+079558X0200Y         S0      
317m8773            VIA   -    MD0100PA00X+078759Y+063178X0200Y         S0      
317m8773            VIA   -    MD0100PA00X+076450Y+052986X0200Y         S0      
327m8773            R3482 -2          A01X+076450Y+052744X0198Y0197R090 S1      
327m8773            R3449 -1   M      A01X+047242Y+170100X0198Y0197     S1      
327m8773            R3448 -2   M      A01X+047242Y+169700X0198Y0197R180 S1      
317m8773            VIA   -    M      A01X+047400Y+170400X0200Y         S2      
017m8773            VIA   -    M      A18X+047400Y+170400X0260Y         S2      
017m8773                  -    MD0100PA00X+047400Y+170400                       
327m8773            U253  -1          A01X+047287Y+169222X0160Y0200R180 S1      
317m8773            VIA   -    MD0100PA00X+068564Y+167531X0200Y         S0      
327m8774            R4155 -2          A01X+140474Y+164697X0198Y0197R180 S1      
327m8774            VIA   -    M      A01X+139994Y+164697X0300Y         S1      
327m8774            Q134  -5          A01X+140250Y+164211X0170Y0200R180 S1      
327m8774            Q134  -6   M      A01X+139994Y+164211X0170Y0200R180 S1      
317m8775            VIA   -    M      A01X+140003Y+161580X0200Y         S2      
017m8775            VIA   -    M      A18X+140003Y+161580X0260Y         S2      
017m8775                  -    MD0100PA00X+140003Y+161580                       
327m8775            Q134  -2          A01X+140250Y+163463X0170Y0200R180 S1      
327m8775            R4574 -1   M      A01X+140191Y+163017X0198Y0197     S1      
327m8775            R4154 -1   M      A01X+140121Y+162217X0198Y0197R180 S1      
327m8775            R4153 -2   M      A01X+140121Y+162617X0198Y0197     S1      
317m8775            J106  -A7   D0142PA00X+155020Y+173421X0302Y    R180 S3      
317m8775            VIA   -    MD0100PA00X+145355Y+168689X0200Y         S0      
327m8776            VIA   -    M      A01X+046450Y+167977X0300Y         S1      
327m8776            U253  -4          A01X+046775Y+168474X0160Y0200R180 S1      
327m8776            R3457 -1   M      A01X+046492Y+167600X0198Y0197     S1      
327m8776            R3392 -1          A01X+046492Y+166800X0198Y0197     S1      
327m8776            R3456 -2   M      A01X+046492Y+167200X0198Y0197R180 S1      
317m8777            VIA   -    M      A01X+048350Y+165850X0200Y         S2      
017m8777            VIA   -    M      A18X+048350Y+165850X0260Y         S2      
017m8777                  -    MD0100PA00X+048350Y+165850                       
317m8777            J110  -A7   D0142PA00X+054232Y+173421X0302Y    R180 S3      
327m8777            R3392 -2          A01X+046808Y+166800X0198Y0197     S1      
317m8778            VIA   -    MD0100PA00X+068178Y+157428X0200Y         S0      
317m8778            VIA   -    MD0100PA00X+080486Y+062679X0200Y         S0      
327m8778            R3479 -2          A01X+077823Y+049534X0198Y0197     S1      
317m8778            VIA   -    MD0100PA00X+078728Y+049924X0200Y    R180 S0      
317m8778            VIA   -    MD0100PA00X+086547Y+079308X0200Y         S0      
327m8778            R3451 -2   M      A01X+046858Y+169700X0198Y0197     S1      
327m8778            R3452 -1   M      A01X+046858Y+170100X0198Y0197R180 S1      
317m8778            VIA   -    M      A01X+046858Y+170400X0200Y         S2      
017m8778            VIA   -    M      A18X+046858Y+170400X0260Y         S2      
017m8778                  -    MD0100PA00X+046858Y+170400                       
327m8778            U253  -3          A01X+046775Y+169222X0160Y0200R180 S1      
317m8778            VIA   -    MD0100PA00X+068572Y+167239X0200Y         S0      
317GPU_BASE_ID1     J111  -N8   D0142PA00X+035295Y+167201X0302Y    R180 S3      
317GPU_BASE_ID1     VIA   -    M      A01X+073285Y+169570X0200Y         S2      
017GPU_BASE_ID1     VIA   -    M      A18X+073285Y+169570X0260Y         S2      
017GPU_BASE_ID1           -    MD0100PA00X+073285Y+169570                       
327GPU_BASE_ID1     R3441 -1   M      A01X+073747Y+168713X0198Y0197R090 S1      
327GPU_BASE_ID1     R3499 -1          A01X+073747Y+168368X0198Y0197R270 S1      
317GPU_BASE_ID0     J111  -A3   D0142PA00X+031358Y+173421X0302Y    R180 S3      
327GPU_BASE_ID0     R3516 -1          A01X+074133Y+168013X0198Y0197R270 S1      
327GPU_BASE_ID0     R3440 -1   M      A01X+074133Y+168374X0198Y0197R090 S1      
317GPU_BASE_ID0     VIA   -    M      A01X+074677Y+169604X0200Y         S2      
017GPU_BASE_ID0     VIA   -    M      A18X+074677Y+169604X0260Y         S2      
017GPU_BASE_ID0           -    MD0100PA00X+074677Y+169604                       
327m8779            R3433 -2          A01X+067311Y+172217X0198Y0197R090 S1      
327m8779            Q102  -5          A01X+066465Y+171962X0170Y0200R090 S1      
327m8779            Q102  -6   M      A01X+066465Y+172217X0170Y0200R090 S1      
327m8779            VIA   -    M      A01X+066956Y+172354X0300Y    R270 S1      
317m8780            VIA   -    M      A01X+082288Y+078033X0200Y         S2      
017m8780            VIA   -    M      A18X+082288Y+078033X0260Y         S2      
017m8780                  -    MD0100PA00X+082288Y+078033                       
317m8780            VIA   -    MD0100PA00X+076856Y+067757X0200Y         S0      
317m8780            VIA   -    MD0100PA00X+081298Y+046358X0200Y    R180 S0      
327m8780            R3480 -2          A01X+080938Y+046358X0198Y0197     S1      
317m8780            VIA   -    MD0100PA00X+065956Y+171467X0200Y         S0      
327m8780            C1973 -1   M      A01X+064882Y+171714X0198Y0197     S1      
327m8780            R3438 -2          A01X+064498Y+171714X0198Y0197     S1      
327m8780            Q102  -3   M      A01X+065717Y+171706X0170Y0200R090 S1      
317m8781            VIA   -    M      A01X+066212Y+172040X0200Y         S2      
017m8781            VIA   -    M      A18X+066212Y+172040X0260Y         S2      
017m8781                  -    MD0100PA00X+066212Y+172040                       
317m8781            J110  -A5   D0142PA00X+052657Y+173421X0302Y    R180 S3      
327m8781            R3429 -2          A01X+064498Y+172214X0198Y0197     S1      
327m8781            R3463 -1   M      A01X+064882Y+172214X0198Y0197     S1      
327m8781            Q102  -2   M      A01X+065717Y+171962X0170Y0200R090 S1      
327m8782            VIA   -    M      A01X+118945Y+172370X0300Y    R090 S1      
327m8782            R4138 -2          A01X+119990Y+173180X0198Y0197R180 S1      
327m8782            Q129  -5   M      A01X+119431Y+172370X0170Y0200R270 S1      
327m8782            Q129  -6          A01X+119431Y+172114X0170Y0200R270 S1      
317m8783            VIA   -    MD0100PA00X+160278Y+143592X0200Y         S0      
327m8783            R4148 -2          A01X+079273Y+046334X0198Y0197     S1      
317m8783            VIA   -    MD0100PA00X+079732Y+046334X0200Y         S0      
327m8783            Q129  -3          A01X+120179Y+172626X0170Y0200R270 S1      
327m8783            R4576 -2   M      A01X+120625Y+172786X0198Y0197R090 S1      
327m8783            C17   -1   M      A01X+121025Y+172786X0198Y0197R090 S1      
327m8783            R4141 -2   M      A01X+121425Y+172786X0198Y0197R270 S1      
317m8783            VIA   -    M      A01X+121974Y+172786X0200Y         S2      
017m8783            VIA   -    M      A18X+121974Y+172786X0260Y         S2      
017m8783                  -    MD0100PA00X+121974Y+172786                       
317m8783            VIA   -    MD0100PA00X+115928Y+147113X0200Y         S0      
327m8784            Q129  -2          A01X+120179Y+172370X0170Y0200R270 S1      
327m8784            R4576 -1   M      A01X+120625Y+172471X0198Y0197R090 S1      
327m8784            R4133 -2   M      A01X+121025Y+172401X0198Y0197R090 S1      
327m8784            R4134 -1   M      A01X+121425Y+172401X0198Y0197R270 S1      
317m8784            VIA   -    M      A01X+121974Y+172286X0200Y         S2      
017m8784            VIA   -    M      A18X+121974Y+172286X0260Y         S2      
017m8784                  -    MD0100PA00X+121974Y+172286                       
317m8784            J108  -A5   D0142PA00X+127027Y+173421X0302Y    R180 S3      
327m8785            Q136  -5          A01X+174462Y+172597X0170Y0200R090 S1      
327m8785            Q136  -6   M      A01X+174462Y+172853X0170Y0200R090 S1      
327m8785            R4165 -2          A01X+174948Y+172373X0198Y0197R090 S1      
327m8785            VIA   -    M      A01X+174948Y+172853X0300Y    R270 S1      
317m8786            VIA   -    MD0100PA00X+096005Y+051698X0200Y         S0      
317m8786            VIA   -    MD0100PA00X+095826Y+046581X0200Y         S0      
317m8786            VIA   -    MD0100PA00X+079725Y+045134X0200Y         S0      
327m8786            R4172 -2          A01X+079273Y+045134X0198Y0197     S1      
327m8786            C5    -1   M      A01X+172863Y+172342X0198Y0197R270 S1      
317m8786            VIA   -    M      A01X+171915Y+172153X0200Y         S2      
017m8786            VIA   -    M      A18X+171915Y+172153X0260Y         S2      
017m8786                  -    MD0100PA00X+171915Y+172153                       
327m8786            R4168 -2   M      A01X+172463Y+172342X0198Y0197R090 S1      
327m8786            Q136  -3          A01X+173714Y+172342X0170Y0200R090 S1      
327m8786            R4571 -2   M      A01X+173263Y+172342X0198Y0197R270 S1      
327m8787            R4139 -2          A01X+120827Y+167306X0198Y0197     S1      
327m8787            VIA   -    M      A01X+121307Y+167306X0300Y    R180 S1      
327m8787            Q133  -5          A01X+121051Y+167792X0170Y0200     S1      
327m8787            Q133  -6   M      A01X+121307Y+167792X0170Y0200     S1      
327m8788            R4136 -1   M      A01X+121180Y+169786X0198Y0197     S1      
327m8788            R4135 -2   M      A01X+121180Y+169386X0198Y0197R180 S1      
327m8788            Q133  -2          A01X+121051Y+168540X0170Y0200     S1      
327m8788            R4578 -1   M      A01X+121110Y+168986X0198Y0197R180 S1      
317m8788            VIA   -    M      A01X+121295Y+170334X0200Y    R090 S2      
017m8788            VIA   -    M      A18X+121295Y+170334X0260Y    R090 S2      
017m8788                  -    MD0100PA00X+121295Y+170334                       
317m8788            J108  -A3   D0142PA00X+125453Y+173421X0302Y    R180 S3      
317m8789            J105  -A1   D0142PA00X+156988Y+173421X0302Y0302R180 S3      
327m8789            Q136  -2          A01X+173714Y+172597X0170Y0200R090 S1      
327m8789            R4571 -1   M      A01X+173263Y+172656X0198Y0197R270 S1      
327m8789            R4160 -2   M      A01X+172863Y+172726X0198Y0197R270 S1      
327m8789            R4161 -1   M      A01X+172463Y+172726X0198Y0197R090 S1      
317m8789            VIA   -    M      A01X+171922Y+172726X0200Y         S2      
017m8789            VIA   -    M      A18X+171922Y+172726X0260Y         S2      
017m8789                  -    MD0100PA00X+171922Y+172726                       
327m8790            Q137  -5          A18X+170537Y+172103X0170Y0200R090 S2      
327m8790            VIA   -    M      A18X+171017Y+171896X0260Y         S2      
327m8790            Q137  -6   M      A18X+170537Y+171848X0170Y0200R090 S2      
327m8790            R4166 -2          A18X+171023Y+172328X0198Y0197R090 S2      
327m8791            Q137  -3          A18X+169789Y+172359X0170Y0200R090 S2      
327m8791            R4570 -2   M      A18X+169338Y+172359X0198Y0197R270 S2      
327m8791            C7    -1   M      A18X+168938Y+172359X0198Y0197R270 S2      
327m8791            R4169 -2   M      A18X+168538Y+172359X0198Y0197R090 S2      
317m8791            VIA   -    M      A01X+168088Y+172359X0200Y         S2      
017m8791            VIA   -    M      A18X+168088Y+172359X0260Y         S2      
017m8791                  -    MD0100PA00X+168088Y+172359                       
317m8791            VIA   -    MD0100PA00X+078088Y+045534X0200Y    R180 S0      
327m8791            R4171 -2          A01X+077823Y+045534X0198Y0197     S1      
317m8791            VIA   -    MD0100PA00X+086028Y+048864X0200Y         S0      
327m8792            R4137 -2          A01X+119293Y+167305X0198Y0197     S1      
327m8792            VIA   -    M      A01X+119699Y+167305X0300Y    R180 S1      
327m8792            Q130  -5          A01X+119517Y+167791X0170Y0200     S1      
327m8792            Q130  -6   M      A01X+119773Y+167791X0170Y0200     S1      
327m8793            R4140 -2   M      A01X+119261Y+169785X0198Y0197     S1      
327m8793            Q130  -3          A01X+119261Y+168539X0170Y0200     S1      
327m8793            C16   -1   M      A01X+119261Y+169385X0198Y0197R180 S1      
327m8793            R4577 -2   M      A01X+119261Y+168985X0198Y0197R180 S1      
317m8793            VIA   -    M      A01X+119261Y+170333X0200Y    R090 S2      
017m8793            VIA   -    M      A18X+119261Y+170333X0260Y    R090 S2      
017m8793                  -    MD0100PA00X+119261Y+170333                       
317m8793            VIA   -    MD0100PA00X+159799Y+143318X0200Y         S0      
317m8793            VIA   -    MD0100PA00X+081298Y+048016X0200Y    R180 S0      
327m8793            R4146 -2          A01X+080962Y+048016X0198Y0197     S1      
317m8793            VIA   -    MD0100PA00X+115072Y+146279X0200Y         S0      
327m8794            R4132 -1   M      A01X+119646Y+169785X0198Y0197     S1      
327m8794            R4131 -2   M      A01X+119646Y+169385X0198Y0197R180 S1      
327m8794            Q130  -2          A01X+119517Y+168539X0170Y0200     S1      
327m8794            R4577 -1   M      A01X+119576Y+168985X0198Y0197R180 S1      
317m8794            VIA   -    M      A01X+119761Y+170333X0200Y    R090 S2      
017m8794            VIA   -    M      A18X+119761Y+170333X0260Y    R090 S2      
017m8794                  -    MD0100PA00X+119761Y+170333                       
317m8794            J108  -A1   D0142PA00X+123878Y+173421X0302Y0302R180 S3      
327m8795            VIA   -    M      A18X+167042Y+171837X0260Y         S2      
327m8795            R4163 -1   M      A18X+168538Y+171974X0198Y0197R090 S2      
317m8795            J105  -A5   D0142PA00X+160138Y+173421X0302Y    R180 S3      
327m8795            R4162 -2   M      A18X+168938Y+171974X0198Y0197R270 S2      
327m8795            Q137  -2          A18X+169789Y+172103X0170Y0200R090 S2      
327m8795            R4570 -1   M      A18X+169338Y+172044X0198Y0197R270 S2      
327m8796            VIA   -    M      A18X+066782Y+171044X0260Y         S2      
327m8796            R4126 -2   M      A18X+066806Y+171438X0198Y0197R090 S2      
327m8796            Q132  -6          A18X+066320Y+170958X0170Y0200R090 S2      
327m8796            Q132  -5          A18X+066320Y+171214X0170Y0200R090 S2      
317m8797            J109  -N8   D0142PA00X+061713Y+167201X0302Y    R180 S3      
317m8797            VIA   -    M      A01X+063547Y+171181X0200Y         S2      
017m8797            VIA   -    M      A18X+063547Y+171181X0260Y         S2      
017m8797                  -    MD0100PA00X+063547Y+171181                       
327m8797            R4121 -2   M      A18X+064326Y+171084X0198Y0197R270 S2      
327m8797            R4122 -1   M      A18X+064726Y+171084X0198Y0197R090 S2      
327m8797            Q132  -2          A18X+065572Y+171214X0170Y0200R090 S2      
327m8797            R4573 -1   M      A18X+065126Y+171154X0198Y0197R270 S2      
327m8798            R4164 -2          A01X+167536Y+171208X0198Y0197R090 S1      
327m8798            VIA   -    M      A01X+167536Y+171688X0300Y    R270 S1      
327m8798            Q135  -5          A01X+167050Y+171432X0170Y0200R090 S1      
327m8798            Q135  -6   M      A01X+167050Y+171688X0170Y0200R090 S1      
327m8799            Q135  -3          A01X+166302Y+171176X0170Y0200R090 S1      
317m8799            VIA   -    M      A01X+164503Y+171061X0200Y         S2      
017m8799            VIA   -    M      A18X+164503Y+171061X0260Y         S2      
017m8799                  -    MD0100PA00X+164503Y+171061                       
327m8799            R4569 -2   M      A01X+165851Y+171176X0198Y0197R270 S1      
327m8799            C4    -1   M      A01X+165451Y+171176X0198Y0197R270 S1      
327m8799            R4167 -2   M      A01X+165051Y+171176X0198Y0197R090 S1      
317m8799            VIA   -    MD0100PA00X+086051Y+049777X0200Y         S0      
317m8799            VIA   -    MD0100PA00X+078088Y+046334X0200Y    R180 S0      
327m8799            R4170 -2          A18X+077823Y+046334X0198Y0197R180 S2      
327m8800            VIA   -    M      A18X+066785Y+169558X0260Y         S2      
327m8800            Q131  -6          A18X+066320Y+169558X0170Y0200R090 S2      
327m8800            Q131  -5          A18X+066320Y+169814X0170Y0200R090 S2      
327m8800            R4127 -2   M      A18X+066822Y+170016X0198Y0197     S2      
317m8801            VIA   -    MD0100PA00X+082279Y+077751X0200Y         S0      
317m8801            VIA   -    M      A01X+081298Y+047616X0200Y    R180 S2      
017m8801            VIA   -    M      A18X+081298Y+047616X0260Y    R180 S2      
017m8801                  -    MD0100PA00X+081298Y+047616                       
327m8801            R4144 -2          A01X+080962Y+047616X0198Y0197     S1      
317m8801            VIA   -    MD0100PA00X+077155Y+067796X0200Y         S0      
317m8801            VIA   -    MD0100PA00X+063939Y+170070X0200Y         S0      
327m8801            R4130 -2   M      A18X+064326Y+170070X0198Y0197R090 S2      
327m8801            C14   -1   M      A18X+064726Y+170070X0198Y0197R270 S2      
327m8801            R4572 -2   M      A18X+065126Y+170070X0198Y0197R270 S2      
327m8801            Q131  -3          A18X+065572Y+170070X0170Y0200R090 S2      
317m8802            J109  -N6   D0142PA00X+060138Y+167201X0302Y    R180 S3      
317m8802            VIA   -    M      A01X+063549Y+169684X0200Y         S2      
017m8802            VIA   -    M      A18X+063549Y+169684X0260Y         S2      
017m8802                  -    MD0100PA00X+063549Y+169684                       
327m8802            Q131  -2          A18X+065572Y+169814X0170Y0200R090 S2      
327m8802            R4572 -1   M      A18X+065126Y+169754X0198Y0197R270 S2      
327m8802            R4123 -2   M      A18X+064726Y+169684X0198Y0197R270 S2      
327m8802            R4124 -1   M      A18X+064326Y+169684X0198Y0197R090 S2      
317m8803            J105  -A7   D0142PA00X+161713Y+173421X0302Y    R180 S3      
327m8803            Q135  -2          A01X+166302Y+171432X0170Y0200R090 S1      
317m8803            VIA   -    M      A01X+164503Y+171561X0200Y         S2      
017m8803            VIA   -    M      A18X+164503Y+171561X0260Y         S2      
017m8803                  -    MD0100PA00X+164503Y+171561                       
327m8803            R4569 -1   M      A01X+165851Y+171491X0198Y0197R270 S1      
327m8803            R4158 -2   M      A01X+165451Y+171561X0198Y0197R270 S1      
327m8803            R4159 -1   M      A01X+165051Y+171561X0198Y0197R090 S1      
327m8804            R4125 -2          A18X+064337Y+163682X0198Y0197     S2      
327m8804            VIA   -    M      A18X+064532Y+163326X0260Y         S2      
327m8804            Q128  -6   M      A18X+065227Y+162558X0170Y0200     S2      
327m8804            Q128  -5          A18X+065483Y+162558X0170Y0200     S2      
317m8805            VIA   -    M      A01X+079974Y+062898X0200Y         S2      
017m8805            VIA   -    M      A18X+079974Y+062898X0260Y         S2      
017m8805                  -    MD0100PA00X+079974Y+062898                       
317m8805            VIA   -    MD0100PA00X+082539Y+077002X0200Y         S0      
317m8805            VIA   -    MD0100PA00X+075694Y+067632X0200Y         S0      
327m8805            R4143 -2          A18X+077823Y+047534X0198Y0197R180 S2      
317m8805            VIA   -    MD0100PA00X+078088Y+047534X0200Y    R180 S0      
317m8805            VIA   -    MD0100PA00X+068695Y+162514X0200Y         S0      
327m8805            C12   -1   M      A18X+065739Y+164152X0198Y0197R180 S2      
327m8805            R4128 -2          A18X+065739Y+164552X0198Y0197     S2      
327m8805            R4575 -2   M      A18X+065739Y+163752X0198Y0197R180 S2      
327m8805            Q128  -3   M      A18X+065739Y+163306X0170Y0200     S2      
317m8806            VIA   -    M      A01X+065354Y+164906X0200Y         S2      
017m8806            VIA   -    M      A18X+065354Y+164906X0260Y         S2      
017m8806                  -    MD0100PA00X+065354Y+164906                       
327m8806            Q128  -2          A18X+065483Y+163306X0170Y0200     S2      
327m8806            R4575 -1   M      A18X+065424Y+163752X0198Y0197R180 S2      
327m8806            R4120 -1   M      A18X+065354Y+164552X0198Y0197     S2      
327m8806            R4119 -2   M      A18X+065354Y+164152X0198Y0197R180 S2      
317m8806            J109  -N4   D0142PA00X+058563Y+167201X0302Y    R180 S3      
317GND              VIA   -    MD0100PA00X+054861Y+005799X0200Y         S0      
327GND              R4809 -2          A18X+054861Y+005481X0198Y0197R270 S2      
327GND              U247  -6          A01X+004595Y+052279X0100Y0220R270 S1      
317GND              VIA   -    MD0100PA00X+103375Y+165932X0200Y         S0      
317GND              VIA   -    MD0100PA00X+103380Y+165668X0200Y         S0      
327GND              C1115 -2          A01X+103739Y+165815X0400Y0500     S1      
327GND              PC2161-2          A01X+164651Y+043162X0198Y0197R090 S1      
317GND              VIA   -    MD0100PA00X+084975Y+040128X0200Y         S0      
327GND              C9050 -2          A01X+085262Y+040128X0198Y0197R180 S1      
317GND              VIA   -    MD0100PA00X+087202Y+041330X0200Y         S0      
327GND              U9050 -3          A01X+087086Y+040993X0220Y0320R090 S1      
317GND              VIA   -    MD0100PA00X+024625Y+020436X0200Y         S0      
327GND              U9051 -3          A01X+024071Y+020765X0220Y0320R270 S1      
317GND              VIA   -    MD0100PA00X+025410Y+020924X0200Y         S0      
327GND              C9051 -2          A01X+025527Y+021190X0198Y0197R270 S1      
327GND              R855  -2          A01X+017144Y+040056X0198Y0197     S1      
327GND              R1049 -2          A01X+014461Y+042716X0198Y0197R090 S1      
327GND              C1113 -2          A01X+016536Y+041425X0400Y0500R180 S1      
317GND              VIA   -    MD0100PA00X+016891Y+041593X0200Y         S0      
317GND              VIA   -    MD0100PA00X+016895Y+041295X0200Y         S0      
317GND              VIA   -    MD0100PA00X+017396Y+040056X0200Y    R180 S0      
327GND              R1474 -2          A01X+015162Y+043881X0198Y0197R180 S1      
327GND              Q7001 -3          A01X+014977Y+044582X0280Y0460     S1      
327GND              Q7001 -2          A01X+014477Y+044582X0280Y0460     S1      
327GND              Q7001 -1          A01X+013977Y+044582X0280Y0460     S1      
317GND              VIA   -    MD0100PA00X+014983Y+044192X0200Y         S0      
317GND              VIA   -    MD0100PA00X+014921Y+043864X0200Y         S0      
317GND              VIA   -    MD0100PA00X+014693Y+044187X0200Y         S0      
317GND              VIA   -    MD0100PA00X+014596Y+043880X0200Y         S0      
317GND              VIA   -    MD0100PA00X+014372Y+044196X0200Y         S0      
317GND              VIA   -    MD0100PA00X+014080Y+044192X0200Y         S0      
317GND              VIA   -    MD0100PA00X+013809Y+044190X0200Y         S0      
317GND              VIA   -    MD0100PA00X+014266Y+043893X0200Y         S0      
317GND              VIA   -    MD0100PA00X+013944Y+043900X0200Y         S0      
317GND              VIA   -    MD0100PA00X+014461Y+042956X0200Y    R270 S0      
317GND              VIA   -    MD0100PA00X+016622Y+043846X0200Y         S0      
317GND              VIA   -    MD0100PA00X+016944Y+043839X0200Y         S0      
317GND              VIA   -    MD0100PA00X+017274Y+043826X0200Y         S0      
317GND              VIA   -    MD0100PA00X+016487Y+044136X0200Y         S0      
317GND              VIA   -    MD0100PA00X+016758Y+044138X0200Y         S0      
317GND              VIA   -    MD0100PA00X+017050Y+044142X0200Y         S0      
317GND              VIA   -    MD0100PA00X+017371Y+044133X0200Y         S0      
317GND              VIA   -    MD0100PA00X+017599Y+043810X0200Y         S0      
317GND              VIA   -    MD0100PA00X+017661Y+044138X0200Y         S0      
327GND              Q7003 -3          A01X+017655Y+044528X0280Y0460     S1      
327GND              Q7003 -1          A01X+016655Y+044528X0280Y0460     S1      
327GND              Q7003 -2          A01X+017155Y+044528X0280Y0460     S1      
327GND              R1475 -2          A01X+017840Y+043827X0198Y0197R180 S1      
317GND              VIA   -    MD0100PA00X+019573Y+041241X0200Y         S0      
317GND              VIA   -    MD0100PA00X+019569Y+041539X0200Y         S0      
327GND              C1114 -2          A01X+019214Y+041371X0400Y0500R180 S1      
317GND              VIA   -    MD0100PA00X+018941Y+038818X0200Y    R090 S0      
327GND              R954  -2          A01X+018941Y+039058X0198Y0197R270 S1      
317GND              VIA   -    MD0100PA00X+017212Y+041660X0200Y         S0      
327GND              R1092 -2          A01X+017452Y+041660X0198Y0197R180 S1      
317GND              VIA   -    MD0100PA00X+157223Y+153300X0200Y         S0      
327GND              C7016 -2          A18X+157599Y+153557X0400Y0500R180 S2      
317GND              VIA   -    MD0100PA00X+144420Y+153324X0200Y         S0      
327GND              C7019 -2          A18X+144808Y+153574X0400Y0500R180 S2      
317GND              VIA   -    MD0100PA00X+130829Y+153338X0200Y         S0      
327GND              C7013 -2          A18X+131185Y+153534X0400Y0500R180 S2      
317GND              VIA   -    MD0100PA00X+118005Y+153325X0200Y         S0      
327GND              C7010 -2          A18X+118375Y+153325X0400Y0500R180 S2      
317GND              VIA   -    MD0100PA00X+056286Y+149936X0200Y         S0      
327GND              C7028 -2          A18X+056814Y+150198X0400Y0500R180 S2      
317GND              VIA   -    MD0100PA00X+043614Y+149932X0200Y         S0      
327GND              C7031 -2          A18X+043990Y+150127X0400Y0500R180 S2      
317GND              VIA   -    MD0100PA00X+029995Y+149950X0200Y         S0      
327GND              C7025 -2          A18X+030387Y+150094X0400Y0500R180 S2      
317GND              VIA   -    MD0100PA00X+017732Y+149832X0200Y         S0      
327GND              C7022 -2          A18X+017732Y+150245X0400Y0500R180 S2      
317GND              VIA   -    MD0100PA00X+119505Y+162004X0200Y         S0      
327GND              R6809 -2          A01X+126225Y+158620X0120Y0150R090 S1      
327GND              C7036 -2   M      A01X+156698Y+161836X0400Y0500R270 S1      
327GND              C7002 -2          A01X+156007Y+161824X0400Y0500R270 S1      
327GND              C7035 -2   M      A01X+130291Y+161866X0400Y0500R270 S1      
327GND              C7003 -2          A01X+129596Y+161865X0400Y0500R270 S1      
327GND              C7034 -2   M      A01X+121261Y+161927X0400Y0500R270 S1      
327GND              C7033 -2   M      A01X+120576Y+161927X0400Y0500R270 S1      
327GND              C7032 -2          A01X+124815Y+161065X0950Y1110     S1      
327GND              C7040 -2   M      A01X+055935Y+158572X0400Y0500R270 S1      
327GND              C7006 -2   M      A01X+055240Y+158565X0400Y0500R270 S1      
327GND              C7038 -2   M      A01X+020477Y+158613X0400Y0500R270 S1      
327GND              C7041 -2   M      A01X+019785Y+158611X0400Y0500R270 S1      
327GND              R701  -2          A01X+025447Y+155324X0120Y0150R090 S1      
327GND              C7039 -2   M      A01X+029994Y+158588X0400Y0500R270 S1      
327GND              C469  -2          A18X+044719Y+154229X0198Y0197R270 S2      
327GND              C498  -2          A18X+044195Y+152873X0120Y0150     S2      
327GND              C488  -2          A18X+044194Y+152382X0120Y0150     S2      
327GND              C459  -2          A18X+044989Y+151877X0120Y0150R270 S2      
327GND              C481  -2          A18X+053065Y+152665X0120Y0150R180 S2      
327GND              C433  -2   M      A18X+053550Y+152745X0400Y0500R090 S2      
327GND              C384  -2          A18X+057000Y+152382X0120Y0150     S2      
327GND              C386  -2          A18X+057796Y+151877X0120Y0150R270 S2      
327GND              C413  -2          A18X+057526Y+154229X0198Y0197R270 S2      
327GND              C393  -2          A18X+056979Y+152891X0120Y0150R090 S2      
327GND              C426  -2          A18X+064996Y+151404X0120Y0150R270 S2      
327GND              C554  -2          A18X+119089Y+157529X0198Y0197R270 S2      
327GND              C576  -2          A18X+118543Y+156191X0120Y0150R090 S2      
327GND              C555  -2          A18X+118564Y+155682X0120Y0150     S2      
327GND              C539  -2          A18X+119359Y+155177X0120Y0150R270 S2      
327GND              C566  -2          A18X+127435Y+155965X0120Y0150R180 S2      
327GND              C503  -2   M      A18X+127920Y+156045X0400Y0500R090 S2      
327GND              C622  -2          A18X+132166Y+155177X0120Y0150R270 S2      
327GND              C620  -2          A18X+131370Y+155682X0120Y0150     S2      
327GND              C616  -2          A18X+131349Y+156191X0120Y0150R090 S2      
327GND              C649  -2          A18X+131896Y+157529X0198Y0197R270 S2      
327GND              C658  -2          A18X+140241Y+155965X0120Y0150R180 S2      
327GND              C588  -2   M      A18X+140726Y+156045X0400Y0500R090 S2      
327GND              C1047 -2          A18X+153852Y+155965X0120Y0150R180 S2      
327GND              C991  -2   M      A18X+154337Y+156045X0400Y0500R090 S2      
327GND              C1054 -2          A18X+145507Y+157529X0198Y0197R270 S2      
327GND              C1053 -2          A18X+144961Y+156191X0120Y0150R090 S2      
327GND              C1050 -2          A18X+144981Y+155682X0120Y0150     S2      
327GND              C1006 -2          A18X+145777Y+155177X0120Y0150R270 S2      
327GND              C970  -2          A18X+158313Y+157529X0198Y0197R270 S2      
327GND              C784  -2          A18X+157767Y+156191X0120Y0150R090 S2      
327GND              C781  -2          A18X+157787Y+155682X0120Y0150     S2      
327GND              C779  -2          A18X+158583Y+155177X0120Y0150R270 S2      
327GND              C987  -2          A18X+165784Y+154705X0120Y0150R270 S2      
327GND              C336  -2          A18X+031108Y+154229X0198Y0197R270 S2      
327GND              C293  -2          A18X+031378Y+151877X0120Y0150R270 S2      
327GND              C312  -2          A18X+030562Y+152891X0120Y0150R090 S2      
327GND              C301  -2          A18X+030582Y+152382X0120Y0150     S2      
327GND              C103  -2   M      A18X+039939Y+152745X0400Y0500R090 S2      
327GND              C349  -2          A18X+039454Y+152665X0120Y0150R180 S2      
327GND              C264  -2          A18X+026647Y+152665X0120Y0150R180 S2      
327GND              C221  -2          A18X+018302Y+154229X0198Y0197R270 S2      
327GND              C281  -2          A18X+017756Y+152891X0120Y0150R090 S2      
327GND              C257  -2          A18X+017776Y+152382X0120Y0150     S2      
327GND              C186  -2          A18X+018572Y+151877X0120Y0150R270 S2      
327GND              C7037 -2          A01X+024051Y+157778X0950Y1110     S1      
327GND              R773  -2          A18X+006516Y+077698X0198Y0197R270 S2      
327GND              PC7001-2          A18X+011719Y+139021X0400Y0500R180 S2      
317GND              VIA   -    MD0100PA00X+072192Y+143159X0200Y    R090 S0      
317GND              VIA   -    MD0100PA00X+072192Y+142899X0200Y    R090 S0      
317GND              VIA   -    MD0100PA00X+172021Y+143533X0200Y         S0      
317GND              VIA   -    MD0100PA00X+172281Y+143533X0200Y         S0      
327GND              PC7002-2          A18X+172311Y+143173X0400Y0500R090 S2      
327GND              U247  -5          A01X+004595Y+052476X0100Y0220R270 S1      
327GND              U247  -10         A01X+005432Y+052033X0100Y0220     S1      
327GND              U247  -21         A01X+005432Y+053510X0100Y0220     S1      
327GND              C7001 -2          A01X+152470Y+161083X0950Y1110R180 S1      
327GND              C7000 -2          A01X+126053Y+161083X0950Y1110R180 S1      
327GND              C7004 -2          A01X+025272Y+157783X0950Y1110R180 S1      
327GND              C7014 -2          A18X+163148Y+153344X0950Y1110     S2      
327GND              C7015 -2          A18X+161939Y+153344X0950Y1110R180 S2      
327GND              C7018 -2          A18X+150342Y+153344X0950Y1110     S2      
327GND              C7017 -2          A18X+149133Y+153344X0950Y1110R180 S2      
327GND              C7012 -2          A18X+136730Y+153344X0950Y1110     S2      
327GND              C7011 -2          A18X+135522Y+153344X0950Y1110R180 S2      
327GND              C7009 -2          A18X+123924Y+153344X0950Y1110     S2      
327GND              C7008 -2          A18X+122715Y+153344X0950Y1110R180 S2      
327GND              C7026 -2          A18X+062360Y+150044X0950Y1110     S2      
327GND              C7027 -2          A18X+061152Y+150044X0950Y1110R180 S2      
327GND              C7030 -2          A18X+049554Y+150044X0950Y1110     S2      
327GND              C7029 -2          A18X+048345Y+150044X0950Y1110R180 S2      
327GND              C7023 -2          A18X+035943Y+150044X0950Y1110     S2      
327GND              C7024 -2          A18X+034734Y+150044X0950Y1110R180 S2      
327GND              C7005 -2          A01X+051683Y+157783X0950Y1110R180 S1      
327GND              R924  -2          A01X+044960Y+155494X0120Y0150R090 S1      
327GND              C1067 -2          A01X+045075Y+157110X0120Y0150R270 S1      
327GND              C7020 -2          A18X+023137Y+150044X0950Y1110     S2      
327GND              C7021 -2          A18X+021928Y+150044X0950Y1110R180 S2      
327GND              PC7003-2          A18X+072550Y+143015X0400Y0500R180 S2      
327GND              PC7000-2          A18X+114442Y+138608X0400Y0500R270 S2      
327GND              Y8003 -2   M      A01X+002059Y+052869X0480Y0560     S1      
327GND              Y8003 -4   M      A01X+002689Y+053736X0480Y0560     S1      
327GND              U247  -15         A01X+006072Y+052673X0100Y0220R270 S1      
327GND              U247  -24  M      A01X+004841Y+053510X0100Y0220     S1      
327GND              U247  -25  M      A01X+005333Y+052771X0965Y0965     S1      
317GND              VIA   -    MD0100PA00X+086470Y+083610X0200Y         S0      
317GND              VIA   -    MD0100PA00X+075350Y+067580X0200Y         S0      
327GND              C259  -2          A18X+019130Y+153606X0198Y0197R090 S2      
327GND              C255  -2          A18X+020548Y+153606X0198Y0197R090 S2      
327GND              C254  -2          A18X+020075Y+153606X0198Y0197R090 S2      
327GND              C284  -2          A18X+024800Y+153606X0198Y0197R090 S2      
327GND              C269  -2          A18X+025745Y+153606X0198Y0197R090 S2      
327GND              C258  -2          A18X+025272Y+153606X0198Y0197R090 S2      
327GND              C329  -2          A18X+031937Y+153606X0198Y0197R090 S2      
327GND              C318  -2          A18X+033354Y+153606X0198Y0197R090 S2      
327GND              C339  -2          A18X+037134Y+153606X0198Y0197R090 S2      
327GND              C343  -2          A18X+036661Y+153606X0198Y0197R090 S2      
327GND              C331  -2          A18X+038078Y+153606X0198Y0197R090 S2      
327GND              C351  -2          A18X+039084Y+153606X0198Y0197R090 S2      
327GND              C476  -2          A18X+045548Y+153606X0198Y0197R090 S2      
327GND              C487  -2          A18X+046965Y+153606X0198Y0197R090 S2      
327GND              C490  -2          A18X+046493Y+153606X0198Y0197R090 S2      
327GND              C501  -2          A18X+051217Y+153606X0198Y0197R090 S2      
327GND              C482  -2          A18X+052162Y+153606X0198Y0197R090 S2      
327GND              C494  -2          A18X+051690Y+153606X0198Y0197R090 S2      
327GND              C417  -2          A18X+058354Y+153606X0198Y0197R090 S2      
327GND              C399  -2          A18X+059771Y+153606X0198Y0197R090 S2      
327GND              C420  -2          A18X+063551Y+153606X0198Y0197R090 S2      
327GND              C416  -2          A18X+063078Y+153606X0198Y0197R090 S2      
327GND              C412  -2          A18X+064496Y+153606X0198Y0197R090 S2      
327GND              C402  -2          A18X+065501Y+153606X0198Y0197R090 S2      
327GND              C565  -2          A18X+119918Y+156906X0198Y0197R090 S2      
327GND              C568  -2          A18X+121335Y+156906X0198Y0197R090 S2      
327GND              C579  -2          A18X+120863Y+156906X0198Y0197R090 S2      
327GND              C586  -2          A18X+125587Y+156906X0198Y0197R090 S2      
327GND              C567  -2          A18X+126532Y+156906X0198Y0197R090 S2      
327GND              C571  -2          A18X+126060Y+156906X0198Y0197R090 S2      
327GND              C634  -2          A18X+132724Y+156906X0198Y0197R090 S2      
327GND              C630  -2          A18X+134141Y+156906X0198Y0197R090 S2      
327GND              C648  -2          A18X+137921Y+156906X0198Y0197R090 S2      
327GND              C644  -2          A18X+137448Y+156906X0198Y0197R090 S2      
327GND              C652  -2          A18X+138866Y+156906X0198Y0197R090 S2      
327GND              C663  -2          A18X+139871Y+156906X0198Y0197R090 S2      
327GND              C1030 -2          A18X+146335Y+156906X0198Y0197R090 S2      
327GND              C1049 -2          A18X+147280Y+156906X0198Y0197R090 S2      
327GND              C1041 -2          A18X+147752Y+156906X0198Y0197R090 S2      
327GND              C1026 -2          A18X+152004Y+156906X0198Y0197R090 S2      
327GND              C1036 -2          A18X+152949Y+156906X0198Y0197R090 S2      
327GND              C1045 -2          A18X+152477Y+156906X0198Y0197R090 S2      
327GND              C974  -2          A18X+159141Y+156906X0198Y0197R090 S2      
327GND              C799  -2          A18X+160559Y+156906X0198Y0197R090 S2      
327GND              C981  -2          A18X+163866Y+156906X0198Y0197R090 S2      
327GND              C973  -2          A18X+164338Y+156906X0198Y0197R090 S2      
327GND              C977  -2          A18X+165283Y+156906X0198Y0197R090 S2      
327GND              C988  -2          A18X+166289Y+156906X0198Y0197R090 S2      
317GND              VIA   -    MD0100PA00X+055620Y+153669X0200Y    R090 S0      
317GND              VIA   -    MD0100PA00X+054126Y+153688X0200Y    R090 S0      
317GND              VIA   -    MD0100PA00X+052894Y+154826X0200Y         S0      
327GND              R907  -2          A01X+053158Y+155152X0120Y0150R090 S1      
327GND              R6901 -2   M      A01X+052847Y+155150X0120Y0150R090 S1      
327GND              R1435 -2          A01X+054410Y+153364X0120Y0150R270 S1      
327GND              R6902 -2          A01X+053965Y+153957X0120Y0150R180 S1      
317GND              VIA   -    MD0100PA00X+027802Y+149339X0200Y    R090 S0      
317GND              VIA   -    MD0100PA00X+028062Y+149148X0200Y    R090 S0      
317GND              VIA   -    MD0100PA00X+028322Y+149339X0200Y    R090 S0      
317GND              VIA   -    MD0100PA00X+027802Y+149817X0200Y    R090 S0      
317GND              VIA   -    MD0100PA00X+028322Y+149817X0200Y    R090 S0      
317GND              VIA   -    MD0100PA00X+054481Y+146000X0200Y         S0      
317GND              H115  -8   MD0220PA00X+092874Y+033890X0360Y    R180 S3      
317GND              H115  -6   MD0220PA00X+094598Y+032165X0360Y    R180 S3      
317GND              H115  -7   MD0220PA00X+094093Y+033385X0360Y    R180 S3      
317GND              H115  -2   MD0220PA00X+091150Y+032165X0360Y    R180 S3      
317GND              H115  -9   MD0220PA00X+091655Y+033385X0360Y    R180 S3      
317GND              H115  -5   MD0220PA00X+094093Y+030946X0360Y    R180 S3      
317GND              H115  -4   MD0220PA00X+092874Y+030441X0360Y    R180 S3      
317GND              H115  -3   MD0220PA00X+091655Y+030946X0360Y    R180 S3      
317GND              VIA   -    MD0100PA00X+066605Y+150167X0200Y         S0      
327GND              R1421 -2          A01X+066821Y+150304X0120Y0150R090 S1      
327GND              R1376 -2          A01X+040431Y+150310X0120Y0150     S1      
317GND              VIA   -    MD0100PA00X+040158Y+150487X0200Y         S0      
317GND              VIA   -    MD0080PA00X+152285Y+113010X0160Y         S0      
317GND              VIA   -    MD0080PA00X+152167Y+090832X0160Y    R180 S0      
317GND              VIA   -    MD0080PA00X+139957Y+090832X0160Y    R180 S0      
317GND              VIA   -    MD0080PA00X+150317Y+090832X0160Y    R180 S0      
317GND              VIA   -    MD0080PA00X+150435Y+113010X0160Y         S0      
317GND              VIA   -    MD0080PA00X+036792Y+090832X0160Y    R180 S0      
317GND              VIA   -    MD0080PA00X+033461Y+090832X0160Y    R180 S0      
317GND              VIA   -    MD0080PA00X+040122Y+090832X0160Y    R180 S0      
317GND              VIA   -    MD0080PA00X+052703Y+090832X0160Y    R180 S0      
317GND              VIA   -    MD0080PA00X+131193Y+113010X0160Y         S0      
317GND              VIA   -    MD0080PA00X+033579Y+113010X0160Y         S0      
317GND              VIA   -    MD0080PA00X+038646Y+123572X0160Y    R090 S0      
317GND              VIA   -    MD0080PA00X+038630Y+124075X0160Y    R090 S0      
317GND              VIA   -    MD0080PA00X+031096Y+121913X0160Y    R090 S0      
317GND              VIA   -    MD0080PA00X+031112Y+121409X0160Y    R090 S0      
317GND              VIA   -    MD0080PA00X+038865Y+122345X0160Y    R090 S0      
317GND              VIA   -    MD0080PA00X+038880Y+121842X0160Y    R090 S0      
317GND              VIA   -    MD0080PA00X+036770Y+121662X0160Y         S0      
317GND              VIA   -    MD0080PA00X+037273Y+121678X0160Y         S0      
317GND              VIA   -    MD0080PA00X+051340Y+113010X0160Y         S0      
317GND              VIA   -    MD0080PA00X+134406Y+090832X0160Y    R180 S0      
317GND              VIA   -    MD0080PA00X+035430Y+113010X0160Y         S0      
317GND              VIA   -    MD0080PA00X+049002Y+090832X0160Y    R180 S0      
317GND              VIA   -    MD0080PA00X+147920Y+157564X0160Y         S0      
317GND              VIA   -    MD0080PA00X+146503Y+157564X0160Y         S0      
317GND              VIA   -    MD0080PA00X+059299Y+153606X0160Y         S0      
317GND              VIA   -    MD0080PA00X+059466Y+154264X0160Y         S0      
317GND              VIA   -    MD0080PA00X+137448Y+156906X0160Y         S0      
317GND              VIA   -    MD0080PA00X+060884Y+154264X0160Y         S0      
317GND              VIA   -    MD0080PA00X+061661Y+153606X0160Y         S0      
317GND              VIA   -    MD0080PA00X+061828Y+154264X0160Y         S0      
317GND              VIA   -    MD0080PA00X+062301Y+154264X0160Y         S0      
317GND              VIA   -    MD0080PA00X+145774Y+155220X0160Y         S0      
317GND              VIA   -    MD0080PA00X+152977Y+154724X0160Y         S0      
317GND              VIA   -    MD0080PA00X+152644Y+154030X0160Y         S0      
317GND              VIA   -    MD0080PA00X+152032Y+154724X0160Y         S0      
317GND              VIA   -    MD0080PA00X+151699Y+154030X0160Y         S0      
317GND              VIA   -    MD0080PA00X+151560Y+154724X0160Y         S0      
317GND              VIA   -    MD0080PA00X+151227Y+154030X0160Y         S0      
317GND              VIA   -    MD0080PA00X+151088Y+154724X0160Y         S0      
317GND              VIA   -    MD0080PA00X+150754Y+154030X0160Y         S0      
317GND              VIA   -    MD0080PA00X+150615Y+154724X0160Y         S0      
317GND              VIA   -    MD0080PA00X+150143Y+154724X0160Y         S0      
317GND              VIA   -    MD0080PA00X+149810Y+154030X0160Y         S0      
317GND              VIA   -    MD0080PA00X+149670Y+154724X0160Y         S0      
317GND              VIA   -    MD0080PA00X+149337Y+154030X0160Y         S0      
317GND              VIA   -    MD0080PA00X+149198Y+154724X0160Y         S0      
317GND              VIA   -    MD0080PA00X+148725Y+154724X0160Y         S0      
317GND              VIA   -    MD0080PA00X+148392Y+154030X0160Y         S0      
317GND              VIA   -    MD0080PA00X+148253Y+154724X0160Y         S0      
317GND              VIA   -    MD0080PA00X+147920Y+154030X0160Y         S0      
317GND              VIA   -    MD0080PA00X+147780Y+154724X0160Y         S0      
317GND              VIA   -    MD0080PA00X+147447Y+154030X0160Y         S0      
317GND              VIA   -    MD0080PA00X+147308Y+154724X0160Y         S0      
317GND              VIA   -    MD0080PA00X+146975Y+154030X0160Y         S0      
317GND              VIA   -    MD0080PA00X+146836Y+154724X0160Y         S0      
317GND              VIA   -    MD0080PA00X+146503Y+154030X0160Y         S0      
317GND              VIA   -    MD0080PA00X+146363Y+154724X0160Y         S0      
317GND              VIA   -    MD0080PA00X+146030Y+154030X0160Y         S0      
317GND              VIA   -    MD0080PA00X+145891Y+154724X0160Y         S0      
317GND              VIA   -    MD0080PA00X+145499Y+154051X0160Y         S0      
317GND              VIA   -    MD0080PA00X+145863Y+156906X0160Y         S0      
317GND              VIA   -    MD0080PA00X+146030Y+157564X0160Y         S0      
317GND              VIA   -    MD0080PA00X+146335Y+156906X0160Y         S0      
317GND              VIA   -    MD0080PA00X+146808Y+156906X0160Y         S0      
317GND              VIA   -    MD0080PA00X+147280Y+156906X0160Y         S0      
317GND              VIA   -    MD0080PA00X+147447Y+157564X0160Y         S0      
317GND              VIA   -    MD0080PA00X+148392Y+157564X0160Y         S0      
317GND              VIA   -    MD0080PA00X+148697Y+156906X0160Y         S0      
317GND              VIA   -    MD0080PA00X+149642Y+156906X0160Y         S0      
317GND              VIA   -    MD0080PA00X+150282Y+157564X0160Y         S0      
317GND              VIA   -    MD0080PA00X+151060Y+156906X0160Y         S0      
317GND              VIA   -    MD0080PA00X+152004Y+156906X0160Y         S0      
317GND              VIA   -    MD0080PA00X+152172Y+157564X0160Y         S0      
317GND              VIA   -    MD0080PA00X+152949Y+156906X0160Y         S0      
317GND              VIA   -    MD0080PA00X+153117Y+157564X0160Y         S0      
317GND              VIA   -    MD0080PA00X+153482Y+156906X0160Y         S0      
317GND              VIA   -    MD0080PA00X+166289Y+156906X0160Y         S0      
317GND              VIA   -    MD0080PA00X+165923Y+157564X0160Y         S0      
317GND              VIA   -    MD0080PA00X+165756Y+156906X0160Y         S0      
317GND              VIA   -    MD0080PA00X+165450Y+157564X0160Y         S0      
317GND              VIA   -    MD0080PA00X+162143Y+157564X0160Y         S0      
317GND              VIA   -    MD0080PA00X+158316Y+157542X0160Y         S0      
317GND              VIA   -    MD0080PA00X+157769Y+156172X0160Y         S0      
317GND              VIA   -    MD0080PA00X+165923Y+154030X0160Y         S0      
317GND              VIA   -    MD0080PA00X+158580Y+155220X0160Y         S0      
317GND              VIA   -    MD0080PA00X+165784Y+154724X0160Y         S0      
317GND              VIA   -    MD0080PA00X+165450Y+154030X0160Y         S0      
317GND              VIA   -    MD0080PA00X+164978Y+154030X0160Y         S0      
317GND              VIA   -    MD0080PA00X+164839Y+154724X0160Y         S0      
317GND              VIA   -    MD0080PA00X+164506Y+154030X0160Y         S0      
317GND              VIA   -    MD0080PA00X+164366Y+154724X0160Y         S0      
317GND              VIA   -    MD0080PA00X+164033Y+154030X0160Y         S0      
317GND              VIA   -    MD0080PA00X+163894Y+154724X0160Y         S0      
317GND              VIA   -    MD0080PA00X+163561Y+154030X0160Y         S0      
317GND              VIA   -    MD0080PA00X+163421Y+154724X0160Y         S0      
317GND              VIA   -    MD0080PA00X+163088Y+154030X0160Y         S0      
317GND              VIA   -    MD0080PA00X+162949Y+154724X0160Y         S0      
317GND              VIA   -    MD0080PA00X+162616Y+154030X0160Y         S0      
317GND              VIA   -    MD0080PA00X+162476Y+154724X0160Y         S0      
317GND              VIA   -    MD0080PA00X+162143Y+154030X0160Y         S0      
317GND              VIA   -    MD0080PA00X+162004Y+154724X0160Y         S0      
317GND              VIA   -    MD0080PA00X+161671Y+154030X0160Y         S0      
317GND              VIA   -    MD0080PA00X+161532Y+154724X0160Y         S0      
317GND              VIA   -    MD0080PA00X+161198Y+154030X0160Y         S0      
317GND              VIA   -    MD0080PA00X+161059Y+154724X0160Y         S0      
317GND              VIA   -    MD0080PA00X+160726Y+154030X0160Y         S0      
317GND              VIA   -    MD0080PA00X+160587Y+154724X0160Y         S0      
317GND              VIA   -    MD0080PA00X+160254Y+154030X0160Y         S0      
317GND              VIA   -    MD0080PA00X+160114Y+154724X0160Y         S0      
317GND              VIA   -    MD0080PA00X+159781Y+154030X0160Y         S0      
317GND              VIA   -    MD0080PA00X+159642Y+154724X0160Y         S0      
317GND              VIA   -    MD0080PA00X+159309Y+154030X0160Y         S0      
317GND              VIA   -    MD0080PA00X+159169Y+154724X0160Y         S0      
317GND              VIA   -    MD0080PA00X+158836Y+154030X0160Y         S0      
317GND              VIA   -    MD0080PA00X+158697Y+154724X0160Y         S0      
317GND              VIA   -    MD0080PA00X+158306Y+154051X0160Y         S0      
317GND              VIA   -    MD0080PA00X+157769Y+155681X0160Y         S0      
317GND              VIA   -    MD0080PA00X+158669Y+156906X0160Y         S0      
317GND              VIA   -    MD0080PA00X+158836Y+157564X0160Y         S0      
317GND              VIA   -    MD0080PA00X+159141Y+156906X0160Y         S0      
317GND              VIA   -    MD0080PA00X+159309Y+157564X0160Y         S0      
317GND              VIA   -    MD0080PA00X+159614Y+156906X0160Y         S0      
317GND              VIA   -    MD0080PA00X+159781Y+157564X0160Y         S0      
317GND              VIA   -    MD0080PA00X+160086Y+156906X0160Y         S0      
317GND              VIA   -    MD0080PA00X+160254Y+157564X0160Y         S0      
317GND              VIA   -    MD0080PA00X+160726Y+157564X0160Y         S0      
317GND              VIA   -    MD0080PA00X+161198Y+157564X0160Y         S0      
317GND              VIA   -    MD0080PA00X+161504Y+156906X0160Y         S0      
317GND              VIA   -    MD0080PA00X+161671Y+157564X0160Y         S0      
317GND              VIA   -    MD0080PA00X+162448Y+156906X0160Y         S0      
317GND              VIA   -    MD0080PA00X+162616Y+157564X0160Y         S0      
317GND              VIA   -    MD0080PA00X+163088Y+157564X0160Y         S0      
317GND              VIA   -    MD0080PA00X+163561Y+157564X0160Y         S0      
317GND              VIA   -    MD0080PA00X+163866Y+156906X0160Y         S0      
317GND              VIA   -    MD0080PA00X+164033Y+157564X0160Y         S0      
317GND              VIA   -    MD0080PA00X+164506Y+157564X0160Y         S0      
317GND              VIA   -    MD0080PA00X+164811Y+156906X0160Y         S0      
317GND              VIA   -    MD0080PA00X+164978Y+157564X0160Y         S0      
317GND              VIA   -    MD0080PA00X+145510Y+157542X0160Y         S0      
317GND              VIA   -    MD0080PA00X+144963Y+156172X0160Y         S0      
317GND              VIA   -    MD0080PA00X+144963Y+155681X0160Y         S0      
317GND              VIA   -    MD0080PA00X+148865Y+154030X0160Y         S0      
317GND              VIA   -    MD0080PA00X+150282Y+154030X0160Y         S0      
317GND              VIA   -    MD0080PA00X+152172Y+154030X0160Y         S0      
317GND              VIA   -    MD0080PA00X+153117Y+154030X0160Y         S0      
317GND              VIA   -    MD0080PA00X+137616Y+157564X0160Y         S0      
317GND              VIA   -    MD0080PA00X+059939Y+154264X0160Y         S0      
317GND              VIA   -    MD0080PA00X+060411Y+154264X0160Y         S0      
317GND              VIA   -    MD0080PA00X+060716Y+153606X0160Y         S0      
317GND              VIA   -    MD0080PA00X+139871Y+156906X0160Y         S0      
317GND              VIA   -    MD0080PA00X+139506Y+157564X0160Y         S0      
317GND              VIA   -    MD0080PA00X+139338Y+156906X0160Y         S0      
317GND              VIA   -    MD0080PA00X+139033Y+157564X0160Y         S0      
317GND              VIA   -    MD0080PA00X+135726Y+157564X0160Y         S0      
317GND              VIA   -    MD0080PA00X+131899Y+157542X0160Y         S0      
317GND              VIA   -    MD0080PA00X+131351Y+156172X0160Y         S0      
317GND              VIA   -    MD0080PA00X+139506Y+154030X0160Y         S0      
317GND              VIA   -    MD0080PA00X+132162Y+155220X0160Y         S0      
317GND              VIA   -    MD0080PA00X+139366Y+154724X0160Y         S0      
317GND              VIA   -    MD0080PA00X+139033Y+154030X0160Y         S0      
317GND              VIA   -    MD0080PA00X+138561Y+154030X0160Y         S0      
317GND              VIA   -    MD0080PA00X+138421Y+154724X0160Y         S0      
317GND              VIA   -    MD0080PA00X+138088Y+154030X0160Y         S0      
317GND              VIA   -    MD0080PA00X+137949Y+154724X0160Y         S0      
317GND              VIA   -    MD0080PA00X+137616Y+154030X0160Y         S0      
317GND              VIA   -    MD0080PA00X+137476Y+154724X0160Y         S0      
317GND              VIA   -    MD0080PA00X+137143Y+154030X0160Y         S0      
317GND              VIA   -    MD0080PA00X+137004Y+154724X0160Y         S0      
317GND              VIA   -    MD0080PA00X+136671Y+154030X0160Y         S0      
317GND              VIA   -    MD0080PA00X+136532Y+154724X0160Y         S0      
317GND              VIA   -    MD0080PA00X+136198Y+154030X0160Y         S0      
317GND              VIA   -    MD0080PA00X+136059Y+154724X0160Y         S0      
317GND              VIA   -    MD0080PA00X+135726Y+154030X0160Y         S0      
317GND              VIA   -    MD0080PA00X+135587Y+154724X0160Y         S0      
317GND              VIA   -    MD0080PA00X+135254Y+154030X0160Y         S0      
317GND              VIA   -    MD0080PA00X+135114Y+154724X0160Y         S0      
317GND              VIA   -    MD0080PA00X+134781Y+154030X0160Y         S0      
317GND              VIA   -    MD0080PA00X+134642Y+154724X0160Y         S0      
317GND              VIA   -    MD0080PA00X+134309Y+154030X0160Y         S0      
317GND              VIA   -    MD0080PA00X+134169Y+154724X0160Y         S0      
317GND              VIA   -    MD0080PA00X+133836Y+154030X0160Y         S0      
317GND              VIA   -    MD0080PA00X+133697Y+154724X0160Y         S0      
317GND              VIA   -    MD0080PA00X+133364Y+154030X0160Y         S0      
317GND              VIA   -    MD0080PA00X+133224Y+154724X0160Y         S0      
317GND              VIA   -    MD0080PA00X+132891Y+154030X0160Y         S0      
317GND              VIA   -    MD0080PA00X+132752Y+154724X0160Y         S0      
317GND              VIA   -    MD0080PA00X+132419Y+154030X0160Y         S0      
317GND              VIA   -    MD0080PA00X+132280Y+154724X0160Y         S0      
317GND              VIA   -    MD0080PA00X+131888Y+154051X0160Y         S0      
317GND              VIA   -    MD0080PA00X+131351Y+155681X0160Y         S0      
317GND              VIA   -    MD0080PA00X+132251Y+156906X0160Y         S0      
317GND              VIA   -    MD0080PA00X+132419Y+157564X0160Y         S0      
317GND              VIA   -    MD0080PA00X+132724Y+156906X0160Y         S0      
317GND              VIA   -    MD0080PA00X+132891Y+157564X0160Y         S0      
317GND              VIA   -    MD0080PA00X+133196Y+156906X0160Y         S0      
317GND              VIA   -    MD0080PA00X+133364Y+157564X0160Y         S0      
317GND              VIA   -    MD0080PA00X+133669Y+156906X0160Y         S0      
317GND              VIA   -    MD0080PA00X+133836Y+157564X0160Y         S0      
317GND              VIA   -    MD0080PA00X+134309Y+157564X0160Y         S0      
317GND              VIA   -    MD0080PA00X+134781Y+157564X0160Y         S0      
317GND              VIA   -    MD0080PA00X+135086Y+156906X0160Y         S0      
317GND              VIA   -    MD0080PA00X+135254Y+157564X0160Y         S0      
317GND              VIA   -    MD0080PA00X+136031Y+156906X0160Y         S0      
317GND              VIA   -    MD0080PA00X+136198Y+157564X0160Y         S0      
317GND              VIA   -    MD0080PA00X+136671Y+157564X0160Y         S0      
317GND              VIA   -    MD0080PA00X+137143Y+157564X0160Y         S0      
317GND              VIA   -    MD0080PA00X+062773Y+154264X0160Y         S0      
317GND              VIA   -    MD0080PA00X+063078Y+153606X0160Y         S0      
317GND              VIA   -    MD0080PA00X+063246Y+154264X0160Y         S0      
317GND              VIA   -    MD0080PA00X+063718Y+154264X0160Y         S0      
317GND              VIA   -    MD0080PA00X+064023Y+153606X0160Y         S0      
317GND              VIA   -    MD0080PA00X+064191Y+154264X0160Y         S0      
317GND              VIA   -    MD0080PA00X+065501Y+153606X0160Y         S0      
317GND              VIA   -    MD0080PA00X+065136Y+154264X0160Y         S0      
317GND              VIA   -    MD0080PA00X+064968Y+153606X0160Y         S0      
317GND              VIA   -    MD0080PA00X+064663Y+154264X0160Y         S0      
317GND              VIA   -    MD0080PA00X+061356Y+154264X0160Y         S0      
317GND              VIA   -    MD0080PA00X+057529Y+154242X0160Y         S0      
317GND              VIA   -    MD0080PA00X+056981Y+152872X0160Y         S0      
317GND              VIA   -    MD0080PA00X+065136Y+150730X0160Y         S0      
317GND              VIA   -    MD0080PA00X+057792Y+151920X0160Y         S0      
317GND              VIA   -    MD0080PA00X+064996Y+151424X0160Y         S0      
317GND              VIA   -    MD0080PA00X+064663Y+150730X0160Y         S0      
317GND              VIA   -    MD0080PA00X+064191Y+150730X0160Y         S0      
317GND              VIA   -    MD0080PA00X+064051Y+151424X0160Y         S0      
317GND              VIA   -    MD0080PA00X+063718Y+150730X0160Y         S0      
317GND              VIA   -    MD0080PA00X+063579Y+151424X0160Y         S0      
317GND              VIA   -    MD0080PA00X+063246Y+150730X0160Y         S0      
317GND              VIA   -    MD0080PA00X+063106Y+151424X0160Y         S0      
317GND              VIA   -    MD0080PA00X+062773Y+150730X0160Y         S0      
317GND              VIA   -    MD0080PA00X+062634Y+151424X0160Y         S0      
317GND              VIA   -    MD0080PA00X+062301Y+150730X0160Y         S0      
317GND              VIA   -    MD0080PA00X+062162Y+151424X0160Y         S0      
317GND              VIA   -    MD0080PA00X+061828Y+150730X0160Y         S0      
317GND              VIA   -    MD0080PA00X+061689Y+151424X0160Y         S0      
317GND              VIA   -    MD0080PA00X+061356Y+150730X0160Y         S0      
317GND              VIA   -    MD0080PA00X+061217Y+151424X0160Y         S0      
317GND              VIA   -    MD0080PA00X+060884Y+150730X0160Y         S0      
317GND              VIA   -    MD0080PA00X+060744Y+151424X0160Y         S0      
317GND              VIA   -    MD0080PA00X+060411Y+150730X0160Y         S0      
317GND              VIA   -    MD0080PA00X+060272Y+151424X0160Y         S0      
317GND              VIA   -    MD0080PA00X+059939Y+150730X0160Y         S0      
317GND              VIA   -    MD0080PA00X+059799Y+151424X0160Y         S0      
317GND              VIA   -    MD0080PA00X+059466Y+150730X0160Y         S0      
317GND              VIA   -    MD0080PA00X+059327Y+151424X0160Y         S0      
317GND              VIA   -    MD0080PA00X+058994Y+150730X0160Y         S0      
317GND              VIA   -    MD0080PA00X+058854Y+151424X0160Y         S0      
317GND              VIA   -    MD0080PA00X+058521Y+150730X0160Y         S0      
317GND              VIA   -    MD0080PA00X+058382Y+151424X0160Y         S0      
317GND              VIA   -    MD0080PA00X+058049Y+150730X0160Y         S0      
317GND              VIA   -    MD0080PA00X+057910Y+151424X0160Y         S0      
317GND              VIA   -    MD0080PA00X+057518Y+150751X0160Y         S0      
317GND              VIA   -    MD0080PA00X+056981Y+152381X0160Y         S0      
317GND              VIA   -    MD0080PA00X+057881Y+153606X0160Y         S0      
317GND              VIA   -    MD0080PA00X+058049Y+154264X0160Y         S0      
317GND              VIA   -    MD0080PA00X+058354Y+153606X0160Y         S0      
317GND              VIA   -    MD0080PA00X+058521Y+154264X0160Y         S0      
317GND              VIA   -    MD0080PA00X+058826Y+153606X0160Y         S0      
317GND              VIA   -    MD0080PA00X+058994Y+154264X0160Y         S0      
317GND              VIA   -    MD0080PA00X+051857Y+154264X0160Y         S0      
317GND              VIA   -    MD0080PA00X+050912Y+154264X0160Y         S0      
317GND              VIA   -    MD0080PA00X+050440Y+154264X0160Y         S0      
317GND              VIA   -    MD0080PA00X+049967Y+154264X0160Y         S0      
317GND              VIA   -    MD0080PA00X+049022Y+154264X0160Y         S0      
317GND              VIA   -    MD0080PA00X+048550Y+154264X0160Y         S0      
317GND              VIA   -    MD0080PA00X+048077Y+154264X0160Y         S0      
317GND              VIA   -    MD0080PA00X+047132Y+154264X0160Y         S0      
317GND              VIA   -    MD0080PA00X+046188Y+154264X0160Y         S0      
317GND              VIA   -    MD0080PA00X+045715Y+154264X0160Y         S0      
317GND              VIA   -    MD0080PA00X+044722Y+154242X0160Y         S0      
317GND              VIA   -    MD0080PA00X+044175Y+152872X0160Y         S0      
317GND              VIA   -    MD0080PA00X+044175Y+152381X0160Y         S0      
317GND              VIA   -    MD0080PA00X+048077Y+150730X0160Y         S0      
317GND              VIA   -    MD0080PA00X+049495Y+150730X0160Y         S0      
317GND              VIA   -    MD0080PA00X+051384Y+150730X0160Y         S0      
317GND              VIA   -    MD0080PA00X+052329Y+150730X0160Y         S0      
317GND              VIA   -    MD0080PA00X+044986Y+151920X0160Y         S0      
317GND              VIA   -    MD0080PA00X+052190Y+151424X0160Y         S0      
317GND              VIA   -    MD0080PA00X+051857Y+150730X0160Y         S0      
317GND              VIA   -    MD0080PA00X+051245Y+151424X0160Y         S0      
317GND              VIA   -    MD0080PA00X+050912Y+150730X0160Y         S0      
317GND              VIA   -    MD0080PA00X+050773Y+151424X0160Y         S0      
317GND              VIA   -    MD0080PA00X+050440Y+150730X0160Y         S0      
317GND              VIA   -    MD0080PA00X+050300Y+151424X0160Y         S0      
317GND              VIA   -    MD0080PA00X+049967Y+150730X0160Y         S0      
317GND              VIA   -    MD0080PA00X+049828Y+151424X0160Y         S0      
317GND              VIA   -    MD0080PA00X+049355Y+151424X0160Y         S0      
317GND              VIA   -    MD0080PA00X+049022Y+150730X0160Y         S0      
317GND              VIA   -    MD0080PA00X+048883Y+151424X0160Y         S0      
317GND              VIA   -    MD0080PA00X+048550Y+150730X0160Y         S0      
317GND              VIA   -    MD0080PA00X+048410Y+151424X0160Y         S0      
317GND              VIA   -    MD0080PA00X+047938Y+151424X0160Y         S0      
317GND              VIA   -    MD0080PA00X+047605Y+150730X0160Y         S0      
317GND              VIA   -    MD0080PA00X+047466Y+151424X0160Y         S0      
317GND              VIA   -    MD0080PA00X+047132Y+150730X0160Y         S0      
317GND              VIA   -    MD0080PA00X+046993Y+151424X0160Y         S0      
317GND              VIA   -    MD0080PA00X+046660Y+150730X0160Y         S0      
317GND              VIA   -    MD0080PA00X+046521Y+151424X0160Y         S0      
317GND              VIA   -    MD0080PA00X+046188Y+150730X0160Y         S0      
317GND              VIA   -    MD0080PA00X+046048Y+151424X0160Y         S0      
317GND              VIA   -    MD0080PA00X+045715Y+150730X0160Y         S0      
317GND              VIA   -    MD0080PA00X+045576Y+151424X0160Y         S0      
317GND              VIA   -    MD0080PA00X+045243Y+150730X0160Y         S0      
317GND              VIA   -    MD0080PA00X+045103Y+151424X0160Y         S0      
317GND              VIA   -    MD0080PA00X+044712Y+150751X0160Y         S0      
317GND              VIA   -    MD0080PA00X+045075Y+153606X0160Y         S0      
317GND              VIA   -    MD0080PA00X+045243Y+154264X0160Y         S0      
317GND              VIA   -    MD0080PA00X+045548Y+153606X0160Y         S0      
317GND              VIA   -    MD0080PA00X+046020Y+153606X0160Y         S0      
317GND              VIA   -    MD0080PA00X+046493Y+153606X0160Y         S0      
317GND              VIA   -    MD0080PA00X+046660Y+154264X0160Y         S0      
317GND              VIA   -    MD0080PA00X+047605Y+154264X0160Y         S0      
317GND              VIA   -    MD0080PA00X+126227Y+157564X0160Y         S0      
317GND              VIA   -    MD0080PA00X+125282Y+157564X0160Y         S0      
317GND              VIA   -    MD0080PA00X+124810Y+157564X0160Y         S0      
317GND              VIA   -    MD0080PA00X+124337Y+157564X0160Y         S0      
317GND              VIA   -    MD0080PA00X+123392Y+157564X0160Y         S0      
317GND              VIA   -    MD0080PA00X+122920Y+157564X0160Y         S0      
317GND              VIA   -    MD0080PA00X+122447Y+157564X0160Y         S0      
317GND              VIA   -    MD0080PA00X+121502Y+157564X0160Y         S0      
317GND              VIA   -    MD0080PA00X+120558Y+157564X0160Y         S0      
317GND              VIA   -    MD0080PA00X+120085Y+157564X0160Y         S0      
317GND              VIA   -    MD0080PA00X+119092Y+157542X0160Y         S0      
317GND              VIA   -    MD0080PA00X+118545Y+156172X0160Y         S0      
317GND              VIA   -    MD0080PA00X+118545Y+155681X0160Y         S0      
317GND              VIA   -    MD0080PA00X+122447Y+154030X0160Y         S0      
317GND              VIA   -    MD0080PA00X+123865Y+154030X0160Y         S0      
317GND              VIA   -    MD0080PA00X+125754Y+154030X0160Y         S0      
317GND              VIA   -    MD0080PA00X+126699Y+154030X0160Y         S0      
317GND              VIA   -    MD0080PA00X+119356Y+155220X0160Y         S0      
317GND              VIA   -    MD0080PA00X+126560Y+154724X0160Y         S0      
317GND              VIA   -    MD0080PA00X+126227Y+154030X0160Y         S0      
317GND              VIA   -    MD0080PA00X+125615Y+154724X0160Y         S0      
317GND              VIA   -    MD0080PA00X+125282Y+154030X0160Y         S0      
317GND              VIA   -    MD0080PA00X+125143Y+154724X0160Y         S0      
317GND              VIA   -    MD0080PA00X+124810Y+154030X0160Y         S0      
317GND              VIA   -    MD0080PA00X+124670Y+154724X0160Y         S0      
317GND              VIA   -    MD0080PA00X+124337Y+154030X0160Y         S0      
317GND              VIA   -    MD0080PA00X+124198Y+154724X0160Y         S0      
317GND              VIA   -    MD0080PA00X+123725Y+154724X0160Y         S0      
317GND              VIA   -    MD0080PA00X+123392Y+154030X0160Y         S0      
317GND              VIA   -    MD0080PA00X+123253Y+154724X0160Y         S0      
317GND              VIA   -    MD0080PA00X+122920Y+154030X0160Y         S0      
317GND              VIA   -    MD0080PA00X+122780Y+154724X0160Y         S0      
317GND              VIA   -    MD0080PA00X+122308Y+154724X0160Y         S0      
317GND              VIA   -    MD0080PA00X+121975Y+154030X0160Y         S0      
317GND              VIA   -    MD0080PA00X+121836Y+154724X0160Y         S0      
317GND              VIA   -    MD0080PA00X+121502Y+154030X0160Y         S0      
317GND              VIA   -    MD0080PA00X+121363Y+154724X0160Y         S0      
317GND              VIA   -    MD0080PA00X+121030Y+154030X0160Y         S0      
317GND              VIA   -    MD0080PA00X+120891Y+154724X0160Y         S0      
317GND              VIA   -    MD0080PA00X+120558Y+154030X0160Y         S0      
317GND              VIA   -    MD0080PA00X+120418Y+154724X0160Y         S0      
317GND              VIA   -    MD0080PA00X+120085Y+154030X0160Y         S0      
317GND              VIA   -    MD0080PA00X+119946Y+154724X0160Y         S0      
317GND              VIA   -    MD0080PA00X+119613Y+154030X0160Y         S0      
317GND              VIA   -    MD0080PA00X+119473Y+154724X0160Y         S0      
317GND              VIA   -    MD0080PA00X+119082Y+154051X0160Y         S0      
317GND              VIA   -    MD0080PA00X+119445Y+156906X0160Y         S0      
317GND              VIA   -    MD0080PA00X+119613Y+157564X0160Y         S0      
317GND              VIA   -    MD0080PA00X+119918Y+156906X0160Y         S0      
317GND              VIA   -    MD0080PA00X+120390Y+156906X0160Y         S0      
317GND              VIA   -    MD0080PA00X+120863Y+156906X0160Y         S0      
317GND              VIA   -    MD0080PA00X+121030Y+157564X0160Y         S0      
317GND              VIA   -    MD0080PA00X+121975Y+157564X0160Y         S0      
317GND              VIA   -    MD0080PA00X+122280Y+156906X0160Y         S0      
317GND              VIA   -    MD0080PA00X+123225Y+156906X0160Y         S0      
317GND              VIA   -    MD0080PA00X+123865Y+157564X0160Y         S0      
317GND              VIA   -    MD0080PA00X+124642Y+156906X0160Y         S0      
317GND              VIA   -    MD0080PA00X+125587Y+156906X0160Y         S0      
317GND              VIA   -    MD0080PA00X+125754Y+157564X0160Y         S0      
317GND              VIA   -    MD0080PA00X+126532Y+156906X0160Y         S0      
317GND              VIA   -    MD0080PA00X+126699Y+157564X0160Y         S0      
317GND              VIA   -    MD0080PA00X+127065Y+156906X0160Y         S0      
317GND              VIA   -    MD0080PA00X+052329Y+154264X0160Y         S0      
317GND              VIA   -    MD0080PA00X+052695Y+153606X0160Y         S0      
317GND              VIA   -    MD0080PA00X+048855Y+153606X0160Y         S0      
317GND              VIA   -    MD0080PA00X+049495Y+154264X0160Y         S0      
317GND              VIA   -    MD0080PA00X+050272Y+153606X0160Y         S0      
317GND              VIA   -    MD0080PA00X+051217Y+153606X0160Y         S0      
317GND              VIA   -    MD0080PA00X+051384Y+154264X0160Y         S0      
317GND              VIA   -    MD0080PA00X+052162Y+153606X0160Y         S0      
317GND              VIA   -    MD0080PA00X+047910Y+153606X0160Y         S0      
317GND              VIA   -    MD0080PA00X+146975Y+157564X0160Y         S0      
317GND              VIA   -    MD0080PA00X+138088Y+157564X0160Y         S0      
317GND              VIA   -    MD0080PA00X+138393Y+156906X0160Y         S0      
317GND              VIA   -    MD0080PA00X+152644Y+157564X0160Y         S0      
317GND              VIA   -    MD0080PA00X+151699Y+157564X0160Y         S0      
317GND              VIA   -    MD0080PA00X+151227Y+157564X0160Y         S0      
317GND              VIA   -    MD0080PA00X+150754Y+157564X0160Y         S0      
317GND              VIA   -    MD0080PA00X+149810Y+157564X0160Y         S0      
317GND              VIA   -    MD0080PA00X+149337Y+157564X0160Y         S0      
317GND              VIA   -    MD0080PA00X+148865Y+157564X0160Y         S0      
317GND              VIA   -    MD0080PA00X+138561Y+157564X0160Y         S0      
317GND              VIA   -    MD0080PA00X+140075Y+113010X0160Y         S0      
317GND              VIA   -    MD0080PA00X+031464Y+153606X0160Y         S0      
317GND              VIA   -    MD0080PA00X+017758Y+152381X0160Y         S0      
317GND              VIA   -    MD0080PA00X+017758Y+152872X0160Y         S0      
317GND              VIA   -    MD0080PA00X+030564Y+152381X0160Y         S0      
317GND              VIA   -    MD0080PA00X+030564Y+152872X0160Y         S0      
317GND              VIA   -    MD0080PA00X+018305Y+154242X0160Y         S0      
317GND              VIA   -    MD0080PA00X+131075Y+090832X0160Y    R180 S0      
317GND              VIA   -    MD0080PA00X+132926Y+090832X0160Y    R180 S0      
317GND              VIA   -    MD0080PA00X+019298Y+154264X0160Y         S0      
317GND              VIA   -    MD0080PA00X+146616Y+090832X0160Y    R180 S0      
317GND              VIA   -    MD0080PA00X+021660Y+154264X0160Y         S0      
317GND              VIA   -    MD0080PA00X+022132Y+154264X0160Y         S0      
317GND              VIA   -    MD0080PA00X+054553Y+090832X0160Y    R180 S0      
317GND              VIA   -    MD0080PA00X+018658Y+153606X0160Y         S0      
317GND              VIA   -    MD0080PA00X+038718Y+154264X0160Y         S0      
317GND              VIA   -    MD0080PA00X+038246Y+154264X0160Y         S0      
317GND              VIA   -    MD0080PA00X+039084Y+153606X0160Y         S0      
317GND              VIA   -    MD0080PA00X+038551Y+153606X0160Y         S0      
317GND              VIA   -    MD0080PA00X+038579Y+151424X0160Y         S0      
317GND              VIA   -    MD0080PA00X+038718Y+150730X0160Y         S0      
317GND              VIA   -    MD0080PA00X+038246Y+150730X0160Y         S0      
317GND              VIA   -    MD0080PA00X+037301Y+154264X0160Y         S0      
317GND              VIA   -    MD0080PA00X+036828Y+154264X0160Y         S0      
317GND              VIA   -    MD0080PA00X+037773Y+154264X0160Y         S0      
317GND              VIA   -    MD0080PA00X+036661Y+153606X0160Y         S0      
317GND              VIA   -    MD0080PA00X+037606Y+153606X0160Y         S0      
317GND              VIA   -    MD0080PA00X+037162Y+151424X0160Y         S0      
317GND              VIA   -    MD0080PA00X+036689Y+151424X0160Y         S0      
317GND              VIA   -    MD0080PA00X+037634Y+151424X0160Y         S0      
317GND              VIA   -    MD0080PA00X+037301Y+150730X0160Y         S0      
317GND              VIA   -    MD0080PA00X+036828Y+150730X0160Y         S0      
317GND              VIA   -    MD0080PA00X+037773Y+150730X0160Y         S0      
317GND              VIA   -    MD0080PA00X+036356Y+154264X0160Y         S0      
317GND              VIA   -    MD0080PA00X+035884Y+154264X0160Y         S0      
317GND              VIA   -    MD0080PA00X+035411Y+154264X0160Y         S0      
317GND              VIA   -    MD0080PA00X+035244Y+153606X0160Y         S0      
317GND              VIA   -    MD0080PA00X+036217Y+151424X0160Y         S0      
317GND              VIA   -    MD0080PA00X+035744Y+151424X0160Y         S0      
317GND              VIA   -    MD0080PA00X+035272Y+151424X0160Y         S0      
317GND              VIA   -    MD0080PA00X+036356Y+150730X0160Y         S0      
317GND              VIA   -    MD0080PA00X+035884Y+150730X0160Y         S0      
317GND              VIA   -    MD0080PA00X+035411Y+150730X0160Y         S0      
317GND              VIA   -    MD0080PA00X+034939Y+154264X0160Y         S0      
317GND              VIA   -    MD0080PA00X+034466Y+154264X0160Y         S0      
317GND              VIA   -    MD0080PA00X+033994Y+154264X0160Y         S0      
317GND              VIA   -    MD0080PA00X+034299Y+153606X0160Y         S0      
317GND              VIA   -    MD0080PA00X+034799Y+151424X0160Y         S0      
317GND              VIA   -    MD0080PA00X+034327Y+151424X0160Y         S0      
317GND              VIA   -    MD0080PA00X+033854Y+151424X0160Y         S0      
317GND              VIA   -    MD0080PA00X+034939Y+150730X0160Y         S0      
317GND              VIA   -    MD0080PA00X+034466Y+150730X0160Y         S0      
317GND              VIA   -    MD0080PA00X+033994Y+150730X0160Y         S0      
317GND              VIA   -    MD0080PA00X+033521Y+154264X0160Y         S0      
317GND              VIA   -    MD0080PA00X+033049Y+154264X0160Y         S0      
317GND              VIA   -    MD0080PA00X+032576Y+154264X0160Y         S0      
317GND              VIA   -    MD0080PA00X+032882Y+153606X0160Y         S0      
317GND              VIA   -    MD0080PA00X+032409Y+153606X0160Y         S0      
317GND              VIA   -    MD0080PA00X+033382Y+151424X0160Y         S0      
317GND              VIA   -    MD0080PA00X+032910Y+151424X0160Y         S0      
317GND              VIA   -    MD0080PA00X+032437Y+151424X0160Y         S0      
317GND              VIA   -    MD0080PA00X+032576Y+150730X0160Y         S0      
317GND              VIA   -    MD0080PA00X+033521Y+150730X0160Y         S0      
317GND              VIA   -    MD0080PA00X+033049Y+150730X0160Y         S0      
317GND              VIA   -    MD0080PA00X+032104Y+154264X0160Y         S0      
317GND              VIA   -    MD0080PA00X+031632Y+154264X0160Y         S0      
317GND              VIA   -    MD0080PA00X+031111Y+154242X0160Y         S0      
317GND              VIA   -    MD0080PA00X+031937Y+153606X0160Y         S0      
317GND              VIA   -    MD0080PA00X+031965Y+151424X0160Y         S0      
317GND              VIA   -    MD0080PA00X+031492Y+151424X0160Y         S0      
317GND              VIA   -    MD0080PA00X+031375Y+151920X0160Y         S0      
317GND              VIA   -    MD0080PA00X+032104Y+150730X0160Y         S0      
317GND              VIA   -    MD0080PA00X+031632Y+150730X0160Y         S0      
317GND              VIA   -    MD0080PA00X+031101Y+150751X0160Y         S0      
317GND              VIA   -    MD0080PA00X+026278Y+153606X0160Y         S0      
317GND              VIA   -    MD0080PA00X+024800Y+153606X0160Y         S0      
317GND              VIA   -    MD0080PA00X+025745Y+153606X0160Y         S0      
317GND              VIA   -    MD0080PA00X+025773Y+151424X0160Y         S0      
317GND              VIA   -    MD0080PA00X+024828Y+151424X0160Y         S0      
317GND              VIA   -    MD0080PA00X+025440Y+150730X0160Y         S0      
317GND              VIA   -    MD0080PA00X+024967Y+150730X0160Y         S0      
317GND              VIA   -    MD0080PA00X+025912Y+150730X0160Y         S0      
317GND              VIA   -    MD0080PA00X+023855Y+153606X0160Y         S0      
317GND              VIA   -    MD0080PA00X+018825Y+154264X0160Y         S0      
317GND              VIA   -    MD0080PA00X+024355Y+151424X0160Y         S0      
317GND              VIA   -    MD0080PA00X+020715Y+154264X0160Y         S0      
317GND              VIA   -    MD0080PA00X+023883Y+151424X0160Y         S0      
317GND              VIA   -    MD0080PA00X+020243Y+154264X0160Y         S0      
317GND              VIA   -    MD0080PA00X+023410Y+151424X0160Y         S0      
317GND              VIA   -    MD0080PA00X+024495Y+150730X0160Y         S0      
317GND              VIA   -    MD0080PA00X+024022Y+150730X0160Y         S0      
317GND              VIA   -    MD0080PA00X+023550Y+150730X0160Y         S0      
317GND              VIA   -    MD0080PA00X+023077Y+154264X0160Y         S0      
317GND              VIA   -    MD0080PA00X+024967Y+154264X0160Y         S0      
317GND              VIA   -    MD0080PA00X+022438Y+153606X0160Y         S0      
317GND              VIA   -    MD0080PA00X+025912Y+154264X0160Y         S0      
317GND              VIA   -    MD0080PA00X+025440Y+154264X0160Y         S0      
317GND              VIA   -    MD0080PA00X+019770Y+154264X0160Y         S0      
317GND              VIA   -    MD0080PA00X+022938Y+151424X0160Y         S0      
317GND              VIA   -    MD0080PA00X+022466Y+151424X0160Y         S0      
317GND              VIA   -    MD0080PA00X+021993Y+151424X0160Y         S0      
317GND              VIA   -    MD0080PA00X+023077Y+150730X0160Y         S0      
317GND              VIA   -    MD0080PA00X+022605Y+150730X0160Y         S0      
317GND              VIA   -    MD0080PA00X+022132Y+150730X0160Y         S0      
317GND              VIA   -    MD0080PA00X+021188Y+154264X0160Y         S0      
317GND              VIA   -    MD0080PA00X+021493Y+153606X0160Y         S0      
317GND              VIA   -    MD0080PA00X+024495Y+154264X0160Y         S0      
317GND              VIA   -    MD0080PA00X+023550Y+154264X0160Y         S0      
317GND              VIA   -    MD0080PA00X+024022Y+154264X0160Y         S0      
317GND              VIA   -    MD0080PA00X+021048Y+151424X0160Y         S0      
317GND              VIA   -    MD0080PA00X+021521Y+151424X0160Y         S0      
317GND              VIA   -    MD0080PA00X+020576Y+151424X0160Y         S0      
317GND              VIA   -    MD0080PA00X+021660Y+150730X0160Y         S0      
317GND              VIA   -    MD0080PA00X+021188Y+150730X0160Y         S0      
317GND              VIA   -    MD0080PA00X+020715Y+150730X0160Y         S0      
317GND              VIA   -    MD0080PA00X+020243Y+150730X0160Y         S0      
317GND              VIA   -    MD0080PA00X+019130Y+153606X0160Y         S0      
317GND              VIA   -    MD0080PA00X+020075Y+153606X0160Y         S0      
317GND              VIA   -    MD0080PA00X+019603Y+153606X0160Y         S0      
317GND              VIA   -    MD0080PA00X+022605Y+154264X0160Y         S0      
317GND              VIA   -    MD0080PA00X+019158Y+151424X0160Y         S0      
317GND              VIA   -    MD0080PA00X+020103Y+151424X0160Y         S0      
317GND              VIA   -    MD0080PA00X+019631Y+151424X0160Y         S0      
317GND              VIA   -    MD0080PA00X+019770Y+150730X0160Y         S0      
317GND              VIA   -    MD0080PA00X+019298Y+150730X0160Y         S0      
317GND              VIA   -    MD0080PA00X+018825Y+150730X0160Y         S0      
317GND              VIA   -    MD0080PA00X+018686Y+151424X0160Y         S0      
317GND              VIA   -    MD0080PA00X+018569Y+151920X0160Y         S0      
317GND              VIA   -    MD0080PA00X+018295Y+150751X0160Y         S0      
317GND              VIA   -    MD0080PA00X+165274Y+164729X0160Y         S0      
317GND              VIA   -    MD0080PA00X+165274Y+163538X0160Y         S0      
317GND              VIA   -    MD0080PA00X+164671Y+165729X0160Y         S0      
317GND              VIA   -    MD0080PA00X+163891Y+165729X0160Y         S0      
317GND              VIA   -    MD0080PA00X+163465Y+165729X0160Y         S0      
317GND              VIA   -    MD0080PA00X+164495Y+164729X0160Y         S0      
317GND              VIA   -    MD0080PA00X+164067Y+164729X0160Y         S0      
317GND              VIA   -    MD0080PA00X+164495Y+163538X0160Y         S0      
317GND              VIA   -    MD0080PA00X+164067Y+163529X0160Y         S0      
317GND              VIA   -    MD0080PA00X+164671Y+162538X0160Y         S0      
317GND              VIA   -    MD0080PA00X+163892Y+162538X0160Y         S0      
317GND              VIA   -    MD0080PA00X+163465Y+162538X0160Y         S0      
317GND              VIA   -    MD0080PA00X+162685Y+165729X0160Y         S0      
317GND              VIA   -    MD0080PA00X+162259Y+165729X0160Y         S0      
317GND              VIA   -    MD0080PA00X+163289Y+164729X0160Y         S0      
317GND              VIA   -    MD0080PA00X+162083Y+164729X0160Y         S0      
317GND              VIA   -    MD0080PA00X+162861Y+164729X0160Y         S0      
317GND              VIA   -    MD0080PA00X+163289Y+163538X0160Y         S0      
317GND              VIA   -    MD0080PA00X+162083Y+163538X0160Y         S0      
317GND              VIA   -    MD0080PA00X+162861Y+163538X0160Y         S0      
317GND              VIA   -    MD0080PA00X+162685Y+162538X0160Y         S0      
317GND              VIA   -    MD0080PA00X+162259Y+162538X0160Y         S0      
317GND              VIA   -    MD0080PA00X+161053Y+165729X0160Y         S0      
317GND              VIA   -    MD0080PA00X+161479Y+165729X0160Y         S0      
317GND              VIA   -    MD0080PA00X+160877Y+164729X0160Y         S0      
317GND              VIA   -    MD0080PA00X+161655Y+164729X0160Y         S0      
317GND              VIA   -    MD0080PA00X+160449Y+164729X0160Y         S0      
317GND              VIA   -    MD0080PA00X+160877Y+163538X0160Y         S0      
317GND              VIA   -    MD0080PA00X+161655Y+163538X0160Y         S0      
317GND              VIA   -    MD0080PA00X+160449Y+163538X0160Y         S0      
317GND              VIA   -    MD0080PA00X+161479Y+162538X0160Y         S0      
317GND              VIA   -    MD0080PA00X+161053Y+162538X0160Y         S0      
317GND              VIA   -    MD0080PA00X+160273Y+165729X0160Y         S0      
317GND              VIA   -    MD0080PA00X+159847Y+165729X0160Y         S0      
317GND              VIA   -    MD0080PA00X+159067Y+165729X0160Y         S0      
317GND              VIA   -    MD0080PA00X+159671Y+164729X0160Y         S0      
317GND              VIA   -    MD0080PA00X+159243Y+164729X0160Y         S0      
317GND              VIA   -    MD0080PA00X+159671Y+163538X0160Y         S0      
317GND              VIA   -    MD0080PA00X+159243Y+163538X0160Y         S0      
317GND              VIA   -    MD0080PA00X+159847Y+162538X0160Y         S0      
317GND              VIA   -    MD0080PA00X+160273Y+162538X0160Y         S0      
317GND              VIA   -    MD0080PA00X+159067Y+162538X0160Y         S0      
317GND              VIA   -    MD0080PA00X+158641Y+165729X0160Y         S0      
317GND              VIA   -    MD0080PA00X+157861Y+165729X0160Y         S0      
317GND              VIA   -    MD0080PA00X+157435Y+165729X0160Y         S0      
317GND              VIA   -    MD0080PA00X+158465Y+164729X0160Y         S0      
317GND              VIA   -    MD0080PA00X+158037Y+164729X0160Y         S0      
317GND              VIA   -    MD0080PA00X+158465Y+163538X0160Y         S0      
317GND              VIA   -    MD0080PA00X+158037Y+163538X0160Y         S0      
317GND              VIA   -    MD0080PA00X+158641Y+162538X0160Y         S0      
317GND              VIA   -    MD0080PA00X+157861Y+162538X0160Y         S0      
317GND              VIA   -    MD0080PA00X+157435Y+162538X0160Y         S0      
317GND              VIA   -    MD0080PA00X+156655Y+165729X0160Y         S0      
317GND              VIA   -    MD0080PA00X+156229Y+165729X0160Y         S0      
317GND              VIA   -    MD0080PA00X+157259Y+164729X0160Y         S0      
317GND              VIA   -    MD0080PA00X+156053Y+164729X0160Y         S0      
317GND              VIA   -    MD0080PA00X+156831Y+164729X0160Y         S0      
317GND              VIA   -    MD0080PA00X+157259Y+163538X0160Y         S0      
317GND              VIA   -    MD0080PA00X+156053Y+163538X0160Y         S0      
317GND              VIA   -    MD0080PA00X+156831Y+163538X0160Y         S0      
317GND              VIA   -    MD0080PA00X+156655Y+162538X0160Y         S0      
317GND              VIA   -    MD0080PA00X+156229Y+162538X0160Y         S0      
317GND              VIA   -    MD0080PA00X+155023Y+165729X0160Y         S0      
317GND              VIA   -    MD0080PA00X+155449Y+165729X0160Y         S0      
317GND              VIA   -    MD0080PA00X+154847Y+164729X0160Y         S0      
317GND              VIA   -    MD0080PA00X+155625Y+164729X0160Y         S0      
317GND              VIA   -    MD0080PA00X+154419Y+164729X0160Y         S0      
317GND              VIA   -    MD0080PA00X+154847Y+163538X0160Y         S0      
317GND              VIA   -    MD0080PA00X+155625Y+163538X0160Y         S0      
317GND              VIA   -    MD0080PA00X+154419Y+163538X0160Y         S0      
317GND              VIA   -    MD0080PA00X+155449Y+162538X0160Y         S0      
317GND              VIA   -    MD0080PA00X+155023Y+162538X0160Y         S0      
317GND              VIA   -    MD0080PA00X+153817Y+165729X0160Y         S0      
317GND              VIA   -    MD0080PA00X+154243Y+165729X0160Y         S0      
317GND              VIA   -    MD0080PA00X+153037Y+165729X0160Y         S0      
317GND              VIA   -    MD0080PA00X+153641Y+164729X0160Y         S0      
317GND              VIA   -    MD0080PA00X+153213Y+164729X0160Y         S0      
317GND              VIA   -    MD0080PA00X+153641Y+163538X0160Y         S0      
317GND              VIA   -    MD0080PA00X+153213Y+163538X0160Y         S0      
317GND              VIA   -    MD0080PA00X+153817Y+162538X0160Y         S0      
317GND              VIA   -    MD0080PA00X+154243Y+162538X0160Y         S0      
317GND              VIA   -    MD0080PA00X+153037Y+162538X0160Y         S0      
317GND              VIA   -    MD0080PA00X+152611Y+165729X0160Y         S0      
317GND              VIA   -    MD0080PA00X+151405Y+165729X0160Y         S0      
317GND              VIA   -    MD0080PA00X+151831Y+165729X0160Y         S0      
317GND              VIA   -    MD0080PA00X+152435Y+164729X0160Y         S0      
317GND              VIA   -    MD0080PA00X+152007Y+164729X0160Y         S0      
317GND              VIA   -    MD0080PA00X+152435Y+163538X0160Y         S0      
317GND              VIA   -    MD0080PA00X+152007Y+163538X0160Y         S0      
317GND              VIA   -    MD0080PA00X+152611Y+162538X0160Y         S0      
317GND              VIA   -    MD0080PA00X+151831Y+162538X0160Y         S0      
317GND              VIA   -    MD0080PA00X+151405Y+162538X0160Y         S0      
317GND              VIA   -    MD0080PA00X+150625Y+165729X0160Y         S0      
317GND              VIA   -    MD0080PA00X+150199Y+165729X0160Y         S0      
317GND              VIA   -    MD0080PA00X+151229Y+164729X0160Y         S0      
317GND              VIA   -    MD0080PA00X+150023Y+164729X0160Y         S0      
317GND              VIA   -    MD0080PA00X+150801Y+164729X0160Y         S0      
317GND              VIA   -    MD0080PA00X+151229Y+163538X0160Y         S0      
317GND              VIA   -    MD0080PA00X+150023Y+163538X0160Y         S0      
317GND              VIA   -    MD0080PA00X+150801Y+163538X0160Y         S0      
317GND              VIA   -    MD0080PA00X+150625Y+162538X0160Y         S0      
317GND              VIA   -    MD0080PA00X+150199Y+162538X0160Y         S0      
317GND              VIA   -    MD0080PA00X+148993Y+165729X0160Y         S0      
317GND              VIA   -    MD0080PA00X+149419Y+165729X0160Y         S0      
317GND              VIA   -    MD0080PA00X+148817Y+164729X0160Y         S0      
317GND              VIA   -    MD0080PA00X+149595Y+164729X0160Y         S0      
317GND              VIA   -    MD0080PA00X+148817Y+163538X0160Y         S0      
317GND              VIA   -    MD0080PA00X+149595Y+163538X0160Y         S0      
317GND              VIA   -    MD0080PA00X+149419Y+162538X0160Y         S0      
317GND              VIA   -    MD0080PA00X+148993Y+162538X0160Y         S0      
317GND              VIA   -    MD0080PA00X+148213Y+165729X0160Y         S0      
317GND              VIA   -    MD0080PA00X+147787Y+165729X0160Y         S0      
317GND              VIA   -    MD0080PA00X+147007Y+165729X0160Y         S0      
317GND              VIA   -    MD0080PA00X+147611Y+164729X0160Y         S0      
317GND              VIA   -    MD0080PA00X+148389Y+164729X0160Y         S0      
317GND              VIA   -    MD0080PA00X+147183Y+164729X0160Y         S0      
317GND              VIA   -    MD0080PA00X+147611Y+163538X0160Y         S0      
317GND              VIA   -    MD0080PA00X+148389Y+163538X0160Y         S0      
317GND              VIA   -    MD0080PA00X+147183Y+163538X0160Y         S0      
317GND              VIA   -    MD0080PA00X+147787Y+162538X0160Y         S0      
317GND              VIA   -    MD0080PA00X+148213Y+162538X0160Y         S0      
317GND              VIA   -    MD0080PA00X+147007Y+162538X0160Y         S0      
317GND              VIA   -    MD0080PA00X+145801Y+165729X0160Y         S0      
317GND              VIA   -    MD0080PA00X+146581Y+165729X0160Y         S0      
317GND              VIA   -    MD0080PA00X+146405Y+164729X0160Y         S0      
317GND              VIA   -    MD0080PA00X+146405Y+163538X0160Y         S0      
317GND              VIA   -    MD0080PA00X+146581Y+162538X0160Y         S0      
317GND              VIA   -    MD0080PA00X+145801Y+162538X0160Y         S0      
317GND              VIA   -    MD0080PA00X+138254Y+165729X0160Y         S0      
317GND              VIA   -    MD0080PA00X+138857Y+164729X0160Y         S0      
317GND              VIA   -    MD0080PA00X+138078Y+164729X0160Y         S0      
317GND              VIA   -    MD0080PA00X+138078Y+163538X0160Y         S0      
317GND              VIA   -    MD0080PA00X+138857Y+163538X0160Y         S0      
317GND              VIA   -    MD0080PA00X+138254Y+162538X0160Y         S0      
317GND              VIA   -    MD0080PA00X+137474Y+165729X0160Y         S0      
317GND              VIA   -    MD0080PA00X+137048Y+165729X0160Y         S0      
317GND              VIA   -    MD0080PA00X+137650Y+164729X0160Y         S0      
317GND              VIA   -    MD0080PA00X+136872Y+164729X0160Y         S0      
317GND              VIA   -    MD0080PA00X+137650Y+163529X0160Y         S0      
317GND              VIA   -    MD0080PA00X+136872Y+163538X0160Y         S0      
317GND              VIA   -    MD0080PA00X+137474Y+162538X0160Y         S0      
317GND              VIA   -    MD0080PA00X+137048Y+162538X0160Y         S0      
317GND              VIA   -    MD0080PA00X+136268Y+165729X0160Y         S0      
317GND              VIA   -    MD0080PA00X+135062Y+165729X0160Y         S0      
317GND              VIA   -    MD0080PA00X+135842Y+165729X0160Y         S0      
317GND              VIA   -    MD0080PA00X+136444Y+164729X0160Y         S0      
317GND              VIA   -    MD0080PA00X+135238Y+164729X0160Y         S0      
317GND              VIA   -    MD0080PA00X+135666Y+164729X0160Y         S0      
317GND              VIA   -    MD0080PA00X+136444Y+163538X0160Y         S0      
317GND              VIA   -    MD0080PA00X+135666Y+163538X0160Y         S0      
317GND              VIA   -    MD0080PA00X+135238Y+163538X0160Y         S0      
317GND              VIA   -    MD0080PA00X+136268Y+162538X0160Y         S0      
317GND              VIA   -    MD0080PA00X+135842Y+162538X0160Y         S0      
317GND              VIA   -    MD0080PA00X+135062Y+162538X0160Y         S0      
317GND              VIA   -    MD0080PA00X+134636Y+165729X0160Y         S0      
317GND              VIA   -    MD0080PA00X+133856Y+165729X0160Y         S0      
317GND              VIA   -    MD0080PA00X+134460Y+164729X0160Y         S0      
317GND              VIA   -    MD0080PA00X+134032Y+164729X0160Y         S0      
317GND              VIA   -    MD0080PA00X+134460Y+163538X0160Y         S0      
317GND              VIA   -    MD0080PA00X+134032Y+163538X0160Y         S0      
317GND              VIA   -    MD0080PA00X+134636Y+162538X0160Y         S0      
317GND              VIA   -    MD0080PA00X+133856Y+162538X0160Y         S0      
317GND              VIA   -    MD0080PA00X+133430Y+165729X0160Y         S0      
317GND              VIA   -    MD0080PA00X+132650Y+165729X0160Y         S0      
317GND              VIA   -    MD0080PA00X+132224Y+165729X0160Y         S0      
317GND              VIA   -    MD0080PA00X+133254Y+164729X0160Y         S0      
317GND              VIA   -    MD0080PA00X+132048Y+164729X0160Y         S0      
317GND              VIA   -    MD0080PA00X+132826Y+164729X0160Y         S0      
317GND              VIA   -    MD0080PA00X+133254Y+163538X0160Y         S0      
317GND              VIA   -    MD0080PA00X+132826Y+163538X0160Y         S0      
317GND              VIA   -    MD0080PA00X+132048Y+163538X0160Y         S0      
317GND              VIA   -    MD0080PA00X+133430Y+162538X0160Y         S0      
317GND              VIA   -    MD0080PA00X+132224Y+162538X0160Y         S0      
317GND              VIA   -    MD0080PA00X+132650Y+162538X0160Y         S0      
317GND              VIA   -    MD0080PA00X+131444Y+165729X0160Y         S0      
317GND              VIA   -    MD0080PA00X+131018Y+165729X0160Y         S0      
317GND              VIA   -    MD0080PA00X+131620Y+164729X0160Y         S0      
317GND              VIA   -    MD0080PA00X+130842Y+164729X0160Y         S0      
317GND              VIA   -    MD0080PA00X+131620Y+163538X0160Y         S0      
317GND              VIA   -    MD0080PA00X+130842Y+163538X0160Y         S0      
317GND              VIA   -    MD0080PA00X+131444Y+162538X0160Y         S0      
317GND              VIA   -    MD0080PA00X+131018Y+162538X0160Y         S0      
317GND              VIA   -    MD0080PA00X+130238Y+165729X0160Y         S0      
317GND              VIA   -    MD0080PA00X+129032Y+165729X0160Y         S0      
317GND              VIA   -    MD0080PA00X+129812Y+165729X0160Y         S0      
317GND              VIA   -    MD0080PA00X+130414Y+164729X0160Y         S0      
317GND              VIA   -    MD0080PA00X+129208Y+164729X0160Y         S0      
317GND              VIA   -    MD0080PA00X+129636Y+164729X0160Y         S0      
317GND              VIA   -    MD0080PA00X+130414Y+163538X0160Y         S0      
317GND              VIA   -    MD0080PA00X+129636Y+163538X0160Y         S0      
317GND              VIA   -    MD0080PA00X+129208Y+163538X0160Y         S0      
317GND              VIA   -    MD0080PA00X+130238Y+162538X0160Y         S0      
317GND              VIA   -    MD0080PA00X+129032Y+162538X0160Y         S0      
317GND              VIA   -    MD0080PA00X+129812Y+162538X0160Y         S0      
317GND              VIA   -    MD0080PA00X+128606Y+165729X0160Y         S0      
317GND              VIA   -    MD0080PA00X+127826Y+165729X0160Y         S0      
317GND              VIA   -    MD0080PA00X+128430Y+164729X0160Y         S0      
317GND              VIA   -    MD0080PA00X+128002Y+164729X0160Y         S0      
317GND              VIA   -    MD0080PA00X+128430Y+163538X0160Y         S0      
317GND              VIA   -    MD0080PA00X+128002Y+163538X0160Y         S0      
317GND              VIA   -    MD0080PA00X+128606Y+162538X0160Y         S0      
317GND              VIA   -    MD0080PA00X+042343Y+090832X0160Y    R180 S0      
317GND              VIA   -    MD0080PA00X+127826Y+162538X0160Y         S0      
317GND              VIA   -    MD0080PA00X+127400Y+165729X0160Y         S0      
317GND              VIA   -    MD0080PA00X+126194Y+165729X0160Y         S0      
317GND              VIA   -    MD0080PA00X+126620Y+165729X0160Y         S0      
317GND              VIA   -    MD0080PA00X+127224Y+164729X0160Y         S0      
317GND              VIA   -    MD0080PA00X+126796Y+164729X0160Y         S0      
317GND              VIA   -    MD0080PA00X+127224Y+163538X0160Y         S0      
317GND              VIA   -    MD0080PA00X+126796Y+163538X0160Y         S0      
317GND              VIA   -    MD0080PA00X+127400Y+162538X0160Y         S0      
317GND              VIA   -    MD0080PA00X+126194Y+162538X0160Y         S0      
317GND              VIA   -    MD0080PA00X+126620Y+162538X0160Y         S0      
317GND              VIA   -    MD0080PA00X+124988Y+165729X0160Y         S0      
317GND              VIA   -    MD0080PA00X+125414Y+165729X0160Y         S0      
317GND              VIA   -    MD0080PA00X+126018Y+164729X0160Y         S0      
317GND              VIA   -    MD0080PA00X+125590Y+164729X0160Y         S0      
317GND              VIA   -    MD0080PA00X+124812Y+164729X0160Y         S0      
317GND              VIA   -    MD0080PA00X+126018Y+163538X0160Y         S0      
317GND              VIA   -    MD0080PA00X+125590Y+163538X0160Y         S0      
317GND              VIA   -    MD0080PA00X+124812Y+163538X0160Y         S0      
317GND              VIA   -    MD0080PA00X+125414Y+162538X0160Y         S0      
317GND              VIA   -    MD0080PA00X+124988Y+162538X0160Y         S0      
317GND              VIA   -    MD0080PA00X+124208Y+165729X0160Y         S0      
317GND              VIA   -    MD0080PA00X+123782Y+165729X0160Y         S0      
317GND              VIA   -    MD0080PA00X+124384Y+164729X0160Y         S0      
317GND              VIA   -    MD0080PA00X+123178Y+164729X0160Y         S0      
317GND              VIA   -    MD0080PA00X+123606Y+164729X0160Y         S0      
317GND              VIA   -    MD0080PA00X+124384Y+163538X0160Y         S0      
317GND              VIA   -    MD0080PA00X+123606Y+163538X0160Y         S0      
317GND              VIA   -    MD0080PA00X+123178Y+163538X0160Y         S0      
317GND              VIA   -    MD0080PA00X+124208Y+162538X0160Y         S0      
317GND              VIA   -    MD0080PA00X+123782Y+162538X0160Y         S0      
317GND              VIA   -    MD0080PA00X+122576Y+165729X0160Y         S0      
317GND              VIA   -    MD0080PA00X+123002Y+165729X0160Y         S0      
317GND              VIA   -    MD0080PA00X+121796Y+165729X0160Y         S0      
317GND              VIA   -    MD0080PA00X+121972Y+164729X0160Y         S0      
317GND              VIA   -    MD0080PA00X+122400Y+164729X0160Y         S0      
317GND              VIA   -    MD0080PA00X+121972Y+163538X0160Y         S0      
317GND              VIA   -    MD0080PA00X+122400Y+163538X0160Y         S0      
317GND              VIA   -    MD0080PA00X+123002Y+162538X0160Y         S0      
317GND              VIA   -    MD0080PA00X+122576Y+162538X0160Y         S0      
317GND              VIA   -    MD0080PA00X+121796Y+162538X0160Y         S0      
317GND              VIA   -    MD0080PA00X+121370Y+165729X0160Y         S0      
317GND              VIA   -    MD0080PA00X+120590Y+165729X0160Y         S0      
317GND              VIA   -    MD0080PA00X+120164Y+165729X0160Y         S0      
317GND              VIA   -    MD0080PA00X+121194Y+164729X0160Y         S0      
317GND              VIA   -    MD0080PA00X+120766Y+164729X0160Y         S0      
317GND              VIA   -    MD0080PA00X+121194Y+163538X0160Y         S0      
317GND              VIA   -    MD0080PA00X+120766Y+163538X0160Y         S0      
317GND              VIA   -    MD0080PA00X+121370Y+162538X0160Y         S0      
317GND              VIA   -    MD0080PA00X+120164Y+162538X0160Y         S0      
317GND              VIA   -    MD0080PA00X+120590Y+162538X0160Y         S0      
317GND              VIA   -    MD0080PA00X+119384Y+165729X0160Y         S0      
317GND              VIA   -    MD0080PA00X+119988Y+164729X0160Y         S0      
317GND              VIA   -    MD0080PA00X+119988Y+163538X0160Y         S0      
317GND              VIA   -    MD0080PA00X+119384Y+162538X0160Y         S0      
317GND              VIA   -    MD0080PA00X+063708Y+161429X0160Y         S0      
317GND              VIA   -    MD0080PA00X+063884Y+162429X0160Y         S0      
317GND              VIA   -    MD0080PA00X+064487Y+161429X0160Y         S0      
317GND              VIA   -    MD0080PA00X+063708Y+160238X0160Y         S0      
317GND              VIA   -    MD0080PA00X+064487Y+160238X0160Y         S0      
317GND              VIA   -    MD0080PA00X+063884Y+159238X0160Y         S0      
317GND              VIA   -    MD0080PA00X+062502Y+161429X0160Y         S0      
317GND              VIA   -    MD0080PA00X+062074Y+161429X0160Y         S0      
317GND              VIA   -    MD0080PA00X+062678Y+162429X0160Y         S0      
317GND              VIA   -    MD0080PA00X+063280Y+161429X0160Y         S0      
317GND              VIA   -    MD0080PA00X+063104Y+162429X0160Y         S0      
317GND              VIA   -    MD0080PA00X+062502Y+160238X0160Y         S0      
317GND              VIA   -    MD0080PA00X+062074Y+160238X0160Y         S0      
317GND              VIA   -    MD0080PA00X+063280Y+160229X0160Y         S0      
317GND              VIA   -    MD0080PA00X+062678Y+159238X0160Y         S0      
317GND              VIA   -    MD0080PA00X+063104Y+159238X0160Y         S0      
317GND              VIA   -    MD0080PA00X+061296Y+161429X0160Y         S0      
317GND              VIA   -    MD0080PA00X+061472Y+162429X0160Y         S0      
317GND              VIA   -    MD0080PA00X+060692Y+162429X0160Y         S0      
317GND              VIA   -    MD0080PA00X+060868Y+161429X0160Y         S0      
317GND              VIA   -    MD0080PA00X+061898Y+162429X0160Y         S0      
317GND              VIA   -    MD0080PA00X+061296Y+160238X0160Y         S0      
317GND              VIA   -    MD0080PA00X+060868Y+160238X0160Y         S0      
317GND              VIA   -    MD0080PA00X+060692Y+159238X0160Y         S0      
317GND              VIA   -    MD0080PA00X+061472Y+159238X0160Y         S0      
317GND              VIA   -    MD0080PA00X+061898Y+159238X0160Y         S0      
317GND              VIA   -    MD0080PA00X+060090Y+161429X0160Y         S0      
317GND              VIA   -    MD0080PA00X+059060Y+162429X0160Y         S0      
317GND              VIA   -    MD0080PA00X+059486Y+162429X0160Y         S0      
317GND              VIA   -    MD0080PA00X+059662Y+161429X0160Y         S0      
317GND              VIA   -    MD0080PA00X+060266Y+162429X0160Y         S0      
317GND              VIA   -    MD0080PA00X+060090Y+160238X0160Y         S0      
317GND              VIA   -    MD0080PA00X+059662Y+160238X0160Y         S0      
317GND              VIA   -    MD0080PA00X+059486Y+159238X0160Y         S0      
317GND              VIA   -    MD0080PA00X+059060Y+159238X0160Y         S0      
317GND              VIA   -    MD0080PA00X+060266Y+159238X0160Y         S0      
317GND              VIA   -    MD0080PA00X+057678Y+161429X0160Y         S0      
317GND              VIA   -    MD0080PA00X+058884Y+161429X0160Y         S0      
317GND              VIA   -    MD0080PA00X+057854Y+162429X0160Y         S0      
317GND              VIA   -    MD0080PA00X+058280Y+162429X0160Y         S0      
317GND              VIA   -    MD0080PA00X+058456Y+161429X0160Y         S0      
317GND              VIA   -    MD0080PA00X+057678Y+160238X0160Y         S0      
317GND              VIA   -    MD0080PA00X+058884Y+160238X0160Y         S0      
317GND              VIA   -    MD0080PA00X+058456Y+160238X0160Y         S0      
317GND              VIA   -    MD0080PA00X+058280Y+159238X0160Y         S0      
317GND              VIA   -    MD0080PA00X+057854Y+159238X0160Y         S0      
317GND              VIA   -    MD0080PA00X+056472Y+161429X0160Y         S0      
317GND              VIA   -    MD0080PA00X+056648Y+162429X0160Y         S0      
317GND              VIA   -    MD0080PA00X+056044Y+161429X0160Y         S0      
317GND              VIA   -    MD0080PA00X+057074Y+162429X0160Y         S0      
317GND              VIA   -    MD0080PA00X+057250Y+161429X0160Y         S0      
317GND              VIA   -    MD0080PA00X+056472Y+160238X0160Y         S0      
317GND              VIA   -    MD0080PA00X+056044Y+160238X0160Y         S0      
317GND              VIA   -    MD0080PA00X+057250Y+160238X0160Y         S0      
317GND              VIA   -    MD0080PA00X+056648Y+159238X0160Y         S0      
317GND              VIA   -    MD0080PA00X+057074Y+159238X0160Y         S0      
317GND              VIA   -    MD0080PA00X+055266Y+161429X0160Y         S0      
317GND              VIA   -    MD0080PA00X+055442Y+162429X0160Y         S0      
317GND              VIA   -    MD0080PA00X+054662Y+162429X0160Y         S0      
317GND              VIA   -    MD0080PA00X+054838Y+161429X0160Y         S0      
317GND              VIA   -    MD0080PA00X+055868Y+162429X0160Y         S0      
317GND              VIA   -    MD0080PA00X+055266Y+160238X0160Y         S0      
317GND              VIA   -    MD0080PA00X+054838Y+160238X0160Y         S0      
317GND              VIA   -    MD0080PA00X+055442Y+159238X0160Y         S0      
317GND              VIA   -    MD0080PA00X+054662Y+159238X0160Y         S0      
317GND              VIA   -    MD0080PA00X+055868Y+159238X0160Y         S0      
317GND              VIA   -    MD0080PA00X+054060Y+161429X0160Y         S0      
317GND              VIA   -    MD0080PA00X+053456Y+162429X0160Y         S0      
317GND              VIA   -    MD0080PA00X+053030Y+162429X0160Y         S0      
317GND              VIA   -    MD0080PA00X+053632Y+161429X0160Y         S0      
317GND              VIA   -    MD0080PA00X+054236Y+162429X0160Y         S0      
317GND              VIA   -    MD0080PA00X+054060Y+160238X0160Y         S0      
317GND              VIA   -    MD0080PA00X+053632Y+160238X0160Y         S0      
317GND              VIA   -    MD0080PA00X+053456Y+159238X0160Y         S0      
317GND              VIA   -    MD0080PA00X+053030Y+159238X0160Y         S0      
317GND              VIA   -    MD0080PA00X+054236Y+159238X0160Y         S0      
317GND              VIA   -    MD0080PA00X+051648Y+161429X0160Y         S0      
317GND              VIA   -    MD0080PA00X+052854Y+161429X0160Y         S0      
317GND              VIA   -    MD0080PA00X+052250Y+162429X0160Y         S0      
317GND              VIA   -    MD0080PA00X+051824Y+162429X0160Y         S0      
317GND              VIA   -    MD0080PA00X+052426Y+161429X0160Y         S0      
317GND              VIA   -    MD0080PA00X+051648Y+160238X0160Y         S0      
317GND              VIA   -    MD0080PA00X+052854Y+160238X0160Y         S0      
317GND              VIA   -    MD0080PA00X+052426Y+160238X0160Y         S0      
317GND              VIA   -    MD0080PA00X+052250Y+159238X0160Y         S0      
317GND              VIA   -    MD0080PA00X+051824Y+159238X0160Y         S0      
317GND              VIA   -    MD0080PA00X+050442Y+161429X0160Y         S0      
317GND              VIA   -    MD0080PA00X+051044Y+162429X0160Y         S0      
317GND              VIA   -    MD0080PA00X+050618Y+162429X0160Y         S0      
317GND              VIA   -    MD0080PA00X+050014Y+161429X0160Y         S0      
317GND              VIA   -    MD0080PA00X+051220Y+161429X0160Y         S0      
317GND              VIA   -    MD0080PA00X+050442Y+160238X0160Y         S0      
317GND              VIA   -    MD0080PA00X+050014Y+160238X0160Y         S0      
317GND              VIA   -    MD0080PA00X+051220Y+160238X0160Y         S0      
317GND              VIA   -    MD0080PA00X+050618Y+159238X0160Y         S0      
317GND              VIA   -    MD0080PA00X+051044Y+159238X0160Y         S0      
317GND              VIA   -    MD0080PA00X+049236Y+161429X0160Y         S0      
317GND              VIA   -    MD0080PA00X+049412Y+162429X0160Y         S0      
317GND              VIA   -    MD0080PA00X+048632Y+162429X0160Y         S0      
317GND              VIA   -    MD0080PA00X+048808Y+161429X0160Y         S0      
317GND              VIA   -    MD0080PA00X+049838Y+162429X0160Y         S0      
317GND              VIA   -    MD0080PA00X+049236Y+160238X0160Y         S0      
317GND              VIA   -    MD0080PA00X+048808Y+160238X0160Y         S0      
317GND              VIA   -    MD0080PA00X+049412Y+159238X0160Y         S0      
317GND              VIA   -    MD0080PA00X+048632Y+159238X0160Y         S0      
317GND              VIA   -    MD0080PA00X+049838Y+159238X0160Y         S0      
317GND              VIA   -    MD0080PA00X+048030Y+161429X0160Y         S0      
317GND              VIA   -    MD0080PA00X+047426Y+162429X0160Y         S0      
317GND              VIA   -    MD0080PA00X+047602Y+161429X0160Y         S0      
317GND              VIA   -    MD0080PA00X+048206Y+162429X0160Y         S0      
317GND              VIA   -    MD0080PA00X+048030Y+160238X0160Y         S0      
317GND              VIA   -    MD0080PA00X+047602Y+160238X0160Y         S0      
317GND              VIA   -    MD0080PA00X+047426Y+159238X0160Y         S0      
317GND              VIA   -    MD0080PA00X+048206Y+159238X0160Y         S0      
317GND              VIA   -    MD0080PA00X+046220Y+162429X0160Y         S0      
317GND              VIA   -    MD0080PA00X+047000Y+162429X0160Y         S0      
317GND              VIA   -    MD0080PA00X+046824Y+161429X0160Y         S0      
317GND              VIA   -    MD0080PA00X+045618Y+161429X0160Y         S0      
317GND              VIA   -    MD0080PA00X+046396Y+161429X0160Y         S0      
317GND              VIA   -    MD0080PA00X+046824Y+160238X0160Y         S0      
317GND              VIA   -    MD0080PA00X+045618Y+160238X0160Y         S0      
317GND              VIA   -    MD0080PA00X+046396Y+160238X0160Y         S0      
317GND              VIA   -    MD0080PA00X+046220Y+159238X0160Y         S0      
317GND              VIA   -    MD0080PA00X+045794Y+159238X0160Y         S0      
317GND              VIA   -    MD0080PA00X+047000Y+159238X0160Y         S0      
317GND              VIA   -    MD0080PA00X+045014Y+162429X0160Y         S0      
317GND              VIA   -    MD0080PA00X+045014Y+159238X0160Y         S0      
317GND              VIA   -    MD0080PA00X+036687Y+162429X0160Y         S0      
317GND              VIA   -    MD0080PA00X+036863Y+161429X0160Y         S0      
317GND              VIA   -    MD0080PA00X+037291Y+161429X0160Y         S0      
317GND              VIA   -    MD0080PA00X+038070Y+161429X0160Y         S0      
317GND              VIA   -    MD0080PA00X+037467Y+162429X0160Y         S0      
317GND              VIA   -    MD0080PA00X+037291Y+160238X0160Y         S0      
317GND              VIA   -    MD0080PA00X+036863Y+160229X0160Y         S0      
317GND              VIA   -    MD0080PA00X+038070Y+160238X0160Y         S0      
317GND              VIA   -    MD0080PA00X+036687Y+159238X0160Y         S0      
317GND              VIA   -    MD0080PA00X+037467Y+159238X0160Y         S0      
317GND              VIA   -    MD0080PA00X+036261Y+162429X0160Y         S0      
317GND              VIA   -    MD0080PA00X+035657Y+161429X0160Y         S0      
317GND              VIA   -    MD0080PA00X+036085Y+161429X0160Y         S0      
317GND              VIA   -    MD0080PA00X+035481Y+162429X0160Y         S0      
317GND              VIA   -    MD0080PA00X+036085Y+160238X0160Y         S0      
317GND              VIA   -    MD0080PA00X+035657Y+160238X0160Y         S0      
317GND              VIA   -    MD0080PA00X+035481Y+159238X0160Y         S0      
317GND              VIA   -    MD0080PA00X+036261Y+159238X0160Y         S0      
317GND              VIA   -    MD0080PA00X+033673Y+161429X0160Y         S0      
317GND              VIA   -    MD0080PA00X+034451Y+161429X0160Y         S0      
317GND              VIA   -    MD0080PA00X+034879Y+161429X0160Y         S0      
317GND              VIA   -    MD0080PA00X+033849Y+162429X0160Y         S0      
317GND              VIA   -    MD0080PA00X+034275Y+162429X0160Y         S0      
317GND              VIA   -    MD0080PA00X+035055Y+162429X0160Y         S0      
317GND              VIA   -    MD0080PA00X+034879Y+160238X0160Y         S0      
317GND              VIA   -    MD0080PA00X+034451Y+160238X0160Y         S0      
317GND              VIA   -    MD0080PA00X+033673Y+160238X0160Y         S0      
317GND              VIA   -    MD0080PA00X+035055Y+159238X0160Y         S0      
317GND              VIA   -    MD0080PA00X+034275Y+159238X0160Y         S0      
317GND              VIA   -    MD0080PA00X+033849Y+159238X0160Y         S0      
317GND              VIA   -    MD0080PA00X+032467Y+161429X0160Y         S0      
317GND              VIA   -    MD0080PA00X+033245Y+161429X0160Y         S0      
317GND              VIA   -    MD0080PA00X+033069Y+162429X0160Y         S0      
317GND              VIA   -    MD0080PA00X+032643Y+162429X0160Y         S0      
317GND              VIA   -    MD0080PA00X+033245Y+160238X0160Y         S0      
317GND              VIA   -    MD0080PA00X+032467Y+160238X0160Y         S0      
317GND              VIA   -    MD0080PA00X+032643Y+159238X0160Y         S0      
317GND              VIA   -    MD0080PA00X+033069Y+159238X0160Y         S0      
317GND              VIA   -    MD0080PA00X+030833Y+161429X0160Y         S0      
317GND              VIA   -    MD0080PA00X+031261Y+161429X0160Y         S0      
317GND              VIA   -    MD0080PA00X+032039Y+161429X0160Y         S0      
317GND              VIA   -    MD0080PA00X+030657Y+162429X0160Y         S0      
317GND              VIA   -    MD0080PA00X+031863Y+162429X0160Y         S0      
317GND              VIA   -    MD0080PA00X+031437Y+162429X0160Y         S0      
317GND              VIA   -    MD0080PA00X+032039Y+160238X0160Y         S0      
317GND              VIA   -    MD0080PA00X+031261Y+160238X0160Y         S0      
317GND              VIA   -    MD0080PA00X+030833Y+160238X0160Y         S0      
317GND              VIA   -    MD0080PA00X+031437Y+159238X0160Y         S0      
317GND              VIA   -    MD0080PA00X+030657Y+159238X0160Y         S0      
317GND              VIA   -    MD0080PA00X+031863Y+159238X0160Y         S0      
317GND              VIA   -    MD0080PA00X+029627Y+161429X0160Y         S0      
317GND              VIA   -    MD0080PA00X+030055Y+161429X0160Y         S0      
317GND              VIA   -    MD0080PA00X+029452Y+162429X0160Y         S0      
317GND              VIA   -    MD0080PA00X+030231Y+162429X0160Y         S0      
317GND              VIA   -    MD0080PA00X+030055Y+160238X0160Y         S0      
317GND              VIA   -    MD0080PA00X+029627Y+160238X0160Y         S0      
317GND              VIA   -    MD0080PA00X+029451Y+159238X0160Y         S0      
317GND              VIA   -    MD0080PA00X+030231Y+159238X0160Y         S0      
317GND              VIA   -    MD0080PA00X+027643Y+161429X0160Y         S0      
317GND              VIA   -    MD0080PA00X+028421Y+161429X0160Y         S0      
317GND              VIA   -    MD0080PA00X+028849Y+161429X0160Y         S0      
317GND              VIA   -    MD0080PA00X+027819Y+162429X0160Y         S0      
317GND              VIA   -    MD0080PA00X+028245Y+162429X0160Y         S0      
317GND              VIA   -    MD0080PA00X+029024Y+162429X0160Y         S0      
317GND              VIA   -    MD0080PA00X+028849Y+160238X0160Y         S0      
317GND              VIA   -    MD0080PA00X+028421Y+160238X0160Y         S0      
317GND              VIA   -    MD0080PA00X+027643Y+160238X0160Y         S0      
317GND              VIA   -    MD0080PA00X+028245Y+159238X0160Y         S0      
317GND              VIA   -    MD0080PA00X+027819Y+159238X0160Y         S0      
317GND              VIA   -    MD0080PA00X+029025Y+159238X0160Y         S0      
317GND              VIA   -    MD0080PA00X+026437Y+161429X0160Y         S0      
317GND              VIA   -    MD0080PA00X+027215Y+161429X0160Y         S0      
317GND              VIA   -    MD0080PA00X+026613Y+162429X0160Y         S0      
317GND              VIA   -    MD0080PA00X+027039Y+162429X0160Y         S0      
317GND              VIA   -    MD0080PA00X+027215Y+160238X0160Y         S0      
317GND              VIA   -    MD0080PA00X+026437Y+160238X0160Y         S0      
317GND              VIA   -    MD0080PA00X+026613Y+159238X0160Y         S0      
317GND              VIA   -    MD0080PA00X+027039Y+159238X0160Y         S0      
317GND              VIA   -    MD0080PA00X+026009Y+161429X0160Y         S0      
317GND              VIA   -    MD0080PA00X+025231Y+161429X0160Y         S0      
317GND              VIA   -    MD0080PA00X+024803Y+161429X0160Y         S0      
317GND              VIA   -    MD0080PA00X+025407Y+162429X0160Y         S0      
317GND              VIA   -    MD0080PA00X+025833Y+162429X0160Y         S0      
317GND              VIA   -    MD0080PA00X+026009Y+160238X0160Y         S0      
317GND              VIA   -    MD0080PA00X+025231Y+160238X0160Y         S0      
317GND              VIA   -    MD0080PA00X+024803Y+160238X0160Y         S0      
317GND              VIA   -    MD0080PA00X+025407Y+159238X0160Y         S0      
317GND              VIA   -    MD0080PA00X+025833Y+159238X0160Y         S0      
317GND              VIA   -    MD0080PA00X+023597Y+161429X0160Y         S0      
317GND              VIA   -    MD0080PA00X+024025Y+161429X0160Y         S0      
317GND              VIA   -    MD0080PA00X+023421Y+162429X0160Y         S0      
317GND              VIA   -    MD0080PA00X+024201Y+162429X0160Y         S0      
317GND              VIA   -    MD0080PA00X+024627Y+162429X0160Y         S0      
317GND              VIA   -    MD0080PA00X+024025Y+160238X0160Y         S0      
317GND              VIA   -    MD0080PA00X+023597Y+160238X0160Y         S0      
317GND              VIA   -    MD0080PA00X+024627Y+159238X0160Y         S0      
317GND              VIA   -    MD0080PA00X+023421Y+159238X0160Y         S0      
317GND              VIA   -    MD0080PA00X+024201Y+159238X0160Y         S0      
317GND              VIA   -    MD0080PA00X+022391Y+161429X0160Y         S0      
317GND              VIA   -    MD0080PA00X+022819Y+161429X0160Y         S0      
317GND              VIA   -    MD0080PA00X+021789Y+162429X0160Y         S0      
317GND              VIA   -    MD0080PA00X+022215Y+162429X0160Y         S0      
317GND              VIA   -    MD0080PA00X+022995Y+162429X0160Y         S0      
317GND              VIA   -    MD0080PA00X+022819Y+160238X0160Y         S0      
317GND              VIA   -    MD0080PA00X+022391Y+160238X0160Y         S0      
317GND              VIA   -    MD0080PA00X+022215Y+159238X0160Y         S0      
317GND              VIA   -    MD0080PA00X+021789Y+159238X0160Y         S0      
317GND              VIA   -    MD0080PA00X+022995Y+159238X0160Y         S0      
317GND              VIA   -    MD0080PA00X+020407Y+161429X0160Y         S0      
317GND              VIA   -    MD0080PA00X+021185Y+161429X0160Y         S0      
317GND              VIA   -    MD0080PA00X+021613Y+161429X0160Y         S0      
317GND              VIA   -    MD0080PA00X+021009Y+162429X0160Y         S0      
317GND              VIA   -    MD0080PA00X+020583Y+162429X0160Y         S0      
317GND              VIA   -    MD0080PA00X+021185Y+160238X0160Y         S0      
317GND              VIA   -    MD0080PA00X+020407Y+160238X0160Y         S0      
317GND              VIA   -    MD0080PA00X+021613Y+160238X0160Y         S0      
317GND              VIA   -    MD0080PA00X+020583Y+159238X0160Y         S0      
317GND              VIA   -    MD0080PA00X+021009Y+159238X0160Y         S0      
317GND              VIA   -    MD0080PA00X+019201Y+161429X0160Y         S0      
317GND              VIA   -    MD0080PA00X+019979Y+161429X0160Y         S0      
317GND              VIA   -    MD0080PA00X+019803Y+162429X0160Y         S0      
317GND              VIA   -    MD0080PA00X+019377Y+162429X0160Y         S0      
317GND              VIA   -    MD0080PA00X+019979Y+160238X0160Y         S0      
317GND              VIA   -    MD0080PA00X+019201Y+160238X0160Y         S0      
317GND              VIA   -    MD0080PA00X+019377Y+159238X0160Y         S0      
317GND              VIA   -    MD0080PA00X+019803Y+159238X0160Y         S0      
317GND              VIA   -    MD0080PA00X+018597Y+162429X0160Y         S0      
317GND              VIA   -    MD0080PA00X+018597Y+159238X0160Y         S0      
317GND              VIA   -    MD0080PA00X+054671Y+113010X0160Y         S0      
317GND              VIA   -    MD0080PA00X+045789Y+113010X0160Y         S0      
317GND              VIA   -    MD0080PA00X+143285Y+090832X0160Y    R180 S0      
317GND              VIA   -    MD0080PA00X+037752Y+122227X0160Y         S0      
317GND              VIA   -    MD0080PA00X+148955Y+113010X0160Y         S0      
317GND              VIA   -    MD0080PA00X+143404Y+113010X0160Y         S0      
317GND              VIA   -    MD0080PA00X+150250Y+113329X0160Y         S0      
317GND              VIA   -    MD0080PA00X+042461Y+113010X0160Y         S0      
317GND              VIA   -    MD0080PA00X+045794Y+162429X0160Y         S0      
317GND              VIA   -    MD0080PA00X+035311Y+090832X0160Y    R180 S0      
317GND              VIA   -    MD0080PA00X+030359Y+115138X0160Y    R180 S0      
317GND              VIA   -    MD0080PA00X+030359Y+115776X0160Y    R180 S0      
317GND              VIA   -    MD0080PA00X+030359Y+114500X0160Y    R180 S0      
317GND              VIA   -    MD0080PA00X+030359Y+113862X0160Y    R180 S0      
317GND              VIA   -    MD0080PA00X+030359Y+113225X0160Y    R180 S0      
317GND              VIA   -    MD0080PA00X+030359Y+112587X0160Y    R180 S0      
317GND              VIA   -    MD0080PA00X+030359Y+111949X0160Y    R180 S0      
317GND              VIA   -    MD0080PA00X+030359Y+111311X0160Y    R180 S0      
317GND              VIA   -    MD0080PA00X+030359Y+110673X0160Y    R180 S0      
317GND              VIA   -    MD0080PA00X+030359Y+110036X0160Y    R180 S0      
317GND              VIA   -    MD0080PA00X+030359Y+109398X0160Y    R180 S0      
317GND              VIA   -    MD0080PA00X+030359Y+108760X0160Y    R180 S0      
317GND              VIA   -    MD0080PA00X+030359Y+108122X0160Y    R180 S0      
317GND              VIA   -    MD0080PA00X+030359Y+106847X0160Y    R180 S0      
317GND              VIA   -    MD0080PA00X+030359Y+107484X0160Y    R180 S0      
317GND              VIA   -    MD0080PA00X+030359Y+106209X0160Y    R180 S0      
317GND              VIA   -    MD0080PA00X+030359Y+104933X0160Y    R180 S0      
317GND              VIA   -    MD0080PA00X+030359Y+105571X0160Y    R180 S0      
317GND              VIA   -    MD0080PA00X+030359Y+104295X0160Y    R180 S0      
317GND              VIA   -    MD0080PA00X+030359Y+103658X0160Y    R180 S0      
317GND              VIA   -    MD0080PA00X+030359Y+103020X0160Y    R180 S0      
317GND              VIA   -    MD0080PA00X+030241Y+100185X0160Y    R180 S0      
317GND              VIA   -    MD0080PA00X+030241Y+100823X0160Y    R180 S0      
317GND              VIA   -    MD0080PA00X+030241Y+099547X0160Y    R180 S0      
317GND              VIA   -    MD0080PA00X+030241Y+098910X0160Y    R180 S0      
317GND              VIA   -    MD0080PA00X+030241Y+098272X0160Y    R180 S0      
317GND              VIA   -    MD0080PA00X+030241Y+097634X0160Y    R180 S0      
317GND              VIA   -    MD0080PA00X+030241Y+096996X0160Y    R180 S0      
317GND              VIA   -    MD0080PA00X+030241Y+096358X0160Y    R180 S0      
317GND              VIA   -    MD0080PA00X+030241Y+095721X0160Y    R180 S0      
317GND              VIA   -    MD0080PA00X+030241Y+095083X0160Y    R180 S0      
317GND              VIA   -    MD0080PA00X+030241Y+094445X0160Y    R180 S0      
317GND              VIA   -    MD0080PA00X+030241Y+093807X0160Y    R180 S0      
317GND              VIA   -    MD0080PA00X+030241Y+093169X0160Y    R180 S0      
317GND              VIA   -    MD0080PA00X+030241Y+092532X0160Y    R180 S0      
317GND              VIA   -    MD0080PA00X+030241Y+091894X0160Y    R180 S0      
317GND              VIA   -    MD0080PA00X+030241Y+091256X0160Y    R180 S0      
317GND              VIA   -    MD0080PA00X+030241Y+090618X0160Y    R180 S0      
317GND              VIA   -    MD0080PA00X+030315Y+089876X0160Y    R180 S0      
317GND              VIA   -    MD0080PA00X+030315Y+089238X0160Y    R180 S0      
317GND              VIA   -    MD0080PA00X+030500Y+088281X0160Y    R180 S0      
317GND              VIA   -    MD0080PA00X+030315Y+088600X0160Y    R180 S0      
317GND              VIA   -    MD0080PA00X+030315Y+087962X0160Y    R180 S0      
317GND              VIA   -    MD0080PA00X+030870Y+088281X0160Y    R180 S0      
317GND              VIA   -    MD0080PA00X+031426Y+087325X0160Y    R180 S0      
317GND              VIA   -    MD0080PA00X+031981Y+087644X0160Y    R180 S0      
317GND              VIA   -    MD0080PA00X+031056Y+087962X0160Y    R180 S0      
317GND              VIA   -    MD0080PA00X+031796Y+087962X0160Y    R180 S0      
317GND              VIA   -    MD0080PA00X+031056Y+087325X0160Y    R180 S0      
317GND              VIA   -    MD0080PA00X+030870Y+094021X0160Y    R180 S0      
317GND              VIA   -    MD0080PA00X+031426Y+093702X0160Y    R180 S0      
317GND              VIA   -    MD0080PA00X+031426Y+093065X0160Y    R180 S0      
317GND              VIA   -    MD0080PA00X+030870Y+093384X0160Y    R180 S0      
317GND              VIA   -    MD0080PA00X+031611Y+092746X0160Y    R180 S0      
317GND              VIA   -    MD0080PA00X+030870Y+092746X0160Y    R180 S0      
317GND              VIA   -    MD0080PA00X+031611Y+092108X0160Y    R180 S0      
317GND              VIA   -    MD0080PA00X+030870Y+092108X0160Y    R180 S0      
317GND              VIA   -    MD0080PA00X+030870Y+091470X0160Y    R180 S0      
317GND              VIA   -    MD0080PA00X+031426Y+091789X0160Y    R180 S0      
317GND              VIA   -    MD0080PA00X+031611Y+090832X0160Y    R180 S0      
317GND              VIA   -    MD0080PA00X+031426Y+091151X0160Y    R180 S0      
317GND              VIA   -    MD0080PA00X+030870Y+090832X0160Y    R180 S0      
317GND              VIA   -    MD0080PA00X+030870Y+090195X0160Y    R180 S0      
317GND              VIA   -    MD0080PA00X+031611Y+090195X0160Y    R180 S0      
317GND              VIA   -    MD0080PA00X+031426Y+089876X0160Y    R180 S0      
317GND              VIA   -    MD0080PA00X+030870Y+089557X0160Y    R180 S0      
317GND              VIA   -    MD0080PA00X+031426Y+089238X0160Y    R180 S0      
317GND              VIA   -    MD0080PA00X+031981Y+088281X0160Y    R180 S0      
317GND              VIA   -    MD0080PA00X+030870Y+088919X0160Y    R180 S0      
317GND              VIA   -    MD0080PA00X+031611Y+088919X0160Y    R180 S0      
317GND              VIA   -    MD0080PA00X+031611Y+088281X0160Y    R180 S0      
317GND              VIA   -    MD0080PA00X+031426Y+088600X0160Y    R180 S0      
317GND              VIA   -    MD0080PA00X+031056Y+088600X0160Y    R180 S0      
317GND              VIA   -    MD0080PA00X+031426Y+096892X0160Y    R180 S0      
317GND              VIA   -    MD0080PA00X+031611Y+096573X0160Y    R180 S0      
317GND              VIA   -    MD0080PA00X+030870Y+096573X0160Y    R180 S0      
317GND              VIA   -    MD0080PA00X+030870Y+095935X0160Y    R180 S0      
317GND              VIA   -    MD0080PA00X+031611Y+095935X0160Y    R180 S0      
317GND              VIA   -    MD0080PA00X+031426Y+095616X0160Y    R180 S0      
317GND              VIA   -    MD0080PA00X+030870Y+095297X0160Y    R180 S0      
317GND              VIA   -    MD0080PA00X+030870Y+094659X0160Y    R180 S0      
317GND              VIA   -    MD0080PA00X+031611Y+094659X0160Y    R180 S0      
317GND              VIA   -    MD0080PA00X+031426Y+094978X0160Y    R180 S0      
317GND              VIA   -    MD0080PA00X+031611Y+094021X0160Y    R180 S0      
317GND              VIA   -    MD0080PA00X+030870Y+100399X0160Y    R180 S0      
317GND              VIA   -    MD0080PA00X+030870Y+101037X0160Y    R180 S0      
317GND              VIA   -    MD0080PA00X+031611Y+101037X0160Y    R180 S0      
317GND              VIA   -    MD0080PA00X+031426Y+100718X0160Y    R180 S0      
317GND              VIA   -    MD0080PA00X+031611Y+100399X0160Y    R180 S0      
317GND              VIA   -    MD0080PA00X+031426Y+099443X0160Y    R180 S0      
317GND              VIA   -    MD0080PA00X+030870Y+099762X0160Y    R180 S0      
317GND              VIA   -    MD0080PA00X+031611Y+099762X0160Y    R180 S0      
317GND              VIA   -    MD0080PA00X+031426Y+098805X0160Y    R180 S0      
317GND              VIA   -    MD0080PA00X+031056Y+098805X0160Y    R180 S0      
317GND              VIA   -    MD0080PA00X+030870Y+099124X0160Y    R180 S0      
317GND              VIA   -    MD0080PA00X+031981Y+098486X0160Y    R180 S0      
317GND              VIA   -    MD0080PA00X+031241Y+098486X0160Y    R180 S0      
317GND              VIA   -    MD0080PA00X+030870Y+098486X0160Y    R180 S0      
317GND              VIA   -    MD0080PA00X+031611Y+098486X0160Y    R180 S0      
317GND              VIA   -    MD0080PA00X+030870Y+097210X0160Y    R180 S0      
317GND              VIA   -    MD0080PA00X+031426Y+097529X0160Y    R180 S0      
317GND              VIA   -    MD0080PA00X+031611Y+097848X0160Y    R180 S0      
317GND              VIA   -    MD0080PA00X+030870Y+097848X0160Y    R180 S0      
317GND              VIA   -    MD0080PA00X+031796Y+098167X0160Y    R180 S0      
317GND              VIA   -    MD0080PA00X+031544Y+106951X0160Y         S0      
317GND              VIA   -    MD0080PA00X+030989Y+106632X0160Y         S0      
317GND              VIA   -    MD0080PA00X+030989Y+107270X0160Y         S0      
317GND              VIA   -    MD0080PA00X+031729Y+107270X0160Y         S0      
317GND              VIA   -    MD0080PA00X+031544Y+106314X0160Y         S0      
317GND              VIA   -    MD0080PA00X+031359Y+105995X0160Y         S0      
317GND              VIA   -    MD0080PA00X+030989Y+105995X0160Y         S0      
317GND              VIA   -    MD0080PA00X+031729Y+105995X0160Y         S0      
317GND              VIA   -    MD0080PA00X+031729Y+105357X0160Y         S0      
317GND              VIA   -    MD0080PA00X+031544Y+105038X0160Y         S0      
317GND              VIA   -    MD0080PA00X+030989Y+105357X0160Y         S0      
317GND              VIA   -    MD0080PA00X+031174Y+105676X0160Y         S0      
317GND              VIA   -    MD0080PA00X+030989Y+104719X0160Y         S0      
317GND              VIA   -    MD0080PA00X+031544Y+104400X0160Y         S0      
317GND              VIA   -    MD0080PA00X+030989Y+103443X0160Y         S0      
317GND              VIA   -    MD0080PA00X+031729Y+103443X0160Y         S0      
317GND              VIA   -    MD0080PA00X+030989Y+104081X0160Y         S0      
317GND              VIA   -    MD0080PA00X+031729Y+104081X0160Y         S0      
317GND              VIA   -    MD0080PA00X+031544Y+103124X0160Y         S0      
317GND              VIA   -    MD0080PA00X+030989Y+102806X0160Y         S0      
317GND              VIA   -    MD0080PA00X+030989Y+109821X0160Y         S0      
317GND              VIA   -    MD0080PA00X+031729Y+109821X0160Y         S0      
317GND              VIA   -    MD0080PA00X+031544Y+110140X0160Y         S0      
317GND              VIA   -    MD0080PA00X+030989Y+110459X0160Y         S0      
317GND              VIA   -    MD0080PA00X+031729Y+109184X0160Y         S0      
317GND              VIA   -    MD0080PA00X+030989Y+109184X0160Y         S0      
317GND              VIA   -    MD0080PA00X+030989Y+108546X0160Y         S0      
317GND              VIA   -    MD0080PA00X+031544Y+108865X0160Y         S0      
317GND              VIA   -    MD0080PA00X+031544Y+108227X0160Y         S0      
317GND              VIA   -    MD0080PA00X+030989Y+107908X0160Y         S0      
317GND              VIA   -    MD0080PA00X+031729Y+107908X0160Y         S0      
317GND              VIA   -    MD0080PA00X+031544Y+114605X0160Y         S0      
317GND              VIA   -    MD0080PA00X+030989Y+114924X0160Y         S0      
317GND              VIA   -    MD0080PA00X+031729Y+114924X0160Y         S0      
317GND              VIA   -    MD0080PA00X+030989Y+114286X0160Y         S0      
317GND              VIA   -    MD0080PA00X+031729Y+113648X0160Y         S0      
317GND              VIA   -    MD0080PA00X+031544Y+113967X0160Y         S0      
317GND              VIA   -    MD0080PA00X+030989Y+113648X0160Y         S0      
317GND              VIA   -    MD0080PA00X+031729Y+113010X0160Y         S0      
317GND              VIA   -    MD0080PA00X+030989Y+113010X0160Y         S0      
317GND              VIA   -    MD0080PA00X+031544Y+112692X0160Y         S0      
317GND              VIA   -    MD0080PA00X+031544Y+112054X0160Y         S0      
317GND              VIA   -    MD0080PA00X+030989Y+112373X0160Y         S0      
317GND              VIA   -    MD0080PA00X+031729Y+111735X0160Y         S0      
317GND              VIA   -    MD0080PA00X+030989Y+111735X0160Y         S0      
317GND              VIA   -    MD0080PA00X+031729Y+111097X0160Y         S0      
317GND              VIA   -    MD0080PA00X+030989Y+111097X0160Y         S0      
317GND              VIA   -    MD0080PA00X+031544Y+110778X0160Y         S0      
317GND              VIA   -    MD0080PA00X+032099Y+116199X0160Y         S0      
317GND              VIA   -    MD0080PA00X+032099Y+115562X0160Y         S0      
317GND              VIA   -    MD0080PA00X+031174Y+116518X0160Y         S0      
317GND              VIA   -    MD0080PA00X+030804Y+115880X0160Y         S0      
317GND              VIA   -    MD0080PA00X+031359Y+115562X0160Y         S0      
317GND              VIA   -    MD0080PA00X+030989Y+115562X0160Y         S0      
317GND              VIA   -    MD0080PA00X+031729Y+115562X0160Y         S0      
317GND              VIA   -    MD0080PA00X+032906Y+089238X0160Y    R180 S0      
317GND              VIA   -    MD0080PA00X+032721Y+089557X0160Y    R180 S0      
317GND              VIA   -    MD0080PA00X+032166Y+089238X0160Y    R180 S0      
317GND              VIA   -    MD0080PA00X+033461Y+089557X0160Y    R180 S0      
317GND              VIA   -    MD0080PA00X+032721Y+088919X0160Y    R180 S0      
317GND              VIA   -    MD0080PA00X+033461Y+088919X0160Y    R180 S0      
317GND              VIA   -    MD0080PA00X+032906Y+088600X0160Y    R180 S0      
317GND              VIA   -    MD0080PA00X+033091Y+088281X0160Y    R180 S0      
317GND              VIA   -    MD0080PA00X+032536Y+088600X0160Y    R180 S0      
317GND              VIA   -    MD0080PA00X+032166Y+088600X0160Y    R180 S0      
317GND              VIA   -    MD0080PA00X+033461Y+088281X0160Y    R180 S0      
317GND              VIA   -    MD0080PA00X+033460Y+087207X0160Y    R180 S0      
317GND              VIA   -    MD0080PA00X+032536Y+087962X0160Y    R180 S0      
317GND              VIA   -    MD0080PA00X+033276Y+087962X0160Y    R180 S0      
317GND              VIA   -    MD0080PA00X+032721Y+087644X0160Y    R180 S0      
317GND              VIA   -    MD0080PA00X+032721Y+092108X0160Y    R180 S0      
317GND              VIA   -    MD0080PA00X+032906Y+092427X0160Y    R180 S0      
317GND              VIA   -    MD0080PA00X+032166Y+092427X0160Y    R180 S0      
317GND              VIA   -    MD0080PA00X+033461Y+092108X0160Y    R180 S0      
317GND              VIA   -    MD0080PA00X+032906Y+091789X0160Y    R180 S0      
317GND              VIA   -    MD0080PA00X+032721Y+091470X0160Y    R180 S0      
317GND              VIA   -    MD0080PA00X+032166Y+091789X0160Y    R180 S0      
317GND              VIA   -    MD0080PA00X+033461Y+091470X0160Y    R180 S0      
317GND              VIA   -    MD0080PA00X+032721Y+090832X0160Y    R180 S0      
317GND              VIA   -    MD0080PA00X+032906Y+091151X0160Y    R180 S0      
317GND              VIA   -    MD0080PA00X+032906Y+090514X0160Y    R180 S0      
317GND              VIA   -    MD0080PA00X+032166Y+091151X0160Y    R180 S0      
317GND              VIA   -    MD0080PA00X+032166Y+090514X0160Y    R180 S0      
317GND              VIA   -    MD0080PA00X+032906Y+089876X0160Y    R180 S0      
317GND              VIA   -    MD0080PA00X+032721Y+090195X0160Y    R180 S0      
317GND              VIA   -    MD0080PA00X+032166Y+089876X0160Y    R180 S0      
317GND              VIA   -    MD0080PA00X+033461Y+090195X0160Y    R180 S0      
317GND              VIA   -    MD0080PA00X+032721Y+095297X0160Y    R180 S0      
317GND              VIA   -    MD0080PA00X+032166Y+095616X0160Y    R180 S0      
317GND              VIA   -    MD0080PA00X+033461Y+095297X0160Y    R180 S0      
317GND              VIA   -    MD0080PA00X+032721Y+094659X0160Y    R180 S0      
317GND              VIA   -    MD0080PA00X+032906Y+094978X0160Y    R180 S0      
317GND              VIA   -    MD0080PA00X+032906Y+094340X0160Y    R180 S0      
317GND              VIA   -    MD0080PA00X+032166Y+094978X0160Y    R180 S0      
317GND              VIA   -    MD0080PA00X+032166Y+094340X0160Y    R180 S0      
317GND              VIA   -    MD0080PA00X+033461Y+094659X0160Y    R180 S0      
317GND              VIA   -    MD0080PA00X+032906Y+093702X0160Y    R180 S0      
317GND              VIA   -    MD0080PA00X+032721Y+094021X0160Y    R180 S0      
317GND              VIA   -    MD0080PA00X+032166Y+093702X0160Y    R180 S0      
317GND              VIA   -    MD0080PA00X+033461Y+094021X0160Y    R180 S0      
317GND              VIA   -    MD0080PA00X+032906Y+093065X0160Y    R180 S0      
317GND              VIA   -    MD0080PA00X+032721Y+093384X0160Y    R180 S0      
317GND              VIA   -    MD0080PA00X+032721Y+092746X0160Y    R180 S0      
317GND              VIA   -    MD0080PA00X+032166Y+093065X0160Y    R180 S0      
317GND              VIA   -    MD0080PA00X+033461Y+093384X0160Y    R180 S0      
317GND              VIA   -    MD0080PA00X+033461Y+092746X0160Y    R180 S0      
317GND              VIA   -    MD0080PA00X+033091Y+098486X0160Y    R180 S0      
317GND              VIA   -    MD0080PA00X+032721Y+098486X0160Y    R180 S0      
317GND              VIA   -    MD0080PA00X+033461Y+098486X0160Y    R180 S0      
317GND              VIA   -    MD0080PA00X+032721Y+097848X0160Y    R180 S0      
317GND              VIA   -    MD0080PA00X+032906Y+098167X0160Y    R180 S0      
317GND              VIA   -    MD0080PA00X+033276Y+098167X0160Y    R180 S0      
317GND              VIA   -    MD0080PA00X+032721Y+097210X0160Y    R180 S0      
317GND              VIA   -    MD0080PA00X+032906Y+097529X0160Y    R180 S0      
317GND              VIA   -    MD0080PA00X+032166Y+098167X0160Y    R180 S0      
317GND              VIA   -    MD0080PA00X+032166Y+097529X0160Y    R180 S0      
317GND              VIA   -    MD0080PA00X+033461Y+097848X0160Y    R180 S0      
317GND              VIA   -    MD0080PA00X+033461Y+097210X0160Y    R180 S0      
317GND              VIA   -    MD0080PA00X+032906Y+096892X0160Y    R180 S0      
317GND              VIA   -    MD0080PA00X+032166Y+096892X0160Y    R180 S0      
317GND              VIA   -    MD0080PA00X+032721Y+095935X0160Y    R180 S0      
317GND              VIA   -    MD0080PA00X+032166Y+096254X0160Y    R180 S0      
317GND              VIA   -    MD0080PA00X+032721Y+096573X0160Y    R180 S0      
317GND              VIA   -    MD0080PA00X+032906Y+096254X0160Y    R180 S0      
317GND              VIA   -    MD0080PA00X+033461Y+096573X0160Y    R180 S0      
317GND              VIA   -    MD0080PA00X+033461Y+095935X0160Y    R180 S0      
317GND              VIA   -    MD0080PA00X+032906Y+095616X0160Y    R180 S0      
317GND              VIA   -    MD0080PA00X+033579Y+102806X0160Y         S0      
317GND              VIA   -    MD0080PA00X+032839Y+102806X0160Y         S0      
317GND              VIA   -    MD0080PA00X+032721Y+100399X0160Y    R180 S0      
317GND              VIA   -    MD0080PA00X+032906Y+100718X0160Y    R180 S0      
317GND              VIA   -    MD0080PA00X+032721Y+101037X0160Y    R180 S0      
317GND              VIA   -    MD0080PA00X+032166Y+100718X0160Y    R180 S0      
317GND              VIA   -    MD0080PA00X+033461Y+101037X0160Y    R180 S0      
317GND              VIA   -    MD0080PA00X+033461Y+100399X0160Y    R180 S0      
317GND              VIA   -    MD0080PA00X+032906Y+100080X0160Y    R180 S0      
317GND              VIA   -    MD0080PA00X+032166Y+100080X0160Y    R180 S0      
317GND              VIA   -    MD0080PA00X+032721Y+099762X0160Y    R180 S0      
317GND              VIA   -    MD0080PA00X+032906Y+099443X0160Y    R180 S0      
317GND              VIA   -    MD0080PA00X+032906Y+098805X0160Y    R180 S0      
317GND              VIA   -    MD0080PA00X+032721Y+099124X0160Y    R180 S0      
317GND              VIA   -    MD0080PA00X+032166Y+099443X0160Y    R180 S0      
317GND              VIA   -    MD0080PA00X+032166Y+098805X0160Y    R180 S0      
317GND              VIA   -    MD0080PA00X+033461Y+099762X0160Y    R180 S0      
317GND              VIA   -    MD0080PA00X+033461Y+099124X0160Y    R180 S0      
317GND              VIA   -    MD0080PA00X+032839Y+106632X0160Y         S0      
317GND              VIA   -    MD0080PA00X+032284Y+106951X0160Y         S0      
317GND              VIA   -    MD0080PA00X+033024Y+106314X0160Y         S0      
317GND              VIA   -    MD0080PA00X+032284Y+106314X0160Y         S0      
317GND              VIA   -    MD0080PA00X+033579Y+105995X0160Y         S0      
317GND              VIA   -    MD0080PA00X+033579Y+105357X0160Y         S0      
317GND              VIA   -    MD0080PA00X+033579Y+104719X0160Y         S0      
317GND              VIA   -    MD0080PA00X+033024Y+105676X0160Y         S0      
317GND              VIA   -    MD0080PA00X+033024Y+105038X0160Y         S0      
317GND              VIA   -    MD0080PA00X+032469Y+105995X0160Y         S0      
317GND              VIA   -    MD0080PA00X+032839Y+105995X0160Y         S0      
317GND              VIA   -    MD0080PA00X+032839Y+105357X0160Y         S0      
317GND              VIA   -    MD0080PA00X+032654Y+105676X0160Y         S0      
317GND              VIA   -    MD0080PA00X+032284Y+105676X0160Y         S0      
317GND              VIA   -    MD0080PA00X+032284Y+105038X0160Y         S0      
317GND              VIA   -    MD0080PA00X+032839Y+104719X0160Y         S0      
317GND              VIA   -    MD0080PA00X+033579Y+103443X0160Y         S0      
317GND              VIA   -    MD0080PA00X+033579Y+104081X0160Y         S0      
317GND              VIA   -    MD0080PA00X+033024Y+104400X0160Y         S0      
317GND              VIA   -    MD0080PA00X+033024Y+103762X0160Y         S0      
317GND              VIA   -    MD0080PA00X+033024Y+103124X0160Y         S0      
317GND              VIA   -    MD0080PA00X+032839Y+103443X0160Y         S0      
317GND              VIA   -    MD0080PA00X+032839Y+104081X0160Y         S0      
317GND              VIA   -    MD0080PA00X+032284Y+104400X0160Y         S0      
317GND              VIA   -    MD0080PA00X+032284Y+103762X0160Y         S0      
317GND              VIA   -    MD0080PA00X+032284Y+103124X0160Y         S0      
317GND              VIA   -    MD0080PA00X+033579Y+108546X0160Y         S0      
317GND              VIA   -    MD0080PA00X+033579Y+107908X0160Y         S0      
317GND              VIA   -    MD0080PA00X+033024Y+108227X0160Y         S0      
317GND              VIA   -    MD0080PA00X+032284Y+108227X0160Y         S0      
317GND              VIA   -    MD0080PA00X+033024Y+108865X0160Y         S0      
317GND              VIA   -    MD0080PA00X+032839Y+108546X0160Y         S0      
317GND              VIA   -    MD0080PA00X+032284Y+108865X0160Y         S0      
317GND              VIA   -    MD0080PA00X+032839Y+107908X0160Y         S0      
317GND              VIA   -    MD0080PA00X+033024Y+107589X0160Y         S0      
317GND              VIA   -    MD0080PA00X+032284Y+107589X0160Y         S0      
317GND              VIA   -    MD0080PA00X+033579Y+106632X0160Y         S0      
317GND              VIA   -    MD0080PA00X+033579Y+107270X0160Y         S0      
317GND              VIA   -    MD0080PA00X+033024Y+106951X0160Y         S0      
317GND              VIA   -    MD0080PA00X+032839Y+107270X0160Y         S0      
317GND              VIA   -    MD0080PA00X+033579Y+111735X0160Y         S0      
317GND              VIA   -    MD0080PA00X+033579Y+111097X0160Y         S0      
317GND              VIA   -    MD0080PA00X+032284Y+111416X0160Y         S0      
317GND              VIA   -    MD0080PA00X+033024Y+111416X0160Y         S0      
317GND              VIA   -    MD0080PA00X+032839Y+111735X0160Y         S0      
317GND              VIA   -    MD0080PA00X+032839Y+111097X0160Y         S0      
317GND              VIA   -    MD0080PA00X+033024Y+110778X0160Y         S0      
317GND              VIA   -    MD0080PA00X+032284Y+110778X0160Y         S0      
317GND              VIA   -    MD0080PA00X+033579Y+109821X0160Y         S0      
317GND              VIA   -    MD0080PA00X+033579Y+110459X0160Y         S0      
317GND              VIA   -    MD0080PA00X+033579Y+109184X0160Y         S0      
317GND              VIA   -    MD0080PA00X+033024Y+110140X0160Y         S0      
317GND              VIA   -    MD0080PA00X+032284Y+110140X0160Y         S0      
317GND              VIA   -    MD0080PA00X+032839Y+109821X0160Y         S0      
317GND              VIA   -    MD0080PA00X+032839Y+110459X0160Y         S0      
317GND              VIA   -    MD0080PA00X+033024Y+109502X0160Y         S0      
317GND              VIA   -    MD0080PA00X+032284Y+109502X0160Y         S0      
317GND              VIA   -    MD0080PA00X+032839Y+109184X0160Y         S0      
317GND              VIA   -    MD0080PA00X+033579Y+116199X0160Y         S0      
317GND              VIA   -    MD0080PA00X+033579Y+115562X0160Y         S0      
317GND              VIA   -    MD0080PA00X+033024Y+116518X0160Y         S0      
317GND              VIA   -    MD0080PA00X+032839Y+116199X0160Y         S0      
317GND              VIA   -    MD0080PA00X+032284Y+115880X0160Y         S0      
317GND              VIA   -    MD0080PA00X+033394Y+115880X0160Y         S0      
317GND              VIA   -    MD0080PA00X+033024Y+115880X0160Y         S0      
317GND              VIA   -    MD0080PA00X+032654Y+115880X0160Y         S0      
317GND              VIA   -    MD0080PA00X+032284Y+115243X0160Y         S0      
317GND              VIA   -    MD0080PA00X+033024Y+115243X0160Y         S0      
317GND              VIA   -    MD0080PA00X+032839Y+115562X0160Y         S0      
317GND              VIA   -    MD0080PA00X+033579Y+114924X0160Y         S0      
317GND              VIA   -    MD0080PA00X+033579Y+114286X0160Y         S0      
317GND              VIA   -    MD0080PA00X+033579Y+113648X0160Y         S0      
317GND              VIA   -    MD0080PA00X+032284Y+114605X0160Y         S0      
317GND              VIA   -    MD0080PA00X+033024Y+114605X0160Y         S0      
317GND              VIA   -    MD0080PA00X+032839Y+114924X0160Y         S0      
317GND              VIA   -    MD0080PA00X+033024Y+113967X0160Y         S0      
317GND              VIA   -    MD0080PA00X+032839Y+113648X0160Y         S0      
317GND              VIA   -    MD0080PA00X+032284Y+113967X0160Y         S0      
317GND              VIA   -    MD0080PA00X+032839Y+114286X0160Y         S0      
317GND              VIA   -    MD0080PA00X+033579Y+112373X0160Y         S0      
317GND              VIA   -    MD0080PA00X+032839Y+113010X0160Y         S0      
317GND              VIA   -    MD0080PA00X+033024Y+113329X0160Y         S0      
317GND              VIA   -    MD0080PA00X+032284Y+113329X0160Y         S0      
317GND              VIA   -    MD0080PA00X+032284Y+112054X0160Y         S0      
317GND              VIA   -    MD0080PA00X+033024Y+112054X0160Y         S0      
317GND              VIA   -    MD0080PA00X+032839Y+112373X0160Y         S0      
317GND              VIA   -    MD0080PA00X+032284Y+112692X0160Y         S0      
317GND              VIA   -    MD0080PA00X+033024Y+112692X0160Y         S0      
317GND              VIA   -    MD0080PA00X+034016Y+089238X0160Y    R180 S0      
317GND              VIA   -    MD0080PA00X+034201Y+088919X0160Y    R180 S0      
317GND              VIA   -    MD0080PA00X+034756Y+089238X0160Y    R180 S0      
317GND              VIA   -    MD0080PA00X+034201Y+088281X0160Y    R180 S0      
317GND              VIA   -    MD0080PA00X+034756Y+088600X0160Y    R180 S0      
317GND              VIA   -    MD0080PA00X+034016Y+088600X0160Y    R180 S0      
317GND              VIA   -    MD0080PA00X+033646Y+088600X0160Y    R180 S0      
317GND              VIA   -    MD0080PA00X+034571Y+088281X0160Y    R180 S0      
317GND              VIA   -    MD0080PA00X+034016Y+087957X0160Y    R180 S0      
317GND              VIA   -    MD0080PA00X+034386Y+087962X0160Y    R180 S0      
317GND              VIA   -    MD0080PA00X+034201Y+092108X0160Y    R180 S0      
317GND              VIA   -    MD0080PA00X+034016Y+091789X0160Y    R180 S0      
317GND              VIA   -    MD0080PA00X+034756Y+092427X0160Y    R180 S0      
317GND              VIA   -    MD0080PA00X+034756Y+091789X0160Y    R180 S0      
317GND              VIA   -    MD0080PA00X+034201Y+090832X0160Y    R180 S0      
317GND              VIA   -    MD0080PA00X+034016Y+091151X0160Y    R180 S0      
317GND              VIA   -    MD0080PA00X+034016Y+089876X0160Y    R180 S0      
317GND              VIA   -    MD0080PA00X+034201Y+090195X0160Y    R180 S0      
317GND              VIA   -    MD0080PA00X+034756Y+091151X0160Y    R180 S0      
317GND              VIA   -    MD0080PA00X+034756Y+090514X0160Y    R180 S0      
317GND              VIA   -    MD0080PA00X+034756Y+089876X0160Y    R180 S0      
317GND              VIA   -    MD0080PA00X+034016Y+095616X0160Y    R180 S0      
317GND              VIA   -    MD0080PA00X+034201Y+094659X0160Y    R180 S0      
317GND              VIA   -    MD0080PA00X+034016Y+094978X0160Y    R180 S0      
317GND              VIA   -    MD0080PA00X+034756Y+095616X0160Y    R180 S0      
317GND              VIA   -    MD0080PA00X+034756Y+094978X0160Y    R180 S0      
317GND              VIA   -    MD0080PA00X+034756Y+094340X0160Y    R180 S0      
317GND              VIA   -    MD0080PA00X+034016Y+093702X0160Y    R180 S0      
317GND              VIA   -    MD0080PA00X+034201Y+094021X0160Y    R180 S0      
317GND              VIA   -    MD0080PA00X+034016Y+093065X0160Y    R180 S0      
317GND              VIA   -    MD0080PA00X+034201Y+092746X0160Y    R180 S0      
317GND              VIA   -    MD0080PA00X+034756Y+093702X0160Y    R180 S0      
317GND              VIA   -    MD0080PA00X+034756Y+093065X0160Y    R180 S0      
317GND              VIA   -    MD0080PA00X+034016Y+099443X0160Y    R180 S0      
317GND              VIA   -    MD0080PA00X+034201Y+099762X0160Y    R180 S0      
317GND              VIA   -    MD0080PA00X+034016Y+098805X0160Y    R180 S0      
317GND              VIA   -    MD0080PA00X+034756Y+100080X0160Y    R180 S0      
317GND              VIA   -    MD0080PA00X+034756Y+099443X0160Y    R180 S0      
317GND              VIA   -    MD0080PA00X+034756Y+098805X0160Y    R180 S0      
317GND              VIA   -    MD0080PA00X+034201Y+098486X0160Y    R180 S0      
317GND              VIA   -    MD0080PA00X+034201Y+097848X0160Y    R180 S0      
317GND              VIA   -    MD0080PA00X+034386Y+098167X0160Y    R180 S0      
317GND              VIA   -    MD0080PA00X+034016Y+097529X0160Y    R180 S0      
317GND              VIA   -    MD0080PA00X+034571Y+098486X0160Y    R180 S0      
317GND              VIA   -    MD0080PA00X+034756Y+098167X0160Y    R180 S0      
317GND              VIA   -    MD0080PA00X+034756Y+097529X0160Y    R180 S0      
317GND              VIA   -    MD0080PA00X+034016Y+096892X0160Y    R180 S0      
317GND              VIA   -    MD0080PA00X+034201Y+096573X0160Y    R180 S0      
317GND              VIA   -    MD0080PA00X+034201Y+095935X0160Y    R180 S0      
317GND              VIA   -    MD0080PA00X+034756Y+096892X0160Y    R180 S0      
317GND              VIA   -    MD0080PA00X+034756Y+096254X0160Y    R180 S0      
317GND              VIA   -    MD0080PA00X+034134Y+104400X0160Y         S0      
317GND              VIA   -    MD0080PA00X+034874Y+104400X0160Y         S0      
317GND              VIA   -    MD0080PA00X+034319Y+103443X0160Y         S0      
317GND              VIA   -    MD0080PA00X+034874Y+103762X0160Y         S0      
317GND              VIA   -    MD0080PA00X+034319Y+104081X0160Y         S0      
317GND              VIA   -    MD0080PA00X+034134Y+103124X0160Y         S0      
317GND              VIA   -    MD0080PA00X+034874Y+103124X0160Y         S0      
317GND              VIA   -    MD0080PA00X+034201Y+100399X0160Y    R180 S0      
317GND              VIA   -    MD0080PA00X+034016Y+100718X0160Y    R180 S0      
317GND              VIA   -    MD0080PA00X+034201Y+101037X0160Y    R180 S0      
317GND              VIA   -    MD0080PA00X+034756Y+100718X0160Y    R180 S0      
317GND              VIA   -    MD0080PA00X+034874Y+108865X0160Y         S0      
317GND              VIA   -    MD0080PA00X+034134Y+108865X0160Y         S0      
317GND              VIA   -    MD0080PA00X+034874Y+108227X0160Y         S0      
317GND              VIA   -    MD0080PA00X+034134Y+108227X0160Y         S0      
317GND              VIA   -    MD0080PA00X+034874Y+107589X0160Y         S0      
317GND              VIA   -    MD0080PA00X+034319Y+107908X0160Y         S0      
317GND              VIA   -    MD0080PA00X+034874Y+106951X0160Y         S0      
317GND              VIA   -    MD0080PA00X+034319Y+107270X0160Y         S0      
317GND              VIA   -    MD0080PA00X+034134Y+106951X0160Y         S0      
317GND              VIA   -    MD0080PA00X+034874Y+106314X0160Y         S0      
317GND              VIA   -    MD0080PA00X+034134Y+106314X0160Y         S0      
317GND              VIA   -    MD0080PA00X+033949Y+105995X0160Y         S0      
317GND              VIA   -    MD0080PA00X+034319Y+105995X0160Y         S0      
317GND              VIA   -    MD0080PA00X+034874Y+105038X0160Y         S0      
317GND              VIA   -    MD0080PA00X+034134Y+105038X0160Y         S0      
317GND              VIA   -    MD0080PA00X+034319Y+105357X0160Y         S0      
317GND              VIA   -    MD0080PA00X+034874Y+105676X0160Y         S0      
317GND              VIA   -    MD0080PA00X+033764Y+105676X0160Y         S0      
317GND              VIA   -    MD0080PA00X+035060Y+105995X0160Y         S0      
317GND              VIA   -    MD0080PA00X+034874Y+111416X0160Y         S0      
317GND              VIA   -    MD0080PA00X+034319Y+111735X0160Y         S0      
317GND              VIA   -    MD0080PA00X+034319Y+111097X0160Y         S0      
317GND              VIA   -    MD0080PA00X+034874Y+110778X0160Y         S0      
317GND              VIA   -    MD0080PA00X+034134Y+110778X0160Y         S0      
317GND              VIA   -    MD0080PA00X+034319Y+109821X0160Y         S0      
317GND              VIA   -    MD0080PA00X+034134Y+110140X0160Y         S0      
317GND              VIA   -    MD0080PA00X+034874Y+110140X0160Y         S0      
317GND              VIA   -    MD0080PA00X+034319Y+109184X0160Y         S0      
317GND              VIA   -    MD0080PA00X+034874Y+109502X0160Y         S0      
317GND              VIA   -    MD0080PA00X+034134Y+114605X0160Y         S0      
317GND              VIA   -    MD0080PA00X+034874Y+114605X0160Y         S0      
317GND              VIA   -    MD0080PA00X+034319Y+114924X0160Y         S0      
317GND              VIA   -    MD0080PA00X+034874Y+113967X0160Y         S0      
317GND              VIA   -    MD0080PA00X+034319Y+113648X0160Y         S0      
317GND              VIA   -    MD0080PA00X+034134Y+113967X0160Y         S0      
317GND              VIA   -    MD0080PA00X+034319Y+113010X0160Y         S0      
317GND              VIA   -    MD0080PA00X+034874Y+113329X0160Y         S0      
317GND              VIA   -    MD0080PA00X+034874Y+112692X0160Y         S0      
317GND              VIA   -    MD0080PA00X+034134Y+112692X0160Y         S0      
317GND              VIA   -    MD0080PA00X+034134Y+112054X0160Y         S0      
317GND              VIA   -    MD0080PA00X+034874Y+112054X0160Y         S0      
317GND              VIA   -    MD0080PA00X+034874Y+116518X0160Y         S0      
317GND              VIA   -    MD0080PA00X+034689Y+116199X0160Y         S0      
317GND              VIA   -    MD0080PA00X+034319Y+116199X0160Y         S0      
317GND              VIA   -    MD0080PA00X+033764Y+116518X0160Y         S0      
317GND              VIA   -    MD0080PA00X+034689Y+115562X0160Y         S0      
317GND              VIA   -    MD0080PA00X+034319Y+115562X0160Y         S0      
317GND              VIA   -    MD0080PA00X+033949Y+115562X0160Y         S0      
317GND              VIA   -    MD0080PA00X+034874Y+115880X0160Y         S0      
317GND              VIA   -    MD0080PA00X+034134Y+115880X0160Y         S0      
317GND              VIA   -    MD0080PA00X+033764Y+115880X0160Y         S0      
317GND              VIA   -    MD0080PA00X+034874Y+115243X0160Y         S0      
317GND              VIA   -    MD0080PA00X+035680Y+087207X0160Y    R180 S0      
317GND              VIA   -    MD0080PA00X+035496Y+087962X0160Y    R180 S0      
317GND              VIA   -    MD0080PA00X+036052Y+087644X0160Y    R180 S0      
317GND              VIA   -    MD0080PA00X+035126Y+087957X0160Y    R180 S0      
317GND              VIA   -    MD0080PA00X+036052Y+090832X0160Y    R180 S0      
317GND              VIA   -    MD0080PA00X+035496Y+090514X0160Y    R180 S0      
317GND              VIA   -    MD0080PA00X+035496Y+091151X0160Y    R180 S0      
317GND              VIA   -    MD0080PA00X+035311Y+090195X0160Y    R180 S0      
317GND              VIA   -    MD0080PA00X+036052Y+090195X0160Y    R180 S0      
317GND              VIA   -    MD0080PA00X+035496Y+089876X0160Y    R180 S0      
317GND              VIA   -    MD0080PA00X+035311Y+089557X0160Y    R180 S0      
317GND              VIA   -    MD0080PA00X+035311Y+088919X0160Y    R180 S0      
317GND              VIA   -    MD0080PA00X+036052Y+089557X0160Y    R180 S0      
317GND              VIA   -    MD0080PA00X+036052Y+088919X0160Y    R180 S0      
317GND              VIA   -    MD0080PA00X+035496Y+089238X0160Y    R180 S0      
317GND              VIA   -    MD0080PA00X+035496Y+088600X0160Y    R180 S0      
317GND              VIA   -    MD0080PA00X+035311Y+088281X0160Y    R180 S0      
317GND              VIA   -    MD0080PA00X+036052Y+088281X0160Y    R180 S0      
317GND              VIA   -    MD0080PA00X+035682Y+088281X0160Y    R180 S0      
317GND              VIA   -    MD0080PA00X+036237Y+088600X0160Y    R180 S0      
317GND              VIA   -    MD0080PA00X+035126Y+088600X0160Y    R180 S0      
317GND              VIA   -    MD0080PA00X+035311Y+092108X0160Y    R180 S0      
317GND              VIA   -    MD0080PA00X+036052Y+092108X0160Y    R180 S0      
317GND              VIA   -    MD0080PA00X+035496Y+092427X0160Y    R180 S0      
317GND              VIA   -    MD0080PA00X+035311Y+091470X0160Y    R180 S0      
317GND              VIA   -    MD0080PA00X+036052Y+091470X0160Y    R180 S0      
317GND              VIA   -    MD0080PA00X+035496Y+091789X0160Y    R180 S0      
317GND              VIA   -    MD0080PA00X+035496Y+094978X0160Y    R180 S0      
317GND              VIA   -    MD0080PA00X+035496Y+094340X0160Y    R180 S0      
317GND              VIA   -    MD0080PA00X+035311Y+094021X0160Y    R180 S0      
317GND              VIA   -    MD0080PA00X+036052Y+094021X0160Y    R180 S0      
317GND              VIA   -    MD0080PA00X+035496Y+093702X0160Y    R180 S0      
317GND              VIA   -    MD0080PA00X+035311Y+092746X0160Y    R180 S0      
317GND              VIA   -    MD0080PA00X+035311Y+093384X0160Y    R180 S0      
317GND              VIA   -    MD0080PA00X+036052Y+093384X0160Y    R180 S0      
317GND              VIA   -    MD0080PA00X+036052Y+092746X0160Y    R180 S0      
317GND              VIA   -    MD0080PA00X+035496Y+093065X0160Y    R180 S0      
317GND              VIA   -    MD0080PA00X+035496Y+096892X0160Y    R180 S0      
317GND              VIA   -    MD0080PA00X+035496Y+096254X0160Y    R180 S0      
317GND              VIA   -    MD0080PA00X+035311Y+096573X0160Y    R180 S0      
317GND              VIA   -    MD0080PA00X+035311Y+095935X0160Y    R180 S0      
317GND              VIA   -    MD0080PA00X+036052Y+096573X0160Y    R180 S0      
317GND              VIA   -    MD0080PA00X+036052Y+095935X0160Y    R180 S0      
317GND              VIA   -    MD0080PA00X+035496Y+095616X0160Y    R180 S0      
317GND              VIA   -    MD0080PA00X+035311Y+095297X0160Y    R180 S0      
317GND              VIA   -    MD0080PA00X+036052Y+095297X0160Y    R180 S0      
317GND              VIA   -    MD0080PA00X+035311Y+094659X0160Y    R180 S0      
317GND              VIA   -    MD0080PA00X+036052Y+094659X0160Y    R180 S0      
317GND              VIA   -    MD0080PA00X+035496Y+100080X0160Y    R180 S0      
317GND              VIA   -    MD0080PA00X+035496Y+099443X0160Y    R180 S0      
317GND              VIA   -    MD0080PA00X+035496Y+098805X0160Y    R180 S0      
317GND              VIA   -    MD0080PA00X+035311Y+099762X0160Y    R180 S0      
317GND              VIA   -    MD0080PA00X+035311Y+099124X0160Y    R180 S0      
317GND              VIA   -    MD0080PA00X+036052Y+099124X0160Y    R180 S0      
317GND              VIA   -    MD0080PA00X+036052Y+099762X0160Y    R180 S0      
317GND              VIA   -    MD0080PA00X+035311Y+098486X0160Y    R180 S0      
317GND              VIA   -    MD0080PA00X+035682Y+098486X0160Y    R180 S0      
317GND              VIA   -    MD0080PA00X+036052Y+098486X0160Y    R180 S0      
317GND              VIA   -    MD0080PA00X+035311Y+097848X0160Y    R180 S0      
317GND              VIA   -    MD0080PA00X+035311Y+097210X0160Y    R180 S0      
317GND              VIA   -    MD0080PA00X+035866Y+098167X0160Y    R180 S0      
317GND              VIA   -    MD0080PA00X+036052Y+097848X0160Y    R180 S0      
317GND              VIA   -    MD0080PA00X+036052Y+097210X0160Y    R180 S0      
317GND              VIA   -    MD0080PA00X+035496Y+098167X0160Y    R180 S0      
317GND              VIA   -    MD0080PA00X+035496Y+097529X0160Y    R180 S0      
317GND              VIA   -    MD0080PA00X+036170Y+103443X0160Y         S0      
317GND              VIA   -    MD0080PA00X+035615Y+103762X0160Y         S0      
317GND              VIA   -    MD0080PA00X+035615Y+103124X0160Y         S0      
317GND              VIA   -    MD0080PA00X+035430Y+103443X0160Y         S0      
317GND              VIA   -    MD0080PA00X+035430Y+104081X0160Y         S0      
317GND              VIA   -    MD0080PA00X+036170Y+102806X0160Y         S0      
317GND              VIA   -    MD0080PA00X+035430Y+102806X0160Y         S0      
317GND              VIA   -    MD0080PA00X+035311Y+101037X0160Y    R180 S0      
317GND              VIA   -    MD0080PA00X+036052Y+101037X0160Y    R180 S0      
317GND              VIA   -    MD0080PA00X+035311Y+100399X0160Y    R180 S0      
317GND              VIA   -    MD0080PA00X+036052Y+100399X0160Y    R180 S0      
317GND              VIA   -    MD0080PA00X+035496Y+100718X0160Y    R180 S0      
317GND              VIA   -    MD0080PA00X+035244Y+105676X0160Y         S0      
317GND              VIA   -    MD0080PA00X+036170Y+105995X0160Y         S0      
317GND              VIA   -    MD0080PA00X+036540Y+105995X0160Y         S0      
317GND              VIA   -    MD0080PA00X+036170Y+105357X0160Y         S0      
317GND              VIA   -    MD0080PA00X+035615Y+105038X0160Y         S0      
317GND              VIA   -    MD0080PA00X+035615Y+105676X0160Y         S0      
317GND              VIA   -    MD0080PA00X+036355Y+105676X0160Y         S0      
317GND              VIA   -    MD0080PA00X+035430Y+105995X0160Y         S0      
317GND              VIA   -    MD0080PA00X+035430Y+105357X0160Y         S0      
317GND              VIA   -    MD0080PA00X+036170Y+104719X0160Y         S0      
317GND              VIA   -    MD0080PA00X+035430Y+104719X0160Y         S0      
317GND              VIA   -    MD0080PA00X+035615Y+104400X0160Y         S0      
317GND              VIA   -    MD0080PA00X+036170Y+104081X0160Y         S0      
317GND              VIA   -    MD0080PA00X+035615Y+108227X0160Y         S0      
317GND              VIA   -    MD0080PA00X+036170Y+108546X0160Y         S0      
317GND              VIA   -    MD0080PA00X+035615Y+108865X0160Y         S0      
317GND              VIA   -    MD0080PA00X+035430Y+108546X0160Y         S0      
317GND              VIA   -    MD0080PA00X+036170Y+107908X0160Y         S0      
317GND              VIA   -    MD0080PA00X+035430Y+107908X0160Y         S0      
317GND              VIA   -    MD0080PA00X+035615Y+107589X0160Y         S0      
317GND              VIA   -    MD0080PA00X+036170Y+107270X0160Y         S0      
317GND              VIA   -    MD0080PA00X+036170Y+106632X0160Y         S0      
317GND              VIA   -    MD0080PA00X+035615Y+106951X0160Y         S0      
317GND              VIA   -    MD0080PA00X+035430Y+106632X0160Y         S0      
317GND              VIA   -    MD0080PA00X+035430Y+107270X0160Y         S0      
317GND              VIA   -    MD0080PA00X+035615Y+106314X0160Y         S0      
317GND              VIA   -    MD0080PA00X+036170Y+109821X0160Y         S0      
317GND              VIA   -    MD0080PA00X+035615Y+110140X0160Y         S0      
317GND              VIA   -    MD0080PA00X+036170Y+110459X0160Y         S0      
317GND              VIA   -    MD0080PA00X+035430Y+109821X0160Y         S0      
317GND              VIA   -    MD0080PA00X+035430Y+110459X0160Y         S0      
317GND              VIA   -    MD0080PA00X+035615Y+109502X0160Y         S0      
317GND              VIA   -    MD0080PA00X+036170Y+109184X0160Y         S0      
317GND              VIA   -    MD0080PA00X+035430Y+109184X0160Y         S0      
317GND              VIA   -    MD0080PA00X+036170Y+113010X0160Y         S0      
317GND              VIA   -    MD0080PA00X+035615Y+113329X0160Y         S0      
317GND              VIA   -    MD0080PA00X+036170Y+112373X0160Y         S0      
317GND              VIA   -    MD0080PA00X+035615Y+112054X0160Y         S0      
317GND              VIA   -    MD0080PA00X+035615Y+112692X0160Y         S0      
317GND              VIA   -    MD0080PA00X+035430Y+112373X0160Y         S0      
317GND              VIA   -    MD0080PA00X+035430Y+111735X0160Y         S0      
317GND              VIA   -    MD0080PA00X+035615Y+111416X0160Y         S0      
317GND              VIA   -    MD0080PA00X+036170Y+111735X0160Y         S0      
317GND              VIA   -    MD0080PA00X+036170Y+111097X0160Y         S0      
317GND              VIA   -    MD0080PA00X+035430Y+111097X0160Y         S0      
317GND              VIA   -    MD0080PA00X+035615Y+110778X0160Y         S0      
317GND              VIA   -    MD0080PA00X+035430Y+116199X0160Y         S0      
317GND              VIA   -    MD0080PA00X+035430Y+115562X0160Y         S0      
317GND              VIA   -    MD0080PA00X+036170Y+115562X0160Y         S0      
317GND              VIA   -    MD0080PA00X+035615Y+115243X0160Y         S0      
317GND              VIA   -    MD0080PA00X+036540Y+115562X0160Y         S0      
317GND              VIA   -    MD0080PA00X+035244Y+115880X0160Y         S0      
317GND              VIA   -    MD0080PA00X+035985Y+115880X0160Y         S0      
317GND              VIA   -    MD0080PA00X+035615Y+115880X0160Y         S0      
317GND              VIA   -    MD0080PA00X+036355Y+115880X0160Y         S0      
317GND              VIA   -    MD0080PA00X+035430Y+114924X0160Y         S0      
317GND              VIA   -    MD0080PA00X+035615Y+114605X0160Y         S0      
317GND              VIA   -    MD0080PA00X+036170Y+114924X0160Y         S0      
317GND              VIA   -    MD0080PA00X+036170Y+114286X0160Y         S0      
317GND              VIA   -    MD0080PA00X+035430Y+114286X0160Y         S0      
317GND              VIA   -    MD0080PA00X+036170Y+113648X0160Y         S0      
317GND              VIA   -    MD0080PA00X+035615Y+113967X0160Y         S0      
317GND              VIA   -    MD0080PA00X+035430Y+113648X0160Y         S0      
317GND              VIA   -    MD0080PA00X+036170Y+116199X0160Y         S0      
317GND              VIA   -    MD0080PA00X+035615Y+116518X0160Y         S0      
317GND              VIA   -    MD0080PA00X+036355Y+116518X0160Y         S0      
317GND              VIA   -    MD0080PA00X+037717Y+087962X0160Y    R180 S0      
317GND              VIA   -    MD0080PA00X+037532Y+087644X0160Y    R180 S0      
317GND              VIA   -    MD0080PA00X+037347Y+087962X0160Y    R180 S0      
317GND              VIA   -    MD0080PA00X+036977Y+087962X0160Y    R180 S0      
317GND              VIA   -    MD0080PA00X+037902Y+089557X0160Y    R180 S0      
317GND              VIA   -    MD0080PA00X+037717Y+088600X0160Y    R180 S0      
317GND              VIA   -    MD0080PA00X+037902Y+088281X0160Y    R180 S0      
317GND              VIA   -    MD0080PA00X+037347Y+088600X0160Y    R180 S0      
317GND              VIA   -    MD0080PA00X+036792Y+088281X0160Y    R180 S0      
317GND              VIA   -    MD0080PA00X+037347Y+089238X0160Y    R180 S0      
317GND              VIA   -    MD0080PA00X+036792Y+088919X0160Y    R180 S0      
317GND              VIA   -    MD0080PA00X+036607Y+089238X0160Y    R180 S0      
317GND              VIA   -    MD0080PA00X+036607Y+088600X0160Y    R180 S0      
317GND              VIA   -    MD0080PA00X+037902Y+092108X0160Y    R180 S0      
317GND              VIA   -    MD0080PA00X+037347Y+092427X0160Y    R180 S0      
317GND              VIA   -    MD0080PA00X+036792Y+092108X0160Y    R180 S0      
317GND              VIA   -    MD0080PA00X+037347Y+091789X0160Y    R180 S0      
317GND              VIA   -    MD0080PA00X+036607Y+091789X0160Y    R180 S0      
317GND              VIA   -    MD0080PA00X+037347Y+090514X0160Y    R180 S0      
317GND              VIA   -    MD0080PA00X+037347Y+091151X0160Y    R180 S0      
317GND              VIA   -    MD0080PA00X+037902Y+090832X0160Y    R180 S0      
317GND              VIA   -    MD0080PA00X+037347Y+089876X0160Y    R180 S0      
317GND              VIA   -    MD0080PA00X+036792Y+090195X0160Y    R180 S0      
317GND              VIA   -    MD0080PA00X+036607Y+091151X0160Y    R180 S0      
317GND              VIA   -    MD0080PA00X+036607Y+089876X0160Y    R180 S0      
317GND              VIA   -    MD0080PA00X+037902Y+094021X0160Y    R180 S0      
317GND              VIA   -    MD0080PA00X+037347Y+093702X0160Y    R180 S0      
317GND              VIA   -    MD0080PA00X+036792Y+094021X0160Y    R180 S0      
317GND              VIA   -    MD0080PA00X+037347Y+093065X0160Y    R180 S0      
317GND              VIA   -    MD0080PA00X+037902Y+093384X0160Y    R180 S0      
317GND              VIA   -    MD0080PA00X+036792Y+092746X0160Y    R180 S0      
317GND              VIA   -    MD0080PA00X+036607Y+093702X0160Y    R180 S0      
317GND              VIA   -    MD0080PA00X+036607Y+093065X0160Y    R180 S0      
317GND              VIA   -    MD0080PA00X+037902Y+096573X0160Y    R180 S0      
317GND              VIA   -    MD0080PA00X+037347Y+096892X0160Y    R180 S0      
317GND              VIA   -    MD0080PA00X+037347Y+096254X0160Y    R180 S0      
317GND              VIA   -    MD0080PA00X+036792Y+096573X0160Y    R180 S0      
317GND              VIA   -    MD0080PA00X+036792Y+095935X0160Y    R180 S0      
317GND              VIA   -    MD0080PA00X+036607Y+096892X0160Y    R180 S0      
317GND              VIA   -    MD0080PA00X+037902Y+095297X0160Y    R180 S0      
317GND              VIA   -    MD0080PA00X+037347Y+095616X0160Y    R180 S0      
317GND              VIA   -    MD0080PA00X+037347Y+094978X0160Y    R180 S0      
317GND              VIA   -    MD0080PA00X+037347Y+094340X0160Y    R180 S0      
317GND              VIA   -    MD0080PA00X+036792Y+094659X0160Y    R180 S0      
317GND              VIA   -    MD0080PA00X+036607Y+095616X0160Y    R180 S0      
317GND              VIA   -    MD0080PA00X+036607Y+094978X0160Y    R180 S0      
317GND              VIA   -    MD0080PA00X+037902Y+097848X0160Y    R180 S0      
317GND              VIA   -    MD0080PA00X+037162Y+098486X0160Y    R180 S0      
317GND              VIA   -    MD0080PA00X+037902Y+098486X0160Y    R180 S0      
317GND              VIA   -    MD0080PA00X+036792Y+098486X0160Y    R180 S0      
317GND              VIA   -    MD0080PA00X+037347Y+098167X0160Y    R180 S0      
317GND              VIA   -    MD0080PA00X+037347Y+097529X0160Y    R180 S0      
317GND              VIA   -    MD0080PA00X+036792Y+097848X0160Y    R180 S0      
317GND              VIA   -    MD0080PA00X+036977Y+098167X0160Y    R180 S0      
317GND              VIA   -    MD0080PA00X+036607Y+097529X0160Y    R180 S0      
317GND              VIA   -    MD0080PA00X+038020Y+102806X0160Y         S0      
317GND              VIA   -    MD0080PA00X+036792Y+101037X0160Y    R180 S0      
317GND              VIA   -    MD0080PA00X+037902Y+100399X0160Y    R180 S0      
317GND              VIA   -    MD0080PA00X+036792Y+100399X0160Y    R180 S0      
317GND              VIA   -    MD0080PA00X+037347Y+100718X0160Y    R180 S0      
317GND              VIA   -    MD0080PA00X+036607Y+100718X0160Y    R180 S0      
317GND              VIA   -    MD0080PA00X+037347Y+100080X0160Y    R180 S0      
317GND              VIA   -    MD0080PA00X+037347Y+099443X0160Y    R180 S0      
317GND              VIA   -    MD0080PA00X+037902Y+099762X0160Y    R180 S0      
317GND              VIA   -    MD0080PA00X+037347Y+098805X0160Y    R180 S0      
317GND              VIA   -    MD0080PA00X+037902Y+099124X0160Y    R180 S0      
317GND              VIA   -    MD0080PA00X+036792Y+099762X0160Y    R180 S0      
317GND              VIA   -    MD0080PA00X+036607Y+098805X0160Y    R180 S0      
317GND              VIA   -    MD0080PA00X+036607Y+099443X0160Y    R180 S0      
317GND              VIA   -    MD0080PA00X+037650Y+105995X0160Y         S0      
317GND              VIA   -    MD0080PA00X+038020Y+105995X0160Y         S0      
317GND              VIA   -    MD0080PA00X+037465Y+105676X0160Y         S0      
317GND              VIA   -    MD0080PA00X+037465Y+105038X0160Y         S0      
317GND              VIA   -    MD0080PA00X+037835Y+105676X0160Y         S0      
317GND              VIA   -    MD0080PA00X+038020Y+105357X0160Y         S0      
317GND              VIA   -    MD0080PA00X+036910Y+105995X0160Y         S0      
317GND              VIA   -    MD0080PA00X+036910Y+105357X0160Y         S0      
317GND              VIA   -    MD0080PA00X+038020Y+104719X0160Y         S0      
317GND              VIA   -    MD0080PA00X+036725Y+105038X0160Y         S0      
317GND              VIA   -    MD0080PA00X+037465Y+104400X0160Y         S0      
317GND              VIA   -    MD0080PA00X+037465Y+103762X0160Y         S0      
317GND              VIA   -    MD0080PA00X+038020Y+103443X0160Y         S0      
317GND              VIA   -    MD0080PA00X+038020Y+104081X0160Y         S0      
317GND              VIA   -    MD0080PA00X+037465Y+103124X0160Y         S0      
317GND              VIA   -    MD0080PA00X+036910Y+104081X0160Y         S0      
317GND              VIA   -    MD0080PA00X+036910Y+103443X0160Y         S0      
317GND              VIA   -    MD0080PA00X+036725Y+104400X0160Y         S0      
317GND              VIA   -    MD0080PA00X+036725Y+103124X0160Y         S0      
317GND              VIA   -    MD0080PA00X+037465Y+106951X0160Y         S0      
317GND              VIA   -    MD0080PA00X+038020Y+107270X0160Y         S0      
317GND              VIA   -    MD0080PA00X+036910Y+107270X0160Y         S0      
317GND              VIA   -    MD0080PA00X+037465Y+106314X0160Y         S0      
317GND              VIA   -    MD0080PA00X+036725Y+106951X0160Y         S0      
317GND              VIA   -    MD0080PA00X+036725Y+106314X0160Y         S0      
317GND              VIA   -    MD0080PA00X+037465Y+108227X0160Y         S0      
317GND              VIA   -    MD0080PA00X+037465Y+108865X0160Y         S0      
317GND              VIA   -    MD0080PA00X+038020Y+108546X0160Y         S0      
317GND              VIA   -    MD0080PA00X+036910Y+107908X0160Y         S0      
317GND              VIA   -    MD0080PA00X+037465Y+107589X0160Y         S0      
317GND              VIA   -    MD0080PA00X+036725Y+108227X0160Y         S0      
317GND              VIA   -    MD0080PA00X+036725Y+108865X0160Y         S0      
317GND              VIA   -    MD0080PA00X+037465Y+111416X0160Y         S0      
317GND              VIA   -    MD0080PA00X+038020Y+111735X0160Y         S0      
317GND              VIA   -    MD0080PA00X+036910Y+111735X0160Y         S0      
317GND              VIA   -    MD0080PA00X+036910Y+111097X0160Y         S0      
317GND              VIA   -    MD0080PA00X+037465Y+110778X0160Y         S0      
317GND              VIA   -    MD0080PA00X+036725Y+110778X0160Y         S0      
317GND              VIA   -    MD0080PA00X+037465Y+110140X0160Y         S0      
317GND              VIA   -    MD0080PA00X+038020Y+109821X0160Y         S0      
317GND              VIA   -    MD0080PA00X+038020Y+110459X0160Y         S0      
317GND              VIA   -    MD0080PA00X+036910Y+109821X0160Y         S0      
317GND              VIA   -    MD0080PA00X+037465Y+109502X0160Y         S0      
317GND              VIA   -    MD0080PA00X+036910Y+109184X0160Y         S0      
317GND              VIA   -    MD0080PA00X+036725Y+110140X0160Y         S0      
317GND              VIA   -    MD0080PA00X+036910Y+113010X0160Y         S0      
317GND              VIA   -    MD0080PA00X+037465Y+113329X0160Y         S0      
317GND              VIA   -    MD0080PA00X+038020Y+113010X0160Y         S0      
317GND              VIA   -    MD0080PA00X+037465Y+112692X0160Y         S0      
317GND              VIA   -    MD0080PA00X+037465Y+112054X0160Y         S0      
317GND              VIA   -    MD0080PA00X+036725Y+112692X0160Y         S0      
317GND              VIA   -    MD0080PA00X+036725Y+112054X0160Y         S0      
317GND              VIA   -    MD0080PA00X+037650Y+116199X0160Y         S0      
317GND              VIA   -    MD0080PA00X+037465Y+115880X0160Y         S0      
317GND              VIA   -    MD0080PA00X+037835Y+115880X0160Y         S0      
317GND              VIA   -    MD0080PA00X+037465Y+115243X0160Y         S0      
317GND              VIA   -    MD0080PA00X+037280Y+115562X0160Y         S0      
317GND              VIA   -    MD0080PA00X+036910Y+115562X0160Y         S0      
317GND              VIA   -    MD0080PA00X+038020Y+115562X0160Y         S0      
317GND              VIA   -    MD0080PA00X+037465Y+114605X0160Y         S0      
317GND              VIA   -    MD0080PA00X+036910Y+114924X0160Y         S0      
317GND              VIA   -    MD0080PA00X+036910Y+113648X0160Y         S0      
317GND              VIA   -    MD0080PA00X+037465Y+113967X0160Y         S0      
317GND              VIA   -    MD0080PA00X+038020Y+114286X0160Y         S0      
317GND              VIA   -    MD0080PA00X+036725Y+114605X0160Y         S0      
317GND              VIA   -    MD0080PA00X+036725Y+113967X0160Y         S0      
317GND              VIA   -    MD0080PA00X+039382Y+088919X0160Y    R180 S0      
317GND              VIA   -    MD0080PA00X+038642Y+088919X0160Y    R180 S0      
317GND              VIA   -    MD0080PA00X+039012Y+089557X0160Y    R180 S0      
317GND              VIA   -    MD0080PA00X+039197Y+089238X0160Y    R180 S0      
317GND              VIA   -    MD0080PA00X+039012Y+088281X0160Y    R180 S0      
317GND              VIA   -    MD0080PA00X+038827Y+088600X0160Y    R180 S0      
317GND              VIA   -    MD0080PA00X+039382Y+088281X0160Y    R180 S0      
317GND              VIA   -    MD0080PA00X+038642Y+088281X0160Y    R180 S0      
317GND              VIA   -    MD0080PA00X+038457Y+088600X0160Y    R180 S0      
317GND              VIA   -    MD0080PA00X+038087Y+089238X0160Y    R180 S0      
317GND              VIA   -    MD0080PA00X+038272Y+088919X0160Y    R180 S0      
317GND              VIA   -    MD0080PA00X+038272Y+088281X0160Y    R180 S0      
317GND              VIA   -    MD0080PA00X+038457Y+087325X0160Y    R180 S0      
317GND              VIA   -    MD0080PA00X+038827Y+087962X0160Y    R180 S0      
317GND              VIA   -    MD0080PA00X+038642Y+087644X0160Y    R180 S0      
317GND              VIA   -    MD0080PA00X+039012Y+090832X0160Y    R180 S0      
317GND              VIA   -    MD0080PA00X+039197Y+091151X0160Y    R180 S0      
317GND              VIA   -    MD0080PA00X+039197Y+090514X0160Y    R180 S0      
317GND              VIA   -    MD0080PA00X+038642Y+090195X0160Y    R180 S0      
317GND              VIA   -    MD0080PA00X+039012Y+090195X0160Y    R180 S0      
317GND              VIA   -    MD0080PA00X+039197Y+089876X0160Y    R180 S0      
317GND              VIA   -    MD0080PA00X+039382Y+090195X0160Y    R180 S0      
317GND              VIA   -    MD0080PA00X+038087Y+090514X0160Y    R180 S0      
317GND              VIA   -    MD0080PA00X+038087Y+091151X0160Y    R180 S0      
317GND              VIA   -    MD0080PA00X+038087Y+089876X0160Y    R180 S0      
317GND              VIA   -    MD0080PA00X+038272Y+090195X0160Y    R180 S0      
317GND              VIA   -    MD0080PA00X+039012Y+094021X0160Y    R180 S0      
317GND              VIA   -    MD0080PA00X+039012Y+093384X0160Y    R180 S0      
317GND              VIA   -    MD0080PA00X+039197Y+093065X0160Y    R180 S0      
317GND              VIA   -    MD0080PA00X+039382Y+093384X0160Y    R180 S0      
317GND              VIA   -    MD0080PA00X+039012Y+092746X0160Y    R180 S0      
317GND              VIA   -    MD0080PA00X+039382Y+092746X0160Y    R180 S0      
317GND              VIA   -    MD0080PA00X+038642Y+093384X0160Y    R180 S0      
317GND              VIA   -    MD0080PA00X+038642Y+092746X0160Y    R180 S0      
317GND              VIA   -    MD0080PA00X+038087Y+093065X0160Y    R180 S0      
317GND              VIA   -    MD0080PA00X+038272Y+093384X0160Y    R180 S0      
317GND              VIA   -    MD0080PA00X+038272Y+092746X0160Y    R180 S0      
317GND              VIA   -    MD0080PA00X+039197Y+092427X0160Y    R180 S0      
317GND              VIA   -    MD0080PA00X+039012Y+092108X0160Y    R180 S0      
317GND              VIA   -    MD0080PA00X+039012Y+091470X0160Y    R180 S0      
317GND              VIA   -    MD0080PA00X+039382Y+091470X0160Y    R180 S0      
317GND              VIA   -    MD0080PA00X+039197Y+091789X0160Y    R180 S0      
317GND              VIA   -    MD0080PA00X+038642Y+091470X0160Y    R180 S0      
317GND              VIA   -    MD0080PA00X+038087Y+092427X0160Y    R180 S0      
317GND              VIA   -    MD0080PA00X+038087Y+091789X0160Y    R180 S0      
317GND              VIA   -    MD0080PA00X+038272Y+091470X0160Y    R180 S0      
317GND              VIA   -    MD0080PA00X+039012Y+095297X0160Y    R180 S0      
317GND              VIA   -    MD0080PA00X+039197Y+095616X0160Y    R180 S0      
317GND              VIA   -    MD0080PA00X+039012Y+094659X0160Y    R180 S0      
317GND              VIA   -    MD0080PA00X+039382Y+094659X0160Y    R180 S0      
317GND              VIA   -    MD0080PA00X+039197Y+094978X0160Y    R180 S0      
317GND              VIA   -    MD0080PA00X+039197Y+094340X0160Y    R180 S0      
317GND              VIA   -    MD0080PA00X+038642Y+094659X0160Y    R180 S0      
317GND              VIA   -    MD0080PA00X+038087Y+095616X0160Y    R180 S0      
317GND              VIA   -    MD0080PA00X+038087Y+094978X0160Y    R180 S0      
317GND              VIA   -    MD0080PA00X+038087Y+094340X0160Y    R180 S0      
317GND              VIA   -    MD0080PA00X+038272Y+094659X0160Y    R180 S0      
317GND              VIA   -    MD0080PA00X+039382Y+098486X0160Y    R180 S0      
317GND              VIA   -    MD0080PA00X+038642Y+097210X0160Y    R180 S0      
317GND              VIA   -    MD0080PA00X+039197Y+097529X0160Y    R180 S0      
317GND              VIA   -    MD0080PA00X+039197Y+098167X0160Y    R180 S0      
317GND              VIA   -    MD0080PA00X+038457Y+098167X0160Y    R180 S0      
317GND              VIA   -    MD0080PA00X+039012Y+097848X0160Y    R180 S0      
317GND              VIA   -    MD0080PA00X+039012Y+097210X0160Y    R180 S0      
317GND              VIA   -    MD0080PA00X+039382Y+097210X0160Y    R180 S0      
317GND              VIA   -    MD0080PA00X+038087Y+097529X0160Y    R180 S0      
317GND              VIA   -    MD0080PA00X+038272Y+097210X0160Y    R180 S0      
317GND              VIA   -    MD0080PA00X+038642Y+098486X0160Y    R180 S0      
317GND              VIA   -    MD0080PA00X+039197Y+096892X0160Y    R180 S0      
317GND              VIA   -    MD0080PA00X+039197Y+096254X0160Y    R180 S0      
317GND              VIA   -    MD0080PA00X+038642Y+095935X0160Y    R180 S0      
317GND              VIA   -    MD0080PA00X+039012Y+096573X0160Y    R180 S0      
317GND              VIA   -    MD0080PA00X+039012Y+095935X0160Y    R180 S0      
317GND              VIA   -    MD0080PA00X+039382Y+095935X0160Y    R180 S0      
317GND              VIA   -    MD0080PA00X+038087Y+096892X0160Y    R180 S0      
317GND              VIA   -    MD0080PA00X+038087Y+096254X0160Y    R180 S0      
317GND              VIA   -    MD0080PA00X+038272Y+095935X0160Y    R180 S0      
317GND              VIA   -    MD0080PA00X+039315Y+105038X0160Y         S0      
317GND              VIA   -    MD0080PA00X+039315Y+105676X0160Y         S0      
317GND              VIA   -    MD0080PA00X+038575Y+105038X0160Y         S0      
317GND              VIA   -    MD0080PA00X+039500Y+105357X0160Y         S0      
317GND              VIA   -    MD0080PA00X+039130Y+105995X0160Y         S0      
317GND              VIA   -    MD0080PA00X+038760Y+105357X0160Y         S0      
317GND              VIA   -    MD0080PA00X+038760Y+104719X0160Y         S0      
317GND              VIA   -    MD0080PA00X+039500Y+104719X0160Y         S0      
317GND              VIA   -    MD0080PA00X+039315Y+103762X0160Y         S0      
317GND              VIA   -    MD0080PA00X+039315Y+103124X0160Y         S0      
317GND              VIA   -    MD0080PA00X+039500Y+103443X0160Y         S0      
317GND              VIA   -    MD0080PA00X+038760Y+104081X0160Y         S0      
317GND              VIA   -    MD0080PA00X+038760Y+103443X0160Y         S0      
317GND              VIA   -    MD0080PA00X+039500Y+104081X0160Y         S0      
317GND              VIA   -    MD0080PA00X+038575Y+104400X0160Y         S0      
317GND              VIA   -    MD0080PA00X+038575Y+103762X0160Y         S0      
317GND              VIA   -    MD0080PA00X+038575Y+103124X0160Y         S0      
317GND              VIA   -    MD0080PA00X+039315Y+104400X0160Y         S0      
317GND              VIA   -    MD0080PA00X+039500Y+102806X0160Y         S0      
317GND              VIA   -    MD0080PA00X+038760Y+102806X0160Y         S0      
317GND              VIA   -    MD0080PA00X+038457Y+100718X0160Y    R180 S0      
317GND              VIA   -    MD0080PA00X+039567Y+100718X0160Y    R180 S0      
317GND              VIA   -    MD0080PA00X+039382Y+100399X0160Y    R180 S0      
317GND              VIA   -    MD0080PA00X+039197Y+100718X0160Y    R180 S0      
317GND              VIA   -    MD0080PA00X+039012Y+101037X0160Y    R180 S0      
317GND              VIA   -    MD0080PA00X+038272Y+101037X0160Y    R180 S0      
317GND              VIA   -    MD0080PA00X+038642Y+100399X0160Y    R180 S0      
317GND              VIA   -    MD0080PA00X+039382Y+099762X0160Y    R180 S0      
317GND              VIA   -    MD0080PA00X+038457Y+100080X0160Y    R180 S0      
317GND              VIA   -    MD0080PA00X+039197Y+100080X0160Y    R180 S0      
317GND              VIA   -    MD0080PA00X+038642Y+099762X0160Y    R180 S0      
317GND              VIA   -    MD0080PA00X+038642Y+099124X0160Y    R180 S0      
317GND              VIA   -    MD0080PA00X+039382Y+099124X0160Y    R180 S0      
317GND              VIA   -    MD0080PA00X+039197Y+099443X0160Y    R180 S0      
317GND              VIA   -    MD0080PA00X+038457Y+098805X0160Y    R180 S0      
317GND              VIA   -    MD0080PA00X+038457Y+099443X0160Y    R180 S0      
317GND              VIA   -    MD0080PA00X+039197Y+098805X0160Y    R180 S0      
317GND              VIA   -    MD0080PA00X+039315Y+106951X0160Y         S0      
317GND              VIA   -    MD0080PA00X+039130Y+106632X0160Y         S0      
317GND              VIA   -    MD0080PA00X+039130Y+107270X0160Y         S0      
317GND              VIA   -    MD0080PA00X+038390Y+106632X0160Y         S0      
317GND              VIA   -    MD0080PA00X+038760Y+106632X0160Y         S0      
317GND              VIA   -    MD0080PA00X+039500Y+106632X0160Y         S0      
317GND              VIA   -    MD0080PA00X+039315Y+106314X0160Y         S0      
317GND              VIA   -    MD0080PA00X+038205Y+106951X0160Y         S0      
317GND              VIA   -    MD0080PA00X+038205Y+106314X0160Y         S0      
317GND              VIA   -    MD0080PA00X+038390Y+110459X0160Y         S0      
317GND              VIA   -    MD0080PA00X+038760Y+110459X0160Y         S0      
317GND              VIA   -    MD0080PA00X+039500Y+110459X0160Y         S0      
317GND              VIA   -    MD0080PA00X+039130Y+110459X0160Y         S0      
317GND              VIA   -    MD0080PA00X+039130Y+109821X0160Y         S0      
317GND              VIA   -    MD0080PA00X+038760Y+109184X0160Y         S0      
317GND              VIA   -    MD0080PA00X+039500Y+109184X0160Y         S0      
317GND              VIA   -    MD0080PA00X+039130Y+109184X0160Y         S0      
317GND              VIA   -    MD0080PA00X+039315Y+109502X0160Y         S0      
317GND              VIA   -    MD0080PA00X+038390Y+109184X0160Y         S0      
317GND              VIA   -    MD0080PA00X+038205Y+109502X0160Y         S0      
317GND              VIA   -    MD0080PA00X+039315Y+108865X0160Y         S0      
317GND              VIA   -    MD0080PA00X+039130Y+108546X0160Y         S0      
317GND              VIA   -    MD0080PA00X+039315Y+108227X0160Y         S0      
317GND              VIA   -    MD0080PA00X+039500Y+107908X0160Y         S0      
317GND              VIA   -    MD0080PA00X+039130Y+107908X0160Y         S0      
317GND              VIA   -    MD0080PA00X+038390Y+107908X0160Y         S0      
317GND              VIA   -    MD0080PA00X+038760Y+107908X0160Y         S0      
317GND              VIA   -    MD0080PA00X+039315Y+107589X0160Y         S0      
317GND              VIA   -    MD0080PA00X+038205Y+108227X0160Y         S0      
317GND              VIA   -    MD0080PA00X+038205Y+108865X0160Y         S0      
317GND              VIA   -    MD0080PA00X+038205Y+107589X0160Y         S0      
317GND              VIA   -    MD0080PA00X+039315Y+113329X0160Y         S0      
317GND              VIA   -    MD0080PA00X+039315Y+112054X0160Y         S0      
317GND              VIA   -    MD0080PA00X+039500Y+112373X0160Y         S0      
317GND              VIA   -    MD0080PA00X+039130Y+112373X0160Y         S0      
317GND              VIA   -    MD0080PA00X+039315Y+112692X0160Y         S0      
317GND              VIA   -    MD0080PA00X+038760Y+112373X0160Y         S0      
317GND              VIA   -    MD0080PA00X+038390Y+112373X0160Y         S0      
317GND              VIA   -    MD0080PA00X+038205Y+113329X0160Y         S0      
317GND              VIA   -    MD0080PA00X+038205Y+112054X0160Y         S0      
317GND              VIA   -    MD0080PA00X+038205Y+112692X0160Y         S0      
317GND              VIA   -    MD0080PA00X+039315Y+111416X0160Y         S0      
317GND              VIA   -    MD0080PA00X+039130Y+111735X0160Y         S0      
317GND              VIA   -    MD0080PA00X+039500Y+111097X0160Y         S0      
317GND              VIA   -    MD0080PA00X+039130Y+111097X0160Y         S0      
317GND              VIA   -    MD0080PA00X+039315Y+110778X0160Y         S0      
317GND              VIA   -    MD0080PA00X+038760Y+111097X0160Y         S0      
317GND              VIA   -    MD0080PA00X+038390Y+111097X0160Y         S0      
317GND              VIA   -    MD0080PA00X+038205Y+111416X0160Y         S0      
317GND              VIA   -    MD0080PA00X+038205Y+110778X0160Y         S0      
317GND              VIA   -    MD0080PA00X+038760Y+114924X0160Y         S0      
317GND              VIA   -    MD0080PA00X+038390Y+114924X0160Y         S0      
317GND              VIA   -    MD0080PA00X+039500Y+114924X0160Y         S0      
317GND              VIA   -    MD0080PA00X+039315Y+114605X0160Y         S0      
317GND              VIA   -    MD0080PA00X+039130Y+114286X0160Y         S0      
317GND              VIA   -    MD0080PA00X+038760Y+113648X0160Y         S0      
317GND              VIA   -    MD0080PA00X+038390Y+113648X0160Y         S0      
317GND              VIA   -    MD0080PA00X+039130Y+113648X0160Y         S0      
317GND              VIA   -    MD0080PA00X+039500Y+113648X0160Y         S0      
317GND              VIA   -    MD0080PA00X+039315Y+113967X0160Y         S0      
317GND              VIA   -    MD0080PA00X+038205Y+114605X0160Y         S0      
317GND              VIA   -    MD0080PA00X+038205Y+113967X0160Y         S0      
317GND              VIA   -    MD0080PA00X+038760Y+116199X0160Y         S0      
317GND              VIA   -    MD0080PA00X+038760Y+115562X0160Y         S0      
317GND              VIA   -    MD0080PA00X+038390Y+115562X0160Y         S0      
317GND              VIA   -    MD0080PA00X+039500Y+115562X0160Y         S0      
317GND              VIA   -    MD0080PA00X+039130Y+115562X0160Y         S0      
317GND              VIA   -    MD0080PA00X+038945Y+115880X0160Y         S0      
317GND              VIA   -    MD0080PA00X+040308Y+089238X0160Y    R180 S0      
317GND              VIA   -    MD0080PA00X+040492Y+088919X0160Y    R180 S0      
317GND              VIA   -    MD0080PA00X+040863Y+088919X0160Y    R180 S0      
317GND              VIA   -    MD0080PA00X+040122Y+089557X0160Y    R180 S0      
317GND              VIA   -    MD0080PA00X+040492Y+088281X0160Y    R180 S0      
317GND              VIA   -    MD0080PA00X+040863Y+088281X0160Y    R180 S0      
317GND              VIA   -    MD0080PA00X+040122Y+088281X0160Y    R180 S0      
317GND              VIA   -    MD0080PA00X+039752Y+088919X0160Y    R180 S0      
317GND              VIA   -    MD0080PA00X+039752Y+088281X0160Y    R180 S0      
317GND              VIA   -    MD0080PA00X+039937Y+087962X0160Y    R180 S0      
317GND              VIA   -    MD0080PA00X+039937Y+087325X0160Y    R180 S0      
317GND              VIA   -    MD0080PA00X+039752Y+087644X0160Y    R180 S0      
317GND              VIA   -    MD0080PA00X+041048Y+087325X0160Y    R180 S0      
317GND              VIA   -    MD0080PA00X+040122Y+092746X0160Y    R180 S0      
317GND              VIA   -    MD0080PA00X+039752Y+093384X0160Y    R180 S0      
317GND              VIA   -    MD0080PA00X+039752Y+092746X0160Y    R180 S0      
317GND              VIA   -    MD0080PA00X+040308Y+092427X0160Y    R180 S0      
317GND              VIA   -    MD0080PA00X+040122Y+092108X0160Y    R180 S0      
317GND              VIA   -    MD0080PA00X+040492Y+091470X0160Y    R180 S0      
317GND              VIA   -    MD0080PA00X+040308Y+091789X0160Y    R180 S0      
317GND              VIA   -    MD0080PA00X+040863Y+091470X0160Y    R180 S0      
317GND              VIA   -    MD0080PA00X+040122Y+091470X0160Y    R180 S0      
317GND              VIA   -    MD0080PA00X+039752Y+091470X0160Y    R180 S0      
317GND              VIA   -    MD0080PA00X+040308Y+091151X0160Y    R180 S0      
317GND              VIA   -    MD0080PA00X+040308Y+090514X0160Y    R180 S0      
317GND              VIA   -    MD0080PA00X+040308Y+089876X0160Y    R180 S0      
317GND              VIA   -    MD0080PA00X+040492Y+090195X0160Y    R180 S0      
317GND              VIA   -    MD0080PA00X+040863Y+090195X0160Y    R180 S0      
317GND              VIA   -    MD0080PA00X+040122Y+090195X0160Y    R180 S0      
317GND              VIA   -    MD0080PA00X+039752Y+090195X0160Y    R180 S0      
317GND              VIA   -    MD0080PA00X+040308Y+095616X0160Y    R180 S0      
317GND              VIA   -    MD0080PA00X+040122Y+095297X0160Y    R180 S0      
317GND              VIA   -    MD0080PA00X+040492Y+094659X0160Y    R180 S0      
317GND              VIA   -    MD0080PA00X+040308Y+094978X0160Y    R180 S0      
317GND              VIA   -    MD0080PA00X+040863Y+094659X0160Y    R180 S0      
317GND              VIA   -    MD0080PA00X+040308Y+094340X0160Y    R180 S0      
317GND              VIA   -    MD0080PA00X+040122Y+094659X0160Y    R180 S0      
317GND              VIA   -    MD0080PA00X+039752Y+094659X0160Y    R180 S0      
317GND              VIA   -    MD0080PA00X+040122Y+094021X0160Y    R180 S0      
317GND              VIA   -    MD0080PA00X+040308Y+093065X0160Y    R180 S0      
317GND              VIA   -    MD0080PA00X+040492Y+092746X0160Y    R180 S0      
317GND              VIA   -    MD0080PA00X+040863Y+092746X0160Y    R180 S0      
317GND              VIA   -    MD0080PA00X+040122Y+093384X0160Y    R180 S0      
317GND              VIA   -    MD0080PA00X+040492Y+101037X0160Y    R180 S0      
317GND              VIA   -    MD0080PA00X+041046Y+100718X0160Y    R180 S0      
317GND              VIA   -    MD0080PA00X+040122Y+100399X0160Y    R180 S0      
317GND              VIA   -    MD0080PA00X+039937Y+100718X0160Y    R180 S0      
317GND              VIA   -    MD0080PA00X+039752Y+101037X0160Y    R180 S0      
317GND              VIA   -    MD0080PA00X+040861Y+099761X0160Y    R180 S0      
317GND              VIA   -    MD0080PA00X+039937Y+100080X0160Y    R180 S0      
317GND              VIA   -    MD0080PA00X+040122Y+099762X0160Y    R180 S0      
317GND              VIA   -    MD0080PA00X+040122Y+099124X0160Y    R180 S0      
317GND              VIA   -    MD0080PA00X+040678Y+098805X0160Y    R180 S0      
317GND              VIA   -    MD0080PA00X+039937Y+099443X0160Y    R180 S0      
317GND              VIA   -    MD0080PA00X+039937Y+098805X0160Y    R180 S0      
317GND              VIA   -    MD0080PA00X+040863Y+099124X0160Y    R180 S0      
317GND              VIA   -    MD0080PA00X+040863Y+098486X0160Y    R180 S0      
317GND              VIA   -    MD0080PA00X+040122Y+098486X0160Y    R180 S0      
317GND              VIA   -    MD0080PA00X+040308Y+097529X0160Y    R180 S0      
317GND              VIA   -    MD0080PA00X+040122Y+097848X0160Y    R180 S0      
317GND              VIA   -    MD0080PA00X+040678Y+098167X0160Y    R180 S0      
317GND              VIA   -    MD0080PA00X+039937Y+098167X0160Y    R180 S0      
317GND              VIA   -    MD0080PA00X+040492Y+097210X0160Y    R180 S0      
317GND              VIA   -    MD0080PA00X+040863Y+097210X0160Y    R180 S0      
317GND              VIA   -    MD0080PA00X+040122Y+097210X0160Y    R180 S0      
317GND              VIA   -    MD0080PA00X+039752Y+097210X0160Y    R180 S0      
317GND              VIA   -    MD0080PA00X+040308Y+096892X0160Y    R180 S0      
317GND              VIA   -    MD0080PA00X+040308Y+096254X0160Y    R180 S0      
317GND              VIA   -    MD0080PA00X+040492Y+095935X0160Y    R180 S0      
317GND              VIA   -    MD0080PA00X+040863Y+095935X0160Y    R180 S0      
317GND              VIA   -    MD0080PA00X+040122Y+095935X0160Y    R180 S0      
317GND              VIA   -    MD0080PA00X+040122Y+096573X0160Y    R180 S0      
317GND              VIA   -    MD0080PA00X+039752Y+095935X0160Y    R180 S0      
317GND              VIA   -    MD0080PA00X+040796Y+105038X0160Y         S0      
317GND              VIA   -    MD0080PA00X+040056Y+105038X0160Y         S0      
317GND              VIA   -    MD0080PA00X+040056Y+105676X0160Y         S0      
317GND              VIA   -    MD0080PA00X+040981Y+105357X0160Y         S0      
317GND              VIA   -    MD0080PA00X+040241Y+105995X0160Y         S0      
317GND              VIA   -    MD0080PA00X+040796Y+105676X0160Y         S0      
317GND              VIA   -    MD0080PA00X+040241Y+105357X0160Y         S0      
317GND              VIA   -    MD0080PA00X+040981Y+104719X0160Y         S0      
317GND              VIA   -    MD0080PA00X+040241Y+104719X0160Y         S0      
317GND              VIA   -    MD0080PA00X+040980Y+104082X0160Y         S0      
317GND              VIA   -    MD0080PA00X+040980Y+103444X0160Y         S0      
317GND              VIA   -    MD0080PA00X+040056Y+104400X0160Y         S0      
317GND              VIA   -    MD0080PA00X+040056Y+103762X0160Y         S0      
317GND              VIA   -    MD0080PA00X+040056Y+103124X0160Y         S0      
317GND              VIA   -    MD0080PA00X+040241Y+104081X0160Y         S0      
317GND              VIA   -    MD0080PA00X+039870Y+103443X0160Y         S0      
317GND              VIA   -    MD0080PA00X+040980Y+102806X0160Y         S0      
317GND              VIA   -    MD0080PA00X+039870Y+102806X0160Y         S0      
317GND              VIA   -    MD0080PA00X+040241Y+106632X0160Y         S0      
317GND              VIA   -    MD0080PA00X+040981Y+106632X0160Y         S0      
317GND              VIA   -    MD0080PA00X+040611Y+106632X0160Y         S0      
317GND              VIA   -    MD0080PA00X+040426Y+106951X0160Y         S0      
317GND              VIA   -    MD0080PA00X+040241Y+107270X0160Y         S0      
317GND              VIA   -    MD0080PA00X+040426Y+106314X0160Y         S0      
317GND              VIA   -    MD0080PA00X+039870Y+106632X0160Y         S0      
317GND              VIA   -    MD0080PA00X+040426Y+108227X0160Y         S0      
317GND              VIA   -    MD0080PA00X+040241Y+108546X0160Y         S0      
317GND              VIA   -    MD0080PA00X+040426Y+108865X0160Y         S0      
317GND              VIA   -    MD0080PA00X+040241Y+107908X0160Y         S0      
317GND              VIA   -    MD0080PA00X+040981Y+107908X0160Y         S0      
317GND              VIA   -    MD0080PA00X+040611Y+107908X0160Y         S0      
317GND              VIA   -    MD0080PA00X+040426Y+107589X0160Y         S0      
317GND              VIA   -    MD0080PA00X+039870Y+107908X0160Y         S0      
317GND              VIA   -    MD0080PA00X+040241Y+110459X0160Y         S0      
317GND              VIA   -    MD0080PA00X+040241Y+109821X0160Y         S0      
317GND              VIA   -    MD0080PA00X+040241Y+109184X0160Y         S0      
317GND              VIA   -    MD0080PA00X+040981Y+109184X0160Y         S0      
317GND              VIA   -    MD0080PA00X+040611Y+109184X0160Y         S0      
317GND              VIA   -    MD0080PA00X+040426Y+109502X0160Y         S0      
317GND              VIA   -    MD0080PA00X+039870Y+110459X0160Y         S0      
317GND              VIA   -    MD0080PA00X+039870Y+109184X0160Y         S0      
317GND              VIA   -    MD0080PA00X+040241Y+111735X0160Y         S0      
317GND              VIA   -    MD0080PA00X+040426Y+111416X0160Y         S0      
317GND              VIA   -    MD0080PA00X+040241Y+111097X0160Y         S0      
317GND              VIA   -    MD0080PA00X+040981Y+111097X0160Y         S0      
317GND              VIA   -    MD0080PA00X+040611Y+111097X0160Y         S0      
317GND              VIA   -    MD0080PA00X+040426Y+110778X0160Y         S0      
317GND              VIA   -    MD0080PA00X+039870Y+111097X0160Y         S0      
317GND              VIA   -    MD0080PA00X+040241Y+113010X0160Y         S0      
317GND              VIA   -    MD0080PA00X+040426Y+113329X0160Y         S0      
317GND              VIA   -    MD0080PA00X+040426Y+112692X0160Y         S0      
317GND              VIA   -    MD0080PA00X+040241Y+112373X0160Y         S0      
317GND              VIA   -    MD0080PA00X+040426Y+112054X0160Y         S0      
317GND              VIA   -    MD0080PA00X+040981Y+112373X0160Y         S0      
317GND              VIA   -    MD0080PA00X+040611Y+112373X0160Y         S0      
317GND              VIA   -    MD0080PA00X+039870Y+112373X0160Y         S0      
317GND              VIA   -    MD0080PA00X+040056Y+116518X0160Y         S0      
317GND              VIA   -    MD0080PA00X+040981Y+116199X0160Y         S0      
317GND              VIA   -    MD0080PA00X+040056Y+115880X0160Y         S0      
317GND              VIA   -    MD0080PA00X+040241Y+115562X0160Y         S0      
317GND              VIA   -    MD0080PA00X+040981Y+115562X0160Y         S0      
317GND              VIA   -    MD0080PA00X+040611Y+115562X0160Y         S0      
317GND              VIA   -    MD0080PA00X+039870Y+116199X0160Y         S0      
317GND              VIA   -    MD0080PA00X+039870Y+115562X0160Y         S0      
317GND              VIA   -    MD0080PA00X+040981Y+114924X0160Y         S0      
317GND              VIA   -    MD0080PA00X+040611Y+114924X0160Y         S0      
317GND              VIA   -    MD0080PA00X+040426Y+114605X0160Y         S0      
317GND              VIA   -    MD0080PA00X+040241Y+113648X0160Y         S0      
317GND              VIA   -    MD0080PA00X+040981Y+113648X0160Y         S0      
317GND              VIA   -    MD0080PA00X+040611Y+113648X0160Y         S0      
317GND              VIA   -    MD0080PA00X+040426Y+113967X0160Y         S0      
317GND              VIA   -    MD0080PA00X+040241Y+114286X0160Y         S0      
317GND              VIA   -    MD0080PA00X+039870Y+114924X0160Y         S0      
317GND              VIA   -    MD0080PA00X+039870Y+113648X0160Y         S0      
317GND              VIA   -    MD0080PA00X+042528Y+091151X0160Y    R180 S0      
317GND              VIA   -    MD0080PA00X+042528Y+090514X0160Y    R180 S0      
317GND              VIA   -    MD0080PA00X+041603Y+090195X0160Y    R180 S0      
317GND              VIA   -    MD0080PA00X+041973Y+090195X0160Y    R180 S0      
317GND              VIA   -    MD0080PA00X+042528Y+089876X0160Y    R180 S0      
317GND              VIA   -    MD0080PA00X+042343Y+090195X0160Y    R180 S0      
317GND              VIA   -    MD0080PA00X+041233Y+090832X0160Y    R180 S0      
317GND              VIA   -    MD0080PA00X+041418Y+091151X0160Y    R180 S0      
317GND              VIA   -    MD0080PA00X+041418Y+090514X0160Y    R180 S0      
317GND              VIA   -    MD0080PA00X+041418Y+089876X0160Y    R180 S0      
317GND              VIA   -    MD0080PA00X+041233Y+090195X0160Y    R180 S0      
317GND              VIA   -    MD0080PA00X+041973Y+088919X0160Y    R180 S0      
317GND              VIA   -    MD0080PA00X+041603Y+088919X0160Y    R180 S0      
317GND              VIA   -    MD0080PA00X+042528Y+089238X0160Y    R180 S0      
317GND              VIA   -    MD0080PA00X+042343Y+089557X0160Y    R180 S0      
317GND              VIA   -    MD0080PA00X+041603Y+088281X0160Y    R180 S0      
317GND              VIA   -    MD0080PA00X+041973Y+088281X0160Y    R180 S0      
317GND              VIA   -    MD0080PA00X+041418Y+089238X0160Y    R180 S0      
317GND              VIA   -    MD0080PA00X+041233Y+089557X0160Y    R180 S0      
317GND              VIA   -    MD0080PA00X+041233Y+088281X0160Y    R180 S0      
317GND              VIA   -    MD0080PA00X+042158Y+087325X0160Y    R180 S0      
317GND              VIA   -    MD0080PA00X+042343Y+094021X0160Y    R180 S0      
317GND              VIA   -    MD0080PA00X+042528Y+093702X0160Y    R180 S0      
317GND              VIA   -    MD0080PA00X+041603Y+093384X0160Y    R180 S0      
317GND              VIA   -    MD0080PA00X+041603Y+092746X0160Y    R180 S0      
317GND              VIA   -    MD0080PA00X+041973Y+093384X0160Y    R180 S0      
317GND              VIA   -    MD0080PA00X+042528Y+093065X0160Y    R180 S0      
317GND              VIA   -    MD0080PA00X+042343Y+093384X0160Y    R180 S0      
317GND              VIA   -    MD0080PA00X+041973Y+092746X0160Y    R180 S0      
317GND              VIA   -    MD0080PA00X+042343Y+092746X0160Y    R180 S0      
317GND              VIA   -    MD0080PA00X+041418Y+093702X0160Y    R180 S0      
317GND              VIA   -    MD0080PA00X+041233Y+094021X0160Y    R180 S0      
317GND              VIA   -    MD0080PA00X+041418Y+093065X0160Y    R180 S0      
317GND              VIA   -    MD0080PA00X+041233Y+093384X0160Y    R180 S0      
317GND              VIA   -    MD0080PA00X+041233Y+092746X0160Y    R180 S0      
317GND              VIA   -    MD0080PA00X+042343Y+092108X0160Y    R180 S0      
317GND              VIA   -    MD0080PA00X+042528Y+092427X0160Y    R180 S0      
317GND              VIA   -    MD0080PA00X+042528Y+091789X0160Y    R180 S0      
317GND              VIA   -    MD0080PA00X+041603Y+091470X0160Y    R180 S0      
317GND              VIA   -    MD0080PA00X+041973Y+091470X0160Y    R180 S0      
317GND              VIA   -    MD0080PA00X+042343Y+091470X0160Y    R180 S0      
317GND              VIA   -    MD0080PA00X+041233Y+092108X0160Y    R180 S0      
317GND              VIA   -    MD0080PA00X+041418Y+092427X0160Y    R180 S0      
317GND              VIA   -    MD0080PA00X+041233Y+091470X0160Y    R180 S0      
317GND              VIA   -    MD0080PA00X+041418Y+091789X0160Y    R180 S0      
317GND              VIA   -    MD0080PA00X+042528Y+097529X0160Y    R180 S0      
317GND              VIA   -    MD0080PA00X+042158Y+098167X0160Y    R180 S0      
317GND              VIA   -    MD0080PA00X+042343Y+097848X0160Y    R180 S0      
317GND              VIA   -    MD0080PA00X+041233Y+097210X0160Y    R180 S0      
317GND              VIA   -    MD0080PA00X+041418Y+097529X0160Y    R180 S0      
317GND              VIA   -    MD0080PA00X+041418Y+098167X0160Y    R180 S0      
317GND              VIA   -    MD0080PA00X+041233Y+097848X0160Y    R180 S0      
317GND              VIA   -    MD0080PA00X+042528Y+096892X0160Y    R180 S0      
317GND              VIA   -    MD0080PA00X+042528Y+096254X0160Y    R180 S0      
317GND              VIA   -    MD0080PA00X+041973Y+095935X0160Y    R180 S0      
317GND              VIA   -    MD0080PA00X+042343Y+095935X0160Y    R180 S0      
317GND              VIA   -    MD0080PA00X+041603Y+095935X0160Y    R180 S0      
317GND              VIA   -    MD0080PA00X+042343Y+096573X0160Y    R180 S0      
317GND              VIA   -    MD0080PA00X+041418Y+096892X0160Y    R180 S0      
317GND              VIA   -    MD0080PA00X+041418Y+096254X0160Y    R180 S0      
317GND              VIA   -    MD0080PA00X+041233Y+095935X0160Y    R180 S0      
317GND              VIA   -    MD0080PA00X+041233Y+096573X0160Y    R180 S0      
317GND              VIA   -    MD0080PA00X+042528Y+095616X0160Y    R180 S0      
317GND              VIA   -    MD0080PA00X+042343Y+095297X0160Y    R180 S0      
317GND              VIA   -    MD0080PA00X+041973Y+094659X0160Y    R180 S0      
317GND              VIA   -    MD0080PA00X+042343Y+094659X0160Y    R180 S0      
317GND              VIA   -    MD0080PA00X+042528Y+094978X0160Y    R180 S0      
317GND              VIA   -    MD0080PA00X+042528Y+094340X0160Y    R180 S0      
317GND              VIA   -    MD0080PA00X+041603Y+094659X0160Y    R180 S0      
317GND              VIA   -    MD0080PA00X+041418Y+095616X0160Y    R180 S0      
317GND              VIA   -    MD0080PA00X+041233Y+095297X0160Y    R180 S0      
317GND              VIA   -    MD0080PA00X+041418Y+094340X0160Y    R180 S0      
317GND              VIA   -    MD0080PA00X+041233Y+094659X0160Y    R180 S0      
317GND              VIA   -    MD0080PA00X+041418Y+094978X0160Y    R180 S0      
317GND              VIA   -    MD0080PA00X+042276Y+105038X0160Y         S0      
317GND              VIA   -    MD0080PA00X+041536Y+105038X0160Y         S0      
317GND              VIA   -    MD0080PA00X+041536Y+105676X0160Y         S0      
317GND              VIA   -    MD0080PA00X+041721Y+105357X0160Y         S0      
317GND              VIA   -    MD0080PA00X+042461Y+105995X0160Y         S0      
317GND              VIA   -    MD0080PA00X+042276Y+105676X0160Y         S0      
317GND              VIA   -    MD0080PA00X+042461Y+105357X0160Y         S0      
317GND              VIA   -    MD0080PA00X+042461Y+104719X0160Y         S0      
317GND              VIA   -    MD0080PA00X+041721Y+104719X0160Y         S0      
317GND              VIA   -    MD0080PA00X+041351Y+105995X0160Y         S0      
317GND              VIA   -    MD0080PA00X+041720Y+104082X0160Y         S0      
317GND              VIA   -    MD0080PA00X+042460Y+104082X0160Y         S0      
317GND              VIA   -    MD0080PA00X+041602Y+099761X0160Y    R180 S0      
317GND              VIA   -    MD0080PA00X+042342Y+099761X0160Y    R180 S0      
317GND              VIA   -    MD0080PA00X+041603Y+099124X0160Y    R180 S0      
317GND              VIA   -    MD0080PA00X+042343Y+099124X0160Y    R180 S0      
317GND              VIA   -    MD0080PA00X+042158Y+098805X0160Y    R180 S0      
317GND              VIA   -    MD0080PA00X+041418Y+098805X0160Y    R180 S0      
317GND              VIA   -    MD0080PA00X+042343Y+098486X0160Y    R180 S0      
317GND              VIA   -    MD0080PA00X+041603Y+098486X0160Y    R180 S0      
317GND              VIA   -    MD0080PA00X+041973Y+097210X0160Y    R180 S0      
317GND              VIA   -    MD0080PA00X+042343Y+097210X0160Y    R180 S0      
317GND              VIA   -    MD0080PA00X+041603Y+097210X0160Y    R180 S0      
317GND              VIA   -    MD0080PA00X+041536Y+106951X0160Y         S0      
317GND              VIA   -    MD0080PA00X+041721Y+106632X0160Y         S0      
317GND              VIA   -    MD0080PA00X+042091Y+106632X0160Y         S0      
317GND              VIA   -    MD0080PA00X+042461Y+106632X0160Y         S0      
317GND              VIA   -    MD0080PA00X+042461Y+107270X0160Y         S0      
317GND              VIA   -    MD0080PA00X+041536Y+106314X0160Y         S0      
317GND              VIA   -    MD0080PA00X+041351Y+106632X0160Y         S0      
317GND              VIA   -    MD0080PA00X+041351Y+107270X0160Y         S0      
317GND              VIA   -    MD0080PA00X+041536Y+110140X0160Y         S0      
317GND              VIA   -    MD0080PA00X+041721Y+110459X0160Y         S0      
317GND              VIA   -    MD0080PA00X+042461Y+109821X0160Y         S0      
317GND              VIA   -    MD0080PA00X+042461Y+110459X0160Y         S0      
317GND              VIA   -    MD0080PA00X+042091Y+110459X0160Y         S0      
317GND              VIA   -    MD0080PA00X+041721Y+109184X0160Y         S0      
317GND              VIA   -    MD0080PA00X+042461Y+109184X0160Y         S0      
317GND              VIA   -    MD0080PA00X+042091Y+109184X0160Y         S0      
317GND              VIA   -    MD0080PA00X+041536Y+109502X0160Y         S0      
317GND              VIA   -    MD0080PA00X+041351Y+110459X0160Y         S0      
317GND              VIA   -    MD0080PA00X+041351Y+109821X0160Y         S0      
317GND              VIA   -    MD0080PA00X+041351Y+109184X0160Y         S0      
317GND              VIA   -    MD0080PA00X+041536Y+108227X0160Y         S0      
317GND              VIA   -    MD0080PA00X+041536Y+108865X0160Y         S0      
317GND              VIA   -    MD0080PA00X+042461Y+108546X0160Y         S0      
317GND              VIA   -    MD0080PA00X+041721Y+107908X0160Y         S0      
317GND              VIA   -    MD0080PA00X+042461Y+107908X0160Y         S0      
317GND              VIA   -    MD0080PA00X+042091Y+107908X0160Y         S0      
317GND              VIA   -    MD0080PA00X+041536Y+107589X0160Y         S0      
317GND              VIA   -    MD0080PA00X+041351Y+108546X0160Y         S0      
317GND              VIA   -    MD0080PA00X+041351Y+107908X0160Y         S0      
317GND              VIA   -    MD0080PA00X+041351Y+113010X0160Y         S0      
317GND              VIA   -    MD0080PA00X+041351Y+112373X0160Y         S0      
317GND              VIA   -    MD0080PA00X+041536Y+111416X0160Y         S0      
317GND              VIA   -    MD0080PA00X+042461Y+111735X0160Y         S0      
317GND              VIA   -    MD0080PA00X+041721Y+111097X0160Y         S0      
317GND              VIA   -    MD0080PA00X+042091Y+111097X0160Y         S0      
317GND              VIA   -    MD0080PA00X+042461Y+111097X0160Y         S0      
317GND              VIA   -    MD0080PA00X+041536Y+110778X0160Y         S0      
317GND              VIA   -    MD0080PA00X+041351Y+111735X0160Y         S0      
317GND              VIA   -    MD0080PA00X+041351Y+111097X0160Y         S0      
317GND              VIA   -    MD0080PA00X+041536Y+114605X0160Y         S0      
317GND              VIA   -    MD0080PA00X+041721Y+114924X0160Y         S0      
317GND              VIA   -    MD0080PA00X+042091Y+114924X0160Y         S0      
317GND              VIA   -    MD0080PA00X+041721Y+113648X0160Y         S0      
317GND              VIA   -    MD0080PA00X+041536Y+113967X0160Y         S0      
317GND              VIA   -    MD0080PA00X+042091Y+113648X0160Y         S0      
317GND              VIA   -    MD0080PA00X+042461Y+113648X0160Y         S0      
317GND              VIA   -    MD0080PA00X+042461Y+114286X0160Y         S0      
317GND              VIA   -    MD0080PA00X+041351Y+113648X0160Y         S0      
317GND              VIA   -    MD0080PA00X+041351Y+114286X0160Y         S0      
317GND              VIA   -    MD0080PA00X+041536Y+113329X0160Y         S0      
317GND              VIA   -    MD0080PA00X+041721Y+112373X0160Y         S0      
317GND              VIA   -    MD0080PA00X+042091Y+112373X0160Y         S0      
317GND              VIA   -    MD0080PA00X+042461Y+112373X0160Y         S0      
317GND              VIA   -    MD0080PA00X+041536Y+112692X0160Y         S0      
317GND              VIA   -    MD0080PA00X+041536Y+112054X0160Y         S0      
317GND              VIA   -    MD0080PA00X+042091Y+116199X0160Y         S0      
317GND              VIA   -    MD0080PA00X+042276Y+116518X0160Y         S0      
317GND              VIA   -    MD0080PA00X+042276Y+115880X0160Y         S0      
317GND              VIA   -    MD0080PA00X+041721Y+115562X0160Y         S0      
317GND              VIA   -    MD0080PA00X+042091Y+115562X0160Y         S0      
317GND              VIA   -    MD0080PA00X+042461Y+115562X0160Y         S0      
317GND              VIA   -    MD0080PA00X+041166Y+115880X0160Y         S0      
317GND              VIA   -    MD0080PA00X+041351Y+115562X0160Y         S0      
317GND              VIA   -    MD0080PA00X+043453Y+090832X0160Y    R180 S0      
317GND              VIA   -    MD0080PA00X+043268Y+090514X0160Y    R180 S0      
317GND              VIA   -    MD0080PA00X+043453Y+090195X0160Y    R180 S0      
317GND              VIA   -    MD0080PA00X+042898Y+090514X0160Y    R180 S0      
317GND              VIA   -    MD0080PA00X+043453Y+088919X0160Y    R180 S0      
317GND              VIA   -    MD0080PA00X+043453Y+089557X0160Y    R180 S0      
317GND              VIA   -    MD0080PA00X+042713Y+088919X0160Y    R180 S0      
317GND              VIA   -    MD0080PA00X+043083Y+088919X0160Y    R180 S0      
317GND              VIA   -    MD0080PA00X+042713Y+088281X0160Y    R180 S0      
317GND              VIA   -    MD0080PA00X+043083Y+088281X0160Y    R180 S0      
317GND              VIA   -    MD0080PA00X+043268Y+087962X0160Y    R180 S0      
317GND              VIA   -    MD0080PA00X+043453Y+087644X0160Y    R180 S0      
317GND              VIA   -    MD0080PA00X+043453Y+095297X0160Y    R180 S0      
317GND              VIA   -    MD0080PA00X+043453Y+094659X0160Y    R180 S0      
317GND              VIA   -    MD0080PA00X+043268Y+094978X0160Y    R180 S0      
317GND              VIA   -    MD0080PA00X+042898Y+094978X0160Y    R180 S0      
317GND              VIA   -    MD0080PA00X+043453Y+094021X0160Y    R180 S0      
317GND              VIA   -    MD0080PA00X+043268Y+093702X0160Y    R180 S0      
317GND              VIA   -    MD0080PA00X+043453Y+093384X0160Y    R180 S0      
317GND              VIA   -    MD0080PA00X+043453Y+092746X0160Y    R180 S0      
317GND              VIA   -    MD0080PA00X+043268Y+093065X0160Y    R180 S0      
317GND              VIA   -    MD0080PA00X+042898Y+093702X0160Y    R180 S0      
317GND              VIA   -    MD0080PA00X+042898Y+093065X0160Y    R180 S0      
317GND              VIA   -    MD0080PA00X+043453Y+092108X0160Y    R180 S0      
317GND              VIA   -    MD0080PA00X+043453Y+091470X0160Y    R180 S0      
317GND              VIA   -    MD0080PA00X+043268Y+091789X0160Y    R180 S0      
317GND              VIA   -    MD0080PA00X+042898Y+091789X0160Y    R180 S0      
317GND              VIA   -    MD0080PA00X+043082Y+099761X0160Y    R180 S0      
317GND              VIA   -    MD0080PA00X+042898Y+098805X0160Y    R180 S0      
317GND              VIA   -    MD0080PA00X+043083Y+099124X0160Y    R180 S0      
317GND              VIA   -    MD0080PA00X+043453Y+097848X0160Y    R180 S0      
317GND              VIA   -    MD0080PA00X+043268Y+097529X0160Y    R180 S0      
317GND              VIA   -    MD0080PA00X+043453Y+097210X0160Y    R180 S0      
317GND              VIA   -    MD0080PA00X+043083Y+098486X0160Y    R180 S0      
317GND              VIA   -    MD0080PA00X+042898Y+097529X0160Y    R180 S0      
317GND              VIA   -    MD0080PA00X+042898Y+098167X0160Y    R180 S0      
317GND              VIA   -    MD0080PA00X+043453Y+096573X0160Y    R180 S0      
317GND              VIA   -    MD0080PA00X+043453Y+095935X0160Y    R180 S0      
317GND              VIA   -    MD0080PA00X+043268Y+096254X0160Y    R180 S0      
317GND              VIA   -    MD0080PA00X+042898Y+096254X0160Y    R180 S0      
317GND              VIA   -    MD0080PA00X+043571Y+105995X0160Y         S0      
317GND              VIA   -    MD0080PA00X+043201Y+105357X0160Y         S0      
317GND              VIA   -    MD0080PA00X+043201Y+104719X0160Y         S0      
317GND              VIA   -    MD0080PA00X+043016Y+105038X0160Y         S0      
317GND              VIA   -    MD0080PA00X+043016Y+105676X0160Y         S0      
317GND              VIA   -    MD0080PA00X+043386Y+108865X0160Y         S0      
317GND              VIA   -    MD0080PA00X+043571Y+108546X0160Y         S0      
317GND              VIA   -    MD0080PA00X+043571Y+107908X0160Y         S0      
317GND              VIA   -    MD0080PA00X+043386Y+107589X0160Y         S0      
317GND              VIA   -    MD0080PA00X+042646Y+108227X0160Y         S0      
317GND              VIA   -    MD0080PA00X+042646Y+108865X0160Y         S0      
317GND              VIA   -    MD0080PA00X+043016Y+108865X0160Y         S0      
317GND              VIA   -    MD0080PA00X+042646Y+107589X0160Y         S0      
317GND              VIA   -    MD0080PA00X+043016Y+107589X0160Y         S0      
317GND              VIA   -    MD0080PA00X+043571Y+106632X0160Y         S0      
317GND              VIA   -    MD0080PA00X+043571Y+107270X0160Y         S0      
317GND              VIA   -    MD0080PA00X+043386Y+106314X0160Y         S0      
317GND              VIA   -    MD0080PA00X+042646Y+106951X0160Y         S0      
317GND              VIA   -    MD0080PA00X+043016Y+106314X0160Y         S0      
317GND              VIA   -    MD0080PA00X+042646Y+106314X0160Y         S0      
317GND              VIA   -    MD0080PA00X+043571Y+111735X0160Y         S0      
317GND              VIA   -    MD0080PA00X+043571Y+111097X0160Y         S0      
317GND              VIA   -    MD0080PA00X+043386Y+110778X0160Y         S0      
317GND              VIA   -    MD0080PA00X+042646Y+111416X0160Y         S0      
317GND              VIA   -    MD0080PA00X+042646Y+110778X0160Y         S0      
317GND              VIA   -    MD0080PA00X+043016Y+110778X0160Y         S0      
317GND              VIA   -    MD0080PA00X+043386Y+110140X0160Y         S0      
317GND              VIA   -    MD0080PA00X+043571Y+110459X0160Y         S0      
317GND              VIA   -    MD0080PA00X+043571Y+109821X0160Y         S0      
317GND              VIA   -    MD0080PA00X+043571Y+109184X0160Y         S0      
317GND              VIA   -    MD0080PA00X+042646Y+110140X0160Y         S0      
317GND              VIA   -    MD0080PA00X+043016Y+110140X0160Y         S0      
317GND              VIA   -    MD0080PA00X+042646Y+109502X0160Y         S0      
317GND              VIA   -    MD0080PA00X+043571Y+116199X0160Y         S0      
317GND              VIA   -    MD0080PA00X+043571Y+115562X0160Y         S0      
317GND              VIA   -    MD0080PA00X+043016Y+115880X0160Y         S0      
317GND              VIA   -    MD0080PA00X+043201Y+114924X0160Y         S0      
317GND              VIA   -    MD0080PA00X+043571Y+114924X0160Y         S0      
317GND              VIA   -    MD0080PA00X+043571Y+114286X0160Y         S0      
317GND              VIA   -    MD0080PA00X+043571Y+113648X0160Y         S0      
317GND              VIA   -    MD0080PA00X+042831Y+114924X0160Y         S0      
317GND              VIA   -    MD0080PA00X+042646Y+114605X0160Y         S0      
317GND              VIA   -    MD0080PA00X+042646Y+113967X0160Y         S0      
317GND              VIA   -    MD0080PA00X+043386Y+113329X0160Y         S0      
317GND              VIA   -    MD0080PA00X+043571Y+113010X0160Y         S0      
317GND              VIA   -    MD0080PA00X+043386Y+112054X0160Y         S0      
317GND              VIA   -    MD0080PA00X+043571Y+112373X0160Y         S0      
317GND              VIA   -    MD0080PA00X+042646Y+113329X0160Y         S0      
317GND              VIA   -    MD0080PA00X+043016Y+113329X0160Y         S0      
317GND              VIA   -    MD0080PA00X+042646Y+112054X0160Y         S0      
317GND              VIA   -    MD0080PA00X+043016Y+112054X0160Y         S0      
317GND              VIA   -    MD0080PA00X+042646Y+112692X0160Y         S0      
317GND              VIA   -    MD0080PA00X+044746Y+087962X0160Y    R180 S0      
317GND              VIA   -    MD0080PA00X+044561Y+087644X0160Y    R180 S0      
317GND              VIA   -    MD0080PA00X+045116Y+093065X0160Y    R180 S0      
317GND              VIA   -    MD0080PA00X+044746Y+093065X0160Y    R180 S0      
317GND              VIA   -    MD0080PA00X+044561Y+094021X0160Y    R180 S0      
317GND              VIA   -    MD0080PA00X+044561Y+093384X0160Y    R180 S0      
317GND              VIA   -    MD0080PA00X+044561Y+092746X0160Y    R180 S0      
317GND              VIA   -    MD0080PA00X+045486Y+092427X0160Y    R180 S0      
317GND              VIA   -    MD0080PA00X+045486Y+091789X0160Y    R180 S0      
317GND              VIA   -    MD0080PA00X+045116Y+091789X0160Y    R180 S0      
317GND              VIA   -    MD0080PA00X+044746Y+091789X0160Y    R180 S0      
317GND              VIA   -    MD0080PA00X+044561Y+092108X0160Y    R180 S0      
317GND              VIA   -    MD0080PA00X+044561Y+091470X0160Y    R180 S0      
317GND              VIA   -    MD0080PA00X+044746Y+090514X0160Y    R180 S0      
317GND              VIA   -    MD0080PA00X+045486Y+091151X0160Y    R180 S0      
317GND              VIA   -    MD0080PA00X+045486Y+090514X0160Y    R180 S0      
317GND              VIA   -    MD0080PA00X+045116Y+090514X0160Y    R180 S0      
317GND              VIA   -    MD0080PA00X+045486Y+089876X0160Y    R180 S0      
317GND              VIA   -    MD0080PA00X+044561Y+090832X0160Y    R180 S0      
317GND              VIA   -    MD0080PA00X+044561Y+090195X0160Y    R180 S0      
317GND              VIA   -    MD0080PA00X+045486Y+089238X0160Y    R180 S0      
317GND              VIA   -    MD0080PA00X+045301Y+088919X0160Y    R180 S0      
317GND              VIA   -    MD0080PA00X+044931Y+088919X0160Y    R180 S0      
317GND              VIA   -    MD0080PA00X+045301Y+088281X0160Y    R180 S0      
317GND              VIA   -    MD0080PA00X+044561Y+089557X0160Y    R180 S0      
317GND              VIA   -    MD0080PA00X+044561Y+088919X0160Y    R180 S0      
317GND              VIA   -    MD0080PA00X+044561Y+088281X0160Y    R180 S0      
317GND              VIA   -    MD0080PA00X+045420Y+104082X0160Y         S0      
317GND              VIA   -    MD0080PA00X+045302Y+099761X0160Y    R180 S0      
317GND              VIA   -    MD0080PA00X+044562Y+099761X0160Y    R180 S0      
317GND              VIA   -    MD0080PA00X+044746Y+098805X0160Y    R180 S0      
317GND              VIA   -    MD0080PA00X+045486Y+098805X0160Y    R180 S0      
317GND              VIA   -    MD0080PA00X+045301Y+099124X0160Y    R180 S0      
317GND              VIA   -    MD0080PA00X+044561Y+099124X0160Y    R180 S0      
317GND              VIA   -    MD0080PA00X+045301Y+098486X0160Y    R180 S0      
317GND              VIA   -    MD0080PA00X+045486Y+097529X0160Y    R180 S0      
317GND              VIA   -    MD0080PA00X+044746Y+097529X0160Y    R180 S0      
317GND              VIA   -    MD0080PA00X+045116Y+097529X0160Y    R180 S0      
317GND              VIA   -    MD0080PA00X+045486Y+098167X0160Y    R180 S0      
317GND              VIA   -    MD0080PA00X+044746Y+098167X0160Y    R180 S0      
317GND              VIA   -    MD0080PA00X+044561Y+098486X0160Y    R180 S0      
317GND              VIA   -    MD0080PA00X+044561Y+097848X0160Y    R180 S0      
317GND              VIA   -    MD0080PA00X+044561Y+097210X0160Y    R180 S0      
317GND              VIA   -    MD0080PA00X+045486Y+096892X0160Y    R180 S0      
317GND              VIA   -    MD0080PA00X+044746Y+096254X0160Y    R180 S0      
317GND              VIA   -    MD0080PA00X+045116Y+096254X0160Y    R180 S0      
317GND              VIA   -    MD0080PA00X+045486Y+096254X0160Y    R180 S0      
317GND              VIA   -    MD0080PA00X+044561Y+096573X0160Y    R180 S0      
317GND              VIA   -    MD0080PA00X+044561Y+095935X0160Y    R180 S0      
317GND              VIA   -    MD0080PA00X+045486Y+095616X0160Y    R180 S0      
317GND              VIA   -    MD0080PA00X+045486Y+094978X0160Y    R180 S0      
317GND              VIA   -    MD0080PA00X+045116Y+094978X0160Y    R180 S0      
317GND              VIA   -    MD0080PA00X+045486Y+094340X0160Y    R180 S0      
317GND              VIA   -    MD0080PA00X+044746Y+094978X0160Y    R180 S0      
317GND              VIA   -    MD0080PA00X+044561Y+095297X0160Y    R180 S0      
317GND              VIA   -    MD0080PA00X+044561Y+094659X0160Y    R180 S0      
317GND              VIA   -    MD0080PA00X+045486Y+093702X0160Y    R180 S0      
317GND              VIA   -    MD0080PA00X+045116Y+093702X0160Y    R180 S0      
317GND              VIA   -    MD0080PA00X+044746Y+093702X0160Y    R180 S0      
317GND              VIA   -    MD0080PA00X+045486Y+093065X0160Y    R180 S0      
317GND              VIA   -    MD0080PA00X+044864Y+106314X0160Y         S0      
317GND              VIA   -    MD0080PA00X+045234Y+106314X0160Y         S0      
317GND              VIA   -    MD0080PA00X+044679Y+107270X0160Y         S0      
317GND              VIA   -    MD0080PA00X+044679Y+106632X0160Y         S0      
317GND              VIA   -    MD0080PA00X+044864Y+105038X0160Y         S0      
317GND              VIA   -    MD0080PA00X+045419Y+105357X0160Y         S0      
317GND              VIA   -    MD0080PA00X+044864Y+105676X0160Y         S0      
317GND              VIA   -    MD0080PA00X+045419Y+104719X0160Y         S0      
317GND              VIA   -    MD0080PA00X+044679Y+105995X0160Y         S0      
317GND              VIA   -    MD0080PA00X+044679Y+105357X0160Y         S0      
317GND              VIA   -    MD0080PA00X+044679Y+104719X0160Y         S0      
317GND              VIA   -    MD0080PA00X+044864Y+110140X0160Y         S0      
317GND              VIA   -    MD0080PA00X+045234Y+110140X0160Y         S0      
317GND              VIA   -    MD0080PA00X+044679Y+110459X0160Y         S0      
317GND              VIA   -    MD0080PA00X+044679Y+109821X0160Y         S0      
317GND              VIA   -    MD0080PA00X+044679Y+109184X0160Y         S0      
317GND              VIA   -    MD0080PA00X+044864Y+108865X0160Y         S0      
317GND              VIA   -    MD0080PA00X+045234Y+108865X0160Y         S0      
317GND              VIA   -    MD0080PA00X+044864Y+107589X0160Y         S0      
317GND              VIA   -    MD0080PA00X+045234Y+107589X0160Y         S0      
317GND              VIA   -    MD0080PA00X+044679Y+108546X0160Y         S0      
317GND              VIA   -    MD0080PA00X+044679Y+107908X0160Y         S0      
317GND              VIA   -    MD0080PA00X+044864Y+113329X0160Y         S0      
317GND              VIA   -    MD0080PA00X+045234Y+113329X0160Y         S0      
317GND              VIA   -    MD0080PA00X+045234Y+112054X0160Y         S0      
317GND              VIA   -    MD0080PA00X+044864Y+112054X0160Y         S0      
317GND              VIA   -    MD0080PA00X+044679Y+113010X0160Y         S0      
317GND              VIA   -    MD0080PA00X+044679Y+112373X0160Y         S0      
317GND              VIA   -    MD0080PA00X+044864Y+110778X0160Y         S0      
317GND              VIA   -    MD0080PA00X+045234Y+110778X0160Y         S0      
317GND              VIA   -    MD0080PA00X+044679Y+111735X0160Y         S0      
317GND              VIA   -    MD0080PA00X+044679Y+111097X0160Y         S0      
317GND              VIA   -    MD0080PA00X+045419Y+115562X0160Y         S0      
317GND              VIA   -    MD0080PA00X+044679Y+116199X0160Y         S0      
317GND              VIA   -    MD0080PA00X+044679Y+115562X0160Y         S0      
317GND              VIA   -    MD0080PA00X+045049Y+114924X0160Y         S0      
317GND              VIA   -    MD0080PA00X+045419Y+114924X0160Y         S0      
317GND              VIA   -    MD0080PA00X+044679Y+114924X0160Y         S0      
317GND              VIA   -    MD0080PA00X+044679Y+114286X0160Y         S0      
317GND              VIA   -    MD0080PA00X+044679Y+113648X0160Y         S0      
317GND              VIA   -    MD0080PA00X+046596Y+090514X0160Y    R180 S0      
317GND              VIA   -    MD0080PA00X+046781Y+090832X0160Y    R180 S0      
317GND              VIA   -    MD0080PA00X+046411Y+090195X0160Y    R180 S0      
317GND              VIA   -    MD0080PA00X+046781Y+090195X0160Y    R180 S0      
317GND              VIA   -    MD0080PA00X+046596Y+089876X0160Y    R180 S0      
317GND              VIA   -    MD0080PA00X+046041Y+090195X0160Y    R180 S0      
317GND              VIA   -    MD0080PA00X+045671Y+090195X0160Y    R180 S0      
317GND              VIA   -    MD0080PA00X+046411Y+088919X0160Y    R180 S0      
317GND              VIA   -    MD0080PA00X+046781Y+089557X0160Y    R180 S0      
317GND              VIA   -    MD0080PA00X+046596Y+089238X0160Y    R180 S0      
317GND              VIA   -    MD0080PA00X+046781Y+088281X0160Y    R180 S0      
317GND              VIA   -    MD0080PA00X+045671Y+089557X0160Y    R180 S0      
317GND              VIA   -    MD0080PA00X+046041Y+088919X0160Y    R180 S0      
317GND              VIA   -    MD0080PA00X+046966Y+087962X0160Y    R180 S0      
317GND              VIA   -    MD0080PA00X+046041Y+087644X0160Y    R180 S0      
317GND              VIA   -    MD0080PA00X+046596Y+095616X0160Y    R180 S0      
317GND              VIA   -    MD0080PA00X+046781Y+095297X0160Y    R180 S0      
317GND              VIA   -    MD0080PA00X+046596Y+094978X0160Y    R180 S0      
317GND              VIA   -    MD0080PA00X+046596Y+094340X0160Y    R180 S0      
317GND              VIA   -    MD0080PA00X+046411Y+094659X0160Y    R180 S0      
317GND              VIA   -    MD0080PA00X+046781Y+094659X0160Y    R180 S0      
317GND              VIA   -    MD0080PA00X+045671Y+095297X0160Y    R180 S0      
317GND              VIA   -    MD0080PA00X+045671Y+094659X0160Y    R180 S0      
317GND              VIA   -    MD0080PA00X+046041Y+094659X0160Y    R180 S0      
317GND              VIA   -    MD0080PA00X+046596Y+093702X0160Y    R180 S0      
317GND              VIA   -    MD0080PA00X+046781Y+094021X0160Y    R180 S0      
317GND              VIA   -    MD0080PA00X+046411Y+093384X0160Y    R180 S0      
317GND              VIA   -    MD0080PA00X+046411Y+092746X0160Y    R180 S0      
317GND              VIA   -    MD0080PA00X+046781Y+093384X0160Y    R180 S0      
317GND              VIA   -    MD0080PA00X+046781Y+092746X0160Y    R180 S0      
317GND              VIA   -    MD0080PA00X+045671Y+094021X0160Y    R180 S0      
317GND              VIA   -    MD0080PA00X+046041Y+093384X0160Y    R180 S0      
317GND              VIA   -    MD0080PA00X+045671Y+093384X0160Y    R180 S0      
317GND              VIA   -    MD0080PA00X+045671Y+092746X0160Y    R180 S0      
317GND              VIA   -    MD0080PA00X+046041Y+092746X0160Y    R180 S0      
317GND              VIA   -    MD0080PA00X+046596Y+092427X0160Y    R180 S0      
317GND              VIA   -    MD0080PA00X+046781Y+092108X0160Y    R180 S0      
317GND              VIA   -    MD0080PA00X+046596Y+091789X0160Y    R180 S0      
317GND              VIA   -    MD0080PA00X+046411Y+091470X0160Y    R180 S0      
317GND              VIA   -    MD0080PA00X+046781Y+091470X0160Y    R180 S0      
317GND              VIA   -    MD0080PA00X+045671Y+092108X0160Y    R180 S0      
317GND              VIA   -    MD0080PA00X+045671Y+091470X0160Y    R180 S0      
317GND              VIA   -    MD0080PA00X+046041Y+091470X0160Y    R180 S0      
317GND              VIA   -    MD0080PA00X+046596Y+091151X0160Y    R180 S0      
317GND              VIA   -    MD0080PA00X+046344Y+105038X0160Y         S0      
317GND              VIA   -    MD0080PA00X+046344Y+105676X0160Y         S0      
317GND              VIA   -    MD0080PA00X+046900Y+105995X0160Y         S0      
317GND              VIA   -    MD0080PA00X+046900Y+105357X0160Y         S0      
317GND              VIA   -    MD0080PA00X+046900Y+104719X0160Y         S0      
317GND              VIA   -    MD0080PA00X+045604Y+105038X0160Y         S0      
317GND              VIA   -    MD0080PA00X+045789Y+105995X0160Y         S0      
317GND              VIA   -    MD0080PA00X+045604Y+105676X0160Y         S0      
317GND              VIA   -    MD0080PA00X+046159Y+105357X0160Y         S0      
317GND              VIA   -    MD0080PA00X+046159Y+104719X0160Y         S0      
317GND              VIA   -    MD0080PA00X+046161Y+104082X0160Y         S0      
317GND              VIA   -    MD0080PA00X+046901Y+104082X0160Y         S0      
317GND              VIA   -    MD0080PA00X+046042Y+099761X0160Y    R180 S0      
317GND              VIA   -    MD0080PA00X+046783Y+099761X0160Y    R180 S0      
317GND              VIA   -    MD0080PA00X+046781Y+099124X0160Y    R180 S0      
317GND              VIA   -    MD0080PA00X+046966Y+098805X0160Y    R180 S0      
317GND              VIA   -    MD0080PA00X+046226Y+098805X0160Y    R180 S0      
317GND              VIA   -    MD0080PA00X+046041Y+099124X0160Y    R180 S0      
317GND              VIA   -    MD0080PA00X+046781Y+098486X0160Y    R180 S0      
317GND              VIA   -    MD0080PA00X+046411Y+097210X0160Y    R180 S0      
317GND              VIA   -    MD0080PA00X+046596Y+097529X0160Y    R180 S0      
317GND              VIA   -    MD0080PA00X+046781Y+097210X0160Y    R180 S0      
317GND              VIA   -    MD0080PA00X+046781Y+097848X0160Y    R180 S0      
317GND              VIA   -    MD0080PA00X+046966Y+098167X0160Y    R180 S0      
317GND              VIA   -    MD0080PA00X+046041Y+098486X0160Y    R180 S0      
317GND              VIA   -    MD0080PA00X+046041Y+097210X0160Y    R180 S0      
317GND              VIA   -    MD0080PA00X+046226Y+098167X0160Y    R180 S0      
317GND              VIA   -    MD0080PA00X+045671Y+097848X0160Y    R180 S0      
317GND              VIA   -    MD0080PA00X+045671Y+097210X0160Y    R180 S0      
317GND              VIA   -    MD0080PA00X+046596Y+096892X0160Y    R180 S0      
317GND              VIA   -    MD0080PA00X+046411Y+095935X0160Y    R180 S0      
317GND              VIA   -    MD0080PA00X+046596Y+096254X0160Y    R180 S0      
317GND              VIA   -    MD0080PA00X+046781Y+095935X0160Y    R180 S0      
317GND              VIA   -    MD0080PA00X+046781Y+096573X0160Y    R180 S0      
317GND              VIA   -    MD0080PA00X+045671Y+095935X0160Y    R180 S0      
317GND              VIA   -    MD0080PA00X+046041Y+095935X0160Y    R180 S0      
317GND              VIA   -    MD0080PA00X+045671Y+096573X0160Y    R180 S0      
317GND              VIA   -    MD0080PA00X+046529Y+106632X0160Y         S0      
317GND              VIA   -    MD0080PA00X+046714Y+106951X0160Y         S0      
317GND              VIA   -    MD0080PA00X+046900Y+106632X0160Y         S0      
317GND              VIA   -    MD0080PA00X+046900Y+107270X0160Y         S0      
317GND              VIA   -    MD0080PA00X+046714Y+106314X0160Y         S0      
317GND              VIA   -    MD0080PA00X+046159Y+106632X0160Y         S0      
317GND              VIA   -    MD0080PA00X+045789Y+106632X0160Y         S0      
317GND              VIA   -    MD0080PA00X+045789Y+107270X0160Y         S0      
317GND              VIA   -    MD0080PA00X+045604Y+106951X0160Y         S0      
317GND              VIA   -    MD0080PA00X+045604Y+106314X0160Y         S0      
317GND              VIA   -    MD0080PA00X+046714Y+110140X0160Y         S0      
317GND              VIA   -    MD0080PA00X+046900Y+109821X0160Y         S0      
317GND              VIA   -    MD0080PA00X+046529Y+110459X0160Y         S0      
317GND              VIA   -    MD0080PA00X+046900Y+110459X0160Y         S0      
317GND              VIA   -    MD0080PA00X+046529Y+109184X0160Y         S0      
317GND              VIA   -    MD0080PA00X+046900Y+109184X0160Y         S0      
317GND              VIA   -    MD0080PA00X+046714Y+109502X0160Y         S0      
317GND              VIA   -    MD0080PA00X+046159Y+110459X0160Y         S0      
317GND              VIA   -    MD0080PA00X+045789Y+110459X0160Y         S0      
317GND              VIA   -    MD0080PA00X+045604Y+110140X0160Y         S0      
317GND              VIA   -    MD0080PA00X+045789Y+109821X0160Y         S0      
317GND              VIA   -    MD0080PA00X+045604Y+109502X0160Y         S0      
317GND              VIA   -    MD0080PA00X+046159Y+109184X0160Y         S0      
317GND              VIA   -    MD0080PA00X+045789Y+109184X0160Y         S0      
317GND              VIA   -    MD0080PA00X+046714Y+108227X0160Y         S0      
317GND              VIA   -    MD0080PA00X+046714Y+108865X0160Y         S0      
317GND              VIA   -    MD0080PA00X+046900Y+108546X0160Y         S0      
317GND              VIA   -    MD0080PA00X+046529Y+107908X0160Y         S0      
317GND              VIA   -    MD0080PA00X+046900Y+107908X0160Y         S0      
317GND              VIA   -    MD0080PA00X+046714Y+107589X0160Y         S0      
317GND              VIA   -    MD0080PA00X+045604Y+108227X0160Y         S0      
317GND              VIA   -    MD0080PA00X+045789Y+108546X0160Y         S0      
317GND              VIA   -    MD0080PA00X+045604Y+108865X0160Y         S0      
317GND              VIA   -    MD0080PA00X+045789Y+107908X0160Y         S0      
317GND              VIA   -    MD0080PA00X+046159Y+107908X0160Y         S0      
317GND              VIA   -    MD0080PA00X+045604Y+107589X0160Y         S0      
317GND              VIA   -    MD0080PA00X+046714Y+113329X0160Y         S0      
317GND              VIA   -    MD0080PA00X+046900Y+113010X0160Y         S0      
317GND              VIA   -    MD0080PA00X+046714Y+112692X0160Y         S0      
317GND              VIA   -    MD0080PA00X+046529Y+112373X0160Y         S0      
317GND              VIA   -    MD0080PA00X+046714Y+112054X0160Y         S0      
317GND              VIA   -    MD0080PA00X+046900Y+112373X0160Y         S0      
317GND              VIA   -    MD0080PA00X+045604Y+113329X0160Y         S0      
317GND              VIA   -    MD0080PA00X+045604Y+112054X0160Y         S0      
317GND              VIA   -    MD0080PA00X+045789Y+112373X0160Y         S0      
317GND              VIA   -    MD0080PA00X+046159Y+112373X0160Y         S0      
317GND              VIA   -    MD0080PA00X+045604Y+112692X0160Y         S0      
317GND              VIA   -    MD0080PA00X+046900Y+111735X0160Y         S0      
317GND              VIA   -    MD0080PA00X+046714Y+111416X0160Y         S0      
317GND              VIA   -    MD0080PA00X+046714Y+110778X0160Y         S0      
317GND              VIA   -    MD0080PA00X+046529Y+111097X0160Y         S0      
317GND              VIA   -    MD0080PA00X+046900Y+111097X0160Y         S0      
317GND              VIA   -    MD0080PA00X+045604Y+111416X0160Y         S0      
317GND              VIA   -    MD0080PA00X+045789Y+111735X0160Y         S0      
317GND              VIA   -    MD0080PA00X+046159Y+111097X0160Y         S0      
317GND              VIA   -    MD0080PA00X+045789Y+111097X0160Y         S0      
317GND              VIA   -    MD0080PA00X+045604Y+110778X0160Y         S0      
317GND              VIA   -    MD0080PA00X+046529Y+115562X0160Y         S0      
317GND              VIA   -    MD0080PA00X+045974Y+115243X0160Y         S0      
317GND              VIA   -    MD0080PA00X+045974Y+115880X0160Y         S0      
317GND              VIA   -    MD0080PA00X+046529Y+114924X0160Y         S0      
317GND              VIA   -    MD0080PA00X+046714Y+114605X0160Y         S0      
317GND              VIA   -    MD0080PA00X+046529Y+113648X0160Y         S0      
317GND              VIA   -    MD0080PA00X+046900Y+113648X0160Y         S0      
317GND              VIA   -    MD0080PA00X+046714Y+113967X0160Y         S0      
317GND              VIA   -    MD0080PA00X+046900Y+114286X0160Y         S0      
317GND              VIA   -    MD0080PA00X+046159Y+114924X0160Y         S0      
317GND              VIA   -    MD0080PA00X+045604Y+114605X0160Y         S0      
317GND              VIA   -    MD0080PA00X+045789Y+114286X0160Y         S0      
317GND              VIA   -    MD0080PA00X+045789Y+113648X0160Y         S0      
317GND              VIA   -    MD0080PA00X+046159Y+113648X0160Y         S0      
317GND              VIA   -    MD0080PA00X+045604Y+113967X0160Y         S0      
317GND              VIA   -    MD0080PA00X+048262Y+088919X0160Y    R180 S0      
317GND              VIA   -    MD0080PA00X+048262Y+088281X0160Y    R180 S0      
317GND              VIA   -    MD0080PA00X+047152Y+088919X0160Y    R180 S0      
317GND              VIA   -    MD0080PA00X+047522Y+088919X0160Y    R180 S0      
317GND              VIA   -    MD0080PA00X+047707Y+089238X0160Y    R180 S0      
317GND              VIA   -    MD0080PA00X+047892Y+089557X0160Y    R180 S0      
317GND              VIA   -    MD0080PA00X+047152Y+088281X0160Y    R180 S0      
317GND              VIA   -    MD0080PA00X+047522Y+088281X0160Y    R180 S0      
317GND              VIA   -    MD0080PA00X+047892Y+088281X0160Y    R180 S0      
317GND              VIA   -    MD0080PA00X+048262Y+087644X0160Y    R180 S0      
317GND              VIA   -    MD0080PA00X+048077Y+087962X0160Y    R180 S0      
317GND              VIA   -    MD0080PA00X+048077Y+087325X0160Y    R180 S0      
317GND              VIA   -    MD0080PA00X+047152Y+087644X0160Y    R180 S0      
317GND              VIA   -    MD0080PA00X+048262Y+093384X0160Y    R180 S0      
317GND              VIA   -    MD0080PA00X+048262Y+092746X0160Y    R180 S0      
317GND              VIA   -    MD0080PA00X+047892Y+094021X0160Y    R180 S0      
317GND              VIA   -    MD0080PA00X+047707Y+093065X0160Y    R180 S0      
317GND              VIA   -    MD0080PA00X+047152Y+092746X0160Y    R180 S0      
317GND              VIA   -    MD0080PA00X+047522Y+092746X0160Y    R180 S0      
317GND              VIA   -    MD0080PA00X+047892Y+093384X0160Y    R180 S0      
317GND              VIA   -    MD0080PA00X+047892Y+092746X0160Y    R180 S0      
317GND              VIA   -    MD0080PA00X+048262Y+091470X0160Y    R180 S0      
317GND              VIA   -    MD0080PA00X+047707Y+092427X0160Y    R180 S0      
317GND              VIA   -    MD0080PA00X+047892Y+092108X0160Y    R180 S0      
317GND              VIA   -    MD0080PA00X+047152Y+091470X0160Y    R180 S0      
317GND              VIA   -    MD0080PA00X+047522Y+091470X0160Y    R180 S0      
317GND              VIA   -    MD0080PA00X+047707Y+091789X0160Y    R180 S0      
317GND              VIA   -    MD0080PA00X+047892Y+091470X0160Y    R180 S0      
317GND              VIA   -    MD0080PA00X+048262Y+090195X0160Y    R180 S0      
317GND              VIA   -    MD0080PA00X+047707Y+091151X0160Y    R180 S0      
317GND              VIA   -    MD0080PA00X+047707Y+090514X0160Y    R180 S0      
317GND              VIA   -    MD0080PA00X+047892Y+090832X0160Y    R180 S0      
317GND              VIA   -    MD0080PA00X+047707Y+089876X0160Y    R180 S0      
317GND              VIA   -    MD0080PA00X+047522Y+090195X0160Y    R180 S0      
317GND              VIA   -    MD0080PA00X+047152Y+090195X0160Y    R180 S0      
317GND              VIA   -    MD0080PA00X+047892Y+090195X0160Y    R180 S0      
317GND              VIA   -    MD0080PA00X+048010Y+102806X0160Y         S0      
317GND              VIA   -    MD0080PA00X+048262Y+100399X0160Y    R180 S0      
317GND              VIA   -    MD0080PA00X+048262Y+101037X0160Y    R180 S0      
317GND              VIA   -    MD0080PA00X+048447Y+100718X0160Y    R180 S0      
317GND              VIA   -    MD0080PA00X+047707Y+100718X0160Y    R180 S0      
317GND              VIA   -    MD0080PA00X+048447Y+100080X0160Y    R180 S0      
317GND              VIA   -    MD0080PA00X+048262Y+099762X0160Y    R180 S0      
317GND              VIA   -    MD0080PA00X+048262Y+099124X0160Y    R180 S0      
317GND              VIA   -    MD0080PA00X+048447Y+098805X0160Y    R180 S0      
317GND              VIA   -    MD0080PA00X+048447Y+099443X0160Y    R180 S0      
317GND              VIA   -    MD0080PA00X+047707Y+100080X0160Y    R180 S0      
317GND              VIA   -    MD0080PA00X+047707Y+098805X0160Y    R180 S0      
317GND              VIA   -    MD0080PA00X+047522Y+099124X0160Y    R180 S0      
317GND              VIA   -    MD0080PA00X+047707Y+099443X0160Y    R180 S0      
317GND              VIA   -    MD0080PA00X+048262Y+098486X0160Y    R180 S0      
317GND              VIA   -    MD0080PA00X+048262Y+097210X0160Y    R180 S0      
317GND              VIA   -    MD0080PA00X+048447Y+098167X0160Y    R180 S0      
317GND              VIA   -    MD0080PA00X+047522Y+098486X0160Y    R180 S0      
317GND              VIA   -    MD0080PA00X+047152Y+097210X0160Y    R180 S0      
317GND              VIA   -    MD0080PA00X+047522Y+097210X0160Y    R180 S0      
317GND              VIA   -    MD0080PA00X+047707Y+097529X0160Y    R180 S0      
317GND              VIA   -    MD0080PA00X+047707Y+098167X0160Y    R180 S0      
317GND              VIA   -    MD0080PA00X+047892Y+097210X0160Y    R180 S0      
317GND              VIA   -    MD0080PA00X+047892Y+097848X0160Y    R180 S0      
317GND              VIA   -    MD0080PA00X+048262Y+095935X0160Y    R180 S0      
317GND              VIA   -    MD0080PA00X+047707Y+096892X0160Y    R180 S0      
317GND              VIA   -    MD0080PA00X+047707Y+096254X0160Y    R180 S0      
317GND              VIA   -    MD0080PA00X+047152Y+095935X0160Y    R180 S0      
317GND              VIA   -    MD0080PA00X+047522Y+095935X0160Y    R180 S0      
317GND              VIA   -    MD0080PA00X+047892Y+095935X0160Y    R180 S0      
317GND              VIA   -    MD0080PA00X+047892Y+096573X0160Y    R180 S0      
317GND              VIA   -    MD0080PA00X+048262Y+094659X0160Y    R180 S0      
317GND              VIA   -    MD0080PA00X+047707Y+095616X0160Y    R180 S0      
317GND              VIA   -    MD0080PA00X+047892Y+095297X0160Y    R180 S0      
317GND              VIA   -    MD0080PA00X+047707Y+094978X0160Y    R180 S0      
317GND              VIA   -    MD0080PA00X+047152Y+094659X0160Y    R180 S0      
317GND              VIA   -    MD0080PA00X+047522Y+094659X0160Y    R180 S0      
317GND              VIA   -    MD0080PA00X+047707Y+094340X0160Y    R180 S0      
317GND              VIA   -    MD0080PA00X+047892Y+094659X0160Y    R180 S0      
317GND              VIA   -    MD0080PA00X+048010Y+105995X0160Y         S0      
317GND              VIA   -    MD0080PA00X+048380Y+105357X0160Y         S0      
317GND              VIA   -    MD0080PA00X+048380Y+104719X0160Y         S0      
317GND              VIA   -    MD0080PA00X+047825Y+105038X0160Y         S0      
317GND              VIA   -    MD0080PA00X+047084Y+105038X0160Y         S0      
317GND              VIA   -    MD0080PA00X+047825Y+105676X0160Y         S0      
317GND              VIA   -    MD0080PA00X+047084Y+105676X0160Y         S0      
317GND              VIA   -    MD0080PA00X+047640Y+105357X0160Y         S0      
317GND              VIA   -    MD0080PA00X+047640Y+104719X0160Y         S0      
317GND              VIA   -    MD0080PA00X+047640Y+104082X0160Y         S0      
317GND              VIA   -    MD0080PA00X+048195Y+103124X0160Y         S0      
317GND              VIA   -    MD0080PA00X+048380Y+104081X0160Y         S0      
317GND              VIA   -    MD0080PA00X+048010Y+103443X0160Y         S0      
317GND              VIA   -    MD0080PA00X+047825Y+104400X0160Y         S0      
317GND              VIA   -    MD0080PA00X+047825Y+103762X0160Y         S0      
317GND              VIA   -    MD0080PA00X+048010Y+106632X0160Y         S0      
317GND              VIA   -    MD0080PA00X+048010Y+107270X0160Y         S0      
317GND              VIA   -    MD0080PA00X+048380Y+106632X0160Y         S0      
317GND              VIA   -    MD0080PA00X+047825Y+106951X0160Y         S0      
317GND              VIA   -    MD0080PA00X+047640Y+106632X0160Y         S0      
317GND              VIA   -    MD0080PA00X+047270Y+106632X0160Y         S0      
317GND              VIA   -    MD0080PA00X+047825Y+106314X0160Y         S0      
317GND              VIA   -    MD0080PA00X+048380Y+109184X0160Y         S0      
317GND              VIA   -    MD0080PA00X+048010Y+109184X0160Y         S0      
317GND              VIA   -    MD0080PA00X+047640Y+109184X0160Y         S0      
317GND              VIA   -    MD0080PA00X+047270Y+109184X0160Y         S0      
317GND              VIA   -    MD0080PA00X+047825Y+109502X0160Y         S0      
317GND              VIA   -    MD0080PA00X+048010Y+108546X0160Y         S0      
317GND              VIA   -    MD0080PA00X+048010Y+107908X0160Y         S0      
317GND              VIA   -    MD0080PA00X+048380Y+107908X0160Y         S0      
317GND              VIA   -    MD0080PA00X+047825Y+108227X0160Y         S0      
317GND              VIA   -    MD0080PA00X+047825Y+108865X0160Y         S0      
317GND              VIA   -    MD0080PA00X+047270Y+107908X0160Y         S0      
317GND              VIA   -    MD0080PA00X+047640Y+107908X0160Y         S0      
317GND              VIA   -    MD0080PA00X+047825Y+107589X0160Y         S0      
317GND              VIA   -    MD0080PA00X+048010Y+111735X0160Y         S0      
317GND              VIA   -    MD0080PA00X+048010Y+111097X0160Y         S0      
317GND              VIA   -    MD0080PA00X+048380Y+111097X0160Y         S0      
317GND              VIA   -    MD0080PA00X+047825Y+111416X0160Y         S0      
317GND              VIA   -    MD0080PA00X+047825Y+110778X0160Y         S0      
317GND              VIA   -    MD0080PA00X+047640Y+111097X0160Y         S0      
317GND              VIA   -    MD0080PA00X+047270Y+111097X0160Y         S0      
317GND              VIA   -    MD0080PA00X+048010Y+109821X0160Y         S0      
317GND              VIA   -    MD0080PA00X+048380Y+110459X0160Y         S0      
317GND              VIA   -    MD0080PA00X+048010Y+110459X0160Y         S0      
317GND              VIA   -    MD0080PA00X+048010Y+113010X0160Y         S0      
317GND              VIA   -    MD0080PA00X+048010Y+112373X0160Y         S0      
317GND              VIA   -    MD0080PA00X+048380Y+112373X0160Y         S0      
317GND              VIA   -    MD0080PA00X+047825Y+113329X0160Y         S0      
317GND              VIA   -    MD0080PA00X+047825Y+112692X0160Y         S0      
317GND              VIA   -    MD0080PA00X+047825Y+112054X0160Y         S0      
317GND              VIA   -    MD0080PA00X+047270Y+112373X0160Y         S0      
317GND              VIA   -    MD0080PA00X+047640Y+112373X0160Y         S0      
317GND              VIA   -    MD0080PA00X+048195Y+115880X0160Y         S0      
317GND              VIA   -    MD0080PA00X+047084Y+115880X0160Y         S0      
317GND              VIA   -    MD0080PA00X+047455Y+115243X0160Y         S0      
317GND              VIA   -    MD0080PA00X+047640Y+115562X0160Y         S0      
317GND              VIA   -    MD0080PA00X+048380Y+114924X0160Y         S0      
317GND              VIA   -    MD0080PA00X+048010Y+114286X0160Y         S0      
317GND              VIA   -    MD0080PA00X+048010Y+113648X0160Y         S0      
317GND              VIA   -    MD0080PA00X+048380Y+113648X0160Y         S0      
317GND              VIA   -    MD0080PA00X+047825Y+114605X0160Y         S0      
317GND              VIA   -    MD0080PA00X+047270Y+114924X0160Y         S0      
317GND              VIA   -    MD0080PA00X+047640Y+114924X0160Y         S0      
317GND              VIA   -    MD0080PA00X+047270Y+113648X0160Y         S0      
317GND              VIA   -    MD0080PA00X+047640Y+113648X0160Y         S0      
317GND              VIA   -    MD0080PA00X+047825Y+113967X0160Y         S0      
317GND              VIA   -    MD0080PA00X+049927Y+089238X0160Y    R180 S0      
317GND              VIA   -    MD0080PA00X+049742Y+088919X0160Y    R180 S0      
317GND              VIA   -    MD0080PA00X+048817Y+089238X0160Y    R180 S0      
317GND              VIA   -    MD0080PA00X+049002Y+089557X0160Y    R180 S0      
317GND              VIA   -    MD0080PA00X+048632Y+088919X0160Y    R180 S0      
317GND              VIA   -    MD0080PA00X+049372Y+088919X0160Y    R180 S0      
317GND              VIA   -    MD0080PA00X+048632Y+088281X0160Y    R180 S0      
317GND              VIA   -    MD0080PA00X+049002Y+088281X0160Y    R180 S0      
317GND              VIA   -    MD0080PA00X+049372Y+088281X0160Y    R180 S0      
317GND              VIA   -    MD0080PA00X+049187Y+087962X0160Y    R180 S0      
317GND              VIA   -    MD0080PA00X+049372Y+087644X0160Y    R180 S0      
317GND              VIA   -    MD0080PA00X+049927Y+093065X0160Y    R180 S0      
317GND              VIA   -    MD0080PA00X+049742Y+093384X0160Y    R180 S0      
317GND              VIA   -    MD0080PA00X+049742Y+092746X0160Y    R180 S0      
317GND              VIA   -    MD0080PA00X+049002Y+094021X0160Y    R180 S0      
317GND              VIA   -    MD0080PA00X+048817Y+093065X0160Y    R180 S0      
317GND              VIA   -    MD0080PA00X+048632Y+093384X0160Y    R180 S0      
317GND              VIA   -    MD0080PA00X+049002Y+093384X0160Y    R180 S0      
317GND              VIA   -    MD0080PA00X+049372Y+093384X0160Y    R180 S0      
317GND              VIA   -    MD0080PA00X+049002Y+092746X0160Y    R180 S0      
317GND              VIA   -    MD0080PA00X+048632Y+092746X0160Y    R180 S0      
317GND              VIA   -    MD0080PA00X+049372Y+092746X0160Y    R180 S0      
317GND              VIA   -    MD0080PA00X+049927Y+092427X0160Y    R180 S0      
317GND              VIA   -    MD0080PA00X+049742Y+091470X0160Y    R180 S0      
317GND              VIA   -    MD0080PA00X+049927Y+091789X0160Y    R180 S0      
317GND              VIA   -    MD0080PA00X+048817Y+092427X0160Y    R180 S0      
317GND              VIA   -    MD0080PA00X+049002Y+092108X0160Y    R180 S0      
317GND              VIA   -    MD0080PA00X+048632Y+091470X0160Y    R180 S0      
317GND              VIA   -    MD0080PA00X+049002Y+091470X0160Y    R180 S0      
317GND              VIA   -    MD0080PA00X+048817Y+091789X0160Y    R180 S0      
317GND              VIA   -    MD0080PA00X+049372Y+091470X0160Y    R180 S0      
317GND              VIA   -    MD0080PA00X+049927Y+091151X0160Y    R180 S0      
317GND              VIA   -    MD0080PA00X+049927Y+090514X0160Y    R180 S0      
317GND              VIA   -    MD0080PA00X+049927Y+089876X0160Y    R180 S0      
317GND              VIA   -    MD0080PA00X+049742Y+090195X0160Y    R180 S0      
317GND              VIA   -    MD0080PA00X+048817Y+091151X0160Y    R180 S0      
317GND              VIA   -    MD0080PA00X+048817Y+090514X0160Y    R180 S0      
317GND              VIA   -    MD0080PA00X+048817Y+089876X0160Y    R180 S0      
317GND              VIA   -    MD0080PA00X+049002Y+090195X0160Y    R180 S0      
317GND              VIA   -    MD0080PA00X+048632Y+090195X0160Y    R180 S0      
317GND              VIA   -    MD0080PA00X+049372Y+090195X0160Y    R180 S0      
317GND              VIA   -    MD0080PA00X+049927Y+100718X0160Y    R180 S0      
317GND              VIA   -    MD0080PA00X+049742Y+100399X0160Y    R180 S0      
317GND              VIA   -    MD0080PA00X+049742Y+101037X0160Y    R180 S0      
317GND              VIA   -    MD0080PA00X+049002Y+100399X0160Y    R180 S0      
317GND              VIA   -    MD0080PA00X+049002Y+101037X0160Y    R180 S0      
317GND              VIA   -    MD0080PA00X+049187Y+100718X0160Y    R180 S0      
317GND              VIA   -    MD0080PA00X+049927Y+100080X0160Y    R180 S0      
317GND              VIA   -    MD0080PA00X+049927Y+099443X0160Y    R180 S0      
317GND              VIA   -    MD0080PA00X+049927Y+098805X0160Y    R180 S0      
317GND              VIA   -    MD0080PA00X+049742Y+099762X0160Y    R180 S0      
317GND              VIA   -    MD0080PA00X+049742Y+099124X0160Y    R180 S0      
317GND              VIA   -    MD0080PA00X+049187Y+100080X0160Y    R180 S0      
317GND              VIA   -    MD0080PA00X+049002Y+099124X0160Y    R180 S0      
317GND              VIA   -    MD0080PA00X+049002Y+099762X0160Y    R180 S0      
317GND              VIA   -    MD0080PA00X+049187Y+098805X0160Y    R180 S0      
317GND              VIA   -    MD0080PA00X+049187Y+099443X0160Y    R180 S0      
317GND              VIA   -    MD0080PA00X+049742Y+098486X0160Y    R180 S0      
317GND              VIA   -    MD0080PA00X+049927Y+098167X0160Y    R180 S0      
317GND              VIA   -    MD0080PA00X+049927Y+097529X0160Y    R180 S0      
317GND              VIA   -    MD0080PA00X+049742Y+097210X0160Y    R180 S0      
317GND              VIA   -    MD0080PA00X+049002Y+098486X0160Y    R180 S0      
317GND              VIA   -    MD0080PA00X+048632Y+097210X0160Y    R180 S0      
317GND              VIA   -    MD0080PA00X+049002Y+097210X0160Y    R180 S0      
317GND              VIA   -    MD0080PA00X+048817Y+097529X0160Y    R180 S0      
317GND              VIA   -    MD0080PA00X+049372Y+097210X0160Y    R180 S0      
317GND              VIA   -    MD0080PA00X+049002Y+097848X0160Y    R180 S0      
317GND              VIA   -    MD0080PA00X+049187Y+098167X0160Y    R180 S0      
317GND              VIA   -    MD0080PA00X+049927Y+096892X0160Y    R180 S0      
317GND              VIA   -    MD0080PA00X+049742Y+095935X0160Y    R180 S0      
317GND              VIA   -    MD0080PA00X+049927Y+096254X0160Y    R180 S0      
317GND              VIA   -    MD0080PA00X+048817Y+096892X0160Y    R180 S0      
317GND              VIA   -    MD0080PA00X+048817Y+096254X0160Y    R180 S0      
317GND              VIA   -    MD0080PA00X+048632Y+095935X0160Y    R180 S0      
317GND              VIA   -    MD0080PA00X+049002Y+095935X0160Y    R180 S0      
317GND              VIA   -    MD0080PA00X+049372Y+095935X0160Y    R180 S0      
317GND              VIA   -    MD0080PA00X+049002Y+096573X0160Y    R180 S0      
317GND              VIA   -    MD0080PA00X+049927Y+095616X0160Y    R180 S0      
317GND              VIA   -    MD0080PA00X+049927Y+094978X0160Y    R180 S0      
317GND              VIA   -    MD0080PA00X+049927Y+094340X0160Y    R180 S0      
317GND              VIA   -    MD0080PA00X+049742Y+094659X0160Y    R180 S0      
317GND              VIA   -    MD0080PA00X+048817Y+095616X0160Y    R180 S0      
317GND              VIA   -    MD0080PA00X+049002Y+095297X0160Y    R180 S0      
317GND              VIA   -    MD0080PA00X+048817Y+094978X0160Y    R180 S0      
317GND              VIA   -    MD0080PA00X+048632Y+094659X0160Y    R180 S0      
317GND              VIA   -    MD0080PA00X+049002Y+094659X0160Y    R180 S0      
317GND              VIA   -    MD0080PA00X+049372Y+094659X0160Y    R180 S0      
317GND              VIA   -    MD0080PA00X+048817Y+094340X0160Y    R180 S0      
317GND              VIA   -    MD0080PA00X+049860Y+105357X0160Y         S0      
317GND              VIA   -    MD0080PA00X+049860Y+104719X0160Y         S0      
317GND              VIA   -    MD0080PA00X+048565Y+105038X0160Y         S0      
317GND              VIA   -    MD0080PA00X+049305Y+105038X0160Y         S0      
317GND              VIA   -    MD0080PA00X+048565Y+105676X0160Y         S0      
317GND              VIA   -    MD0080PA00X+049120Y+105357X0160Y         S0      
317GND              VIA   -    MD0080PA00X+049120Y+105995X0160Y         S0      
317GND              VIA   -    MD0080PA00X+049305Y+105676X0160Y         S0      
317GND              VIA   -    MD0080PA00X+049120Y+104719X0160Y         S0      
317GND              VIA   -    MD0080PA00X+049860Y+104081X0160Y         S0      
317GND              VIA   -    MD0080PA00X+049675Y+103124X0160Y         S0      
317GND              VIA   -    MD0080PA00X+049305Y+104400X0160Y         S0      
317GND              VIA   -    MD0080PA00X+048565Y+103762X0160Y         S0      
317GND              VIA   -    MD0080PA00X+049305Y+103762X0160Y         S0      
317GND              VIA   -    MD0080PA00X+048935Y+103124X0160Y         S0      
317GND              VIA   -    MD0080PA00X+048750Y+103443X0160Y         S0      
317GND              VIA   -    MD0080PA00X+049120Y+104081X0160Y         S0      
317GND              VIA   -    MD0080PA00X+049490Y+103443X0160Y         S0      
317GND              VIA   -    MD0080PA00X+048565Y+104400X0160Y         S0      
317GND              VIA   -    MD0080PA00X+048750Y+102806X0160Y         S0      
317GND              VIA   -    MD0080PA00X+049490Y+102806X0160Y         S0      
317GND              VIA   -    MD0080PA00X+048935Y+108865X0160Y         S0      
317GND              VIA   -    MD0080PA00X+049120Y+108546X0160Y         S0      
317GND              VIA   -    MD0080PA00X+049120Y+107908X0160Y         S0      
317GND              VIA   -    MD0080PA00X+048750Y+107908X0160Y         S0      
317GND              VIA   -    MD0080PA00X+048935Y+107589X0160Y         S0      
317GND              VIA   -    MD0080PA00X+049490Y+107908X0160Y         S0      
317GND              VIA   -    MD0080PA00X+049860Y+106632X0160Y         S0      
317GND              VIA   -    MD0080PA00X+048935Y+106951X0160Y         S0      
317GND              VIA   -    MD0080PA00X+049120Y+107270X0160Y         S0      
317GND              VIA   -    MD0080PA00X+048750Y+106632X0160Y         S0      
317GND              VIA   -    MD0080PA00X+049120Y+106632X0160Y         S0      
317GND              VIA   -    MD0080PA00X+049490Y+106632X0160Y         S0      
317GND              VIA   -    MD0080PA00X+048935Y+106314X0160Y         S0      
317GND              VIA   -    MD0080PA00X+048750Y+111097X0160Y         S0      
317GND              VIA   -    MD0080PA00X+048935Y+110778X0160Y         S0      
317GND              VIA   -    MD0080PA00X+049490Y+111097X0160Y         S0      
317GND              VIA   -    MD0080PA00X+049675Y+110140X0160Y         S0      
317GND              VIA   -    MD0080PA00X+049860Y+110459X0160Y         S0      
317GND              VIA   -    MD0080PA00X+049860Y+109184X0160Y         S0      
317GND              VIA   -    MD0080PA00X+048750Y+110459X0160Y         S0      
317GND              VIA   -    MD0080PA00X+049120Y+110459X0160Y         S0      
317GND              VIA   -    MD0080PA00X+049120Y+109821X0160Y         S0      
317GND              VIA   -    MD0080PA00X+049490Y+110459X0160Y         S0      
317GND              VIA   -    MD0080PA00X+048935Y+109502X0160Y         S0      
317GND              VIA   -    MD0080PA00X+049120Y+109184X0160Y         S0      
317GND              VIA   -    MD0080PA00X+048750Y+109184X0160Y         S0      
317GND              VIA   -    MD0080PA00X+049490Y+109184X0160Y         S0      
317GND              VIA   -    MD0080PA00X+049860Y+107908X0160Y         S0      
317GND              VIA   -    MD0080PA00X+048935Y+108227X0160Y         S0      
317GND              VIA   -    MD0080PA00X+049860Y+112373X0160Y         S0      
317GND              VIA   -    MD0080PA00X+048935Y+113329X0160Y         S0      
317GND              VIA   -    MD0080PA00X+049120Y+113010X0160Y         S0      
317GND              VIA   -    MD0080PA00X+048935Y+112054X0160Y         S0      
317GND              VIA   -    MD0080PA00X+048750Y+112373X0160Y         S0      
317GND              VIA   -    MD0080PA00X+049120Y+112373X0160Y         S0      
317GND              VIA   -    MD0080PA00X+048935Y+112692X0160Y         S0      
317GND              VIA   -    MD0080PA00X+049490Y+112373X0160Y         S0      
317GND              VIA   -    MD0080PA00X+049860Y+111097X0160Y         S0      
317GND              VIA   -    MD0080PA00X+049120Y+111735X0160Y         S0      
317GND              VIA   -    MD0080PA00X+048935Y+111416X0160Y         S0      
317GND              VIA   -    MD0080PA00X+049120Y+111097X0160Y         S0      
317GND              VIA   -    MD0080PA00X+049675Y+115243X0160Y         S0      
317GND              VIA   -    MD0080PA00X+049860Y+115562X0160Y         S0      
317GND              VIA   -    MD0080PA00X+049305Y+115880X0160Y         S0      
317GND              VIA   -    MD0080PA00X+048565Y+115243X0160Y         S0      
317GND              VIA   -    MD0080PA00X+048750Y+115562X0160Y         S0      
317GND              VIA   -    MD0080PA00X+049860Y+114924X0160Y         S0      
317GND              VIA   -    MD0080PA00X+049860Y+113648X0160Y         S0      
317GND              VIA   -    MD0080PA00X+048750Y+114924X0160Y         S0      
317GND              VIA   -    MD0080PA00X+048935Y+114605X0160Y         S0      
317GND              VIA   -    MD0080PA00X+049490Y+114924X0160Y         S0      
317GND              VIA   -    MD0080PA00X+049120Y+114286X0160Y         S0      
317GND              VIA   -    MD0080PA00X+048750Y+113648X0160Y         S0      
317GND              VIA   -    MD0080PA00X+049120Y+113648X0160Y         S0      
317GND              VIA   -    MD0080PA00X+048935Y+113967X0160Y         S0      
317GND              VIA   -    MD0080PA00X+049490Y+113648X0160Y         S0      
317GND              VIA   -    MD0080PA00X+050113Y+087212X0160Y    R180 S0      
317GND              VIA   -    MD0080PA00X+050297Y+087962X0160Y    R180 S0      
317GND              VIA   -    MD0080PA00X+051407Y+089238X0160Y    R180 S0      
317GND              VIA   -    MD0080PA00X+051222Y+088919X0160Y    R180 S0      
317GND              VIA   -    MD0080PA00X+051407Y+088600X0160Y    R180 S0      
317GND              VIA   -    MD0080PA00X+051222Y+088281X0160Y    R180 S0      
317GND              VIA   -    MD0080PA00X+050112Y+089557X0160Y    R180 S0      
317GND              VIA   -    MD0080PA00X+050667Y+089238X0160Y    R180 S0      
317GND              VIA   -    MD0080PA00X+050482Y+088281X0160Y    R180 S0      
317GND              VIA   -    MD0080PA00X+050297Y+088600X0160Y    R180 S0      
317GND              VIA   -    MD0080PA00X+050667Y+088600X0160Y    R180 S0      
317GND              VIA   -    MD0080PA00X+050852Y+088281X0160Y    R180 S0      
317GND              VIA   -    MD0080PA00X+051222Y+092108X0160Y    R180 S0      
317GND              VIA   -    MD0080PA00X+051407Y+091789X0160Y    R180 S0      
317GND              VIA   -    MD0080PA00X+050667Y+092427X0160Y    R180 S0      
317GND              VIA   -    MD0080PA00X+050112Y+092108X0160Y    R180 S0      
317GND              VIA   -    MD0080PA00X+050667Y+091789X0160Y    R180 S0      
317GND              VIA   -    MD0080PA00X+051222Y+090832X0160Y    R180 S0      
317GND              VIA   -    MD0080PA00X+051407Y+091151X0160Y    R180 S0      
317GND              VIA   -    MD0080PA00X+051407Y+089876X0160Y    R180 S0      
317GND              VIA   -    MD0080PA00X+051222Y+090195X0160Y    R180 S0      
317GND              VIA   -    MD0080PA00X+050112Y+090832X0160Y    R180 S0      
317GND              VIA   -    MD0080PA00X+050667Y+091151X0160Y    R180 S0      
317GND              VIA   -    MD0080PA00X+050667Y+090514X0160Y    R180 S0      
317GND              VIA   -    MD0080PA00X+050667Y+089876X0160Y    R180 S0      
317GND              VIA   -    MD0080PA00X+051407Y+093702X0160Y    R180 S0      
317GND              VIA   -    MD0080PA00X+051222Y+094021X0160Y    R180 S0      
317GND              VIA   -    MD0080PA00X+051407Y+093065X0160Y    R180 S0      
317GND              VIA   -    MD0080PA00X+051222Y+092746X0160Y    R180 S0      
317GND              VIA   -    MD0080PA00X+050112Y+094021X0160Y    R180 S0      
317GND              VIA   -    MD0080PA00X+050667Y+093702X0160Y    R180 S0      
317GND              VIA   -    MD0080PA00X+050112Y+093384X0160Y    R180 S0      
317GND              VIA   -    MD0080PA00X+050667Y+093065X0160Y    R180 S0      
317GND              VIA   -    MD0080PA00X+051407Y+095616X0160Y    R180 S0      
317GND              VIA   -    MD0080PA00X+051222Y+094659X0160Y    R180 S0      
317GND              VIA   -    MD0080PA00X+051407Y+094978X0160Y    R180 S0      
317GND              VIA   -    MD0080PA00X+050667Y+095616X0160Y    R180 S0      
317GND              VIA   -    MD0080PA00X+050112Y+095297X0160Y    R180 S0      
317GND              VIA   -    MD0080PA00X+050667Y+094978X0160Y    R180 S0      
317GND              VIA   -    MD0080PA00X+050667Y+094340X0160Y    R180 S0      
317GND              VIA   -    MD0080PA00X+051222Y+098486X0160Y    R180 S0      
317GND              VIA   -    MD0080PA00X+051222Y+097848X0160Y    R180 S0      
317GND              VIA   -    MD0080PA00X+051407Y+097529X0160Y    R180 S0      
317GND              VIA   -    MD0080PA00X+050852Y+098486X0160Y    R180 S0      
317GND              VIA   -    MD0080PA00X+050112Y+097848X0160Y    R180 S0      
317GND              VIA   -    MD0080PA00X+050667Y+098167X0160Y    R180 S0      
317GND              VIA   -    MD0080PA00X+050667Y+097529X0160Y    R180 S0      
317GND              VIA   -    MD0080PA00X+051037Y+098167X0160Y    R180 S0      
317GND              VIA   -    MD0080PA00X+051407Y+096892X0160Y    R180 S0      
317GND              VIA   -    MD0080PA00X+051222Y+096573X0160Y    R180 S0      
317GND              VIA   -    MD0080PA00X+051222Y+095935X0160Y    R180 S0      
317GND              VIA   -    MD0080PA00X+050667Y+096892X0160Y    R180 S0      
317GND              VIA   -    MD0080PA00X+050112Y+096573X0160Y    R180 S0      
317GND              VIA   -    MD0080PA00X+050667Y+096254X0160Y    R180 S0      
317GND              VIA   -    MD0080PA00X+051222Y+100399X0160Y    R180 S0      
317GND              VIA   -    MD0080PA00X+051407Y+100718X0160Y    R180 S0      
317GND              VIA   -    MD0080PA00X+050667Y+100718X0160Y    R180 S0      
317GND              VIA   -    MD0080PA00X+051222Y+099762X0160Y    R180 S0      
317GND              VIA   -    MD0080PA00X+051407Y+099443X0160Y    R180 S0      
317GND              VIA   -    MD0080PA00X+051407Y+098805X0160Y    R180 S0      
317GND              VIA   -    MD0080PA00X+050667Y+100080X0160Y    R180 S0      
317GND              VIA   -    MD0080PA00X+050667Y+099443X0160Y    R180 S0      
317GND              VIA   -    MD0080PA00X+050667Y+098805X0160Y    R180 S0      
317GND              VIA   -    MD0080PA00X+051340Y+104081X0160Y         S0      
317GND              VIA   -    MD0080PA00X+051340Y+103443X0160Y         S0      
317GND              VIA   -    MD0080PA00X+050785Y+103124X0160Y         S0      
317GND              VIA   -    MD0080PA00X+050045Y+104400X0160Y         S0      
317GND              VIA   -    MD0080PA00X+050785Y+104400X0160Y         S0      
317GND              VIA   -    MD0080PA00X+050230Y+103443X0160Y         S0      
317GND              VIA   -    MD0080PA00X+050045Y+103762X0160Y         S0      
317GND              VIA   -    MD0080PA00X+050785Y+103762X0160Y         S0      
317GND              VIA   -    MD0080PA00X+051340Y+102806X0160Y         S0      
317GND              VIA   -    MD0080PA00X+050230Y+102806X0160Y         S0      
317GND              VIA   -    MD0080PA00X+051340Y+107270X0160Y         S0      
317GND              VIA   -    MD0080PA00X+050230Y+107270X0160Y         S0      
317GND              VIA   -    MD0080PA00X+050045Y+106951X0160Y         S0      
317GND              VIA   -    MD0080PA00X+050785Y+106951X0160Y         S0      
317GND              VIA   -    MD0080PA00X+050045Y+106314X0160Y         S0      
317GND              VIA   -    MD0080PA00X+050785Y+106314X0160Y         S0      
317GND              VIA   -    MD0080PA00X+051340Y+105995X0160Y         S0      
317GND              VIA   -    MD0080PA00X+051340Y+105357X0160Y         S0      
317GND              VIA   -    MD0080PA00X+050600Y+105995X0160Y         S0      
317GND              VIA   -    MD0080PA00X+050230Y+105995X0160Y         S0      
317GND              VIA   -    MD0080PA00X+050045Y+105038X0160Y         S0      
317GND              VIA   -    MD0080PA00X+050415Y+105676X0160Y         S0      
317GND              VIA   -    MD0080PA00X+050045Y+105676X0160Y         S0      
317GND              VIA   -    MD0080PA00X+050785Y+105038X0160Y         S0      
317GND              VIA   -    MD0080PA00X+050785Y+105676X0160Y         S0      
317GND              VIA   -    MD0080PA00X+051340Y+107908X0160Y         S0      
317GND              VIA   -    MD0080PA00X+050045Y+108227X0160Y         S0      
317GND              VIA   -    MD0080PA00X+050785Y+108227X0160Y         S0      
317GND              VIA   -    MD0080PA00X+050230Y+108546X0160Y         S0      
317GND              VIA   -    MD0080PA00X+050045Y+108865X0160Y         S0      
317GND              VIA   -    MD0080PA00X+050785Y+108865X0160Y         S0      
317GND              VIA   -    MD0080PA00X+050045Y+107589X0160Y         S0      
317GND              VIA   -    MD0080PA00X+050785Y+107589X0160Y         S0      
317GND              VIA   -    MD0080PA00X+051340Y+109821X0160Y         S0      
317GND              VIA   -    MD0080PA00X+051340Y+109184X0160Y         S0      
317GND              VIA   -    MD0080PA00X+050230Y+110459X0160Y         S0      
317GND              VIA   -    MD0080PA00X+050785Y+110140X0160Y         S0      
317GND              VIA   -    MD0080PA00X+050230Y+109821X0160Y         S0      
317GND              VIA   -    MD0080PA00X+050045Y+109502X0160Y         S0      
317GND              VIA   -    MD0080PA00X+050785Y+109502X0160Y         S0      
317GND              VIA   -    MD0080PA00X+050230Y+113010X0160Y         S0      
317GND              VIA   -    MD0080PA00X+050045Y+113329X0160Y         S0      
317GND              VIA   -    MD0080PA00X+050785Y+113329X0160Y         S0      
317GND              VIA   -    MD0080PA00X+050045Y+112692X0160Y         S0      
317GND              VIA   -    MD0080PA00X+050785Y+112692X0160Y         S0      
317GND              VIA   -    MD0080PA00X+050045Y+112054X0160Y         S0      
317GND              VIA   -    MD0080PA00X+050785Y+112054X0160Y         S0      
317GND              VIA   -    MD0080PA00X+051340Y+111735X0160Y         S0      
317GND              VIA   -    MD0080PA00X+051340Y+111097X0160Y         S0      
317GND              VIA   -    MD0080PA00X+050045Y+111416X0160Y         S0      
317GND              VIA   -    MD0080PA00X+050230Y+111735X0160Y         S0      
317GND              VIA   -    MD0080PA00X+050785Y+111416X0160Y         S0      
317GND              VIA   -    MD0080PA00X+050045Y+110778X0160Y         S0      
317GND              VIA   -    MD0080PA00X+050785Y+110778X0160Y         S0      
317GND              VIA   -    MD0080PA00X+051340Y+114924X0160Y         S0      
317GND              VIA   -    MD0080PA00X+051340Y+113648X0160Y         S0      
317GND              VIA   -    MD0080PA00X+050045Y+114605X0160Y         S0      
317GND              VIA   -    MD0080PA00X+050785Y+114605X0160Y         S0      
317GND              VIA   -    MD0080PA00X+050230Y+114286X0160Y         S0      
317GND              VIA   -    MD0080PA00X+050045Y+113967X0160Y         S0      
317GND              VIA   -    MD0080PA00X+050785Y+113967X0160Y         S0      
317GND              VIA   -    MD0080PA00X+051340Y+115562X0160Y         S0      
317GND              VIA   -    MD0080PA00X+050415Y+115880X0160Y         S0      
317GND              VIA   -    MD0080PA00X+050785Y+115880X0160Y         S0      
317GND              VIA   -    MD0080PA00X+050230Y+115562X0160Y         S0      
317GND              VIA   -    MD0080PA00X+050785Y+115243X0160Y         S0      
317GND              VIA   -    MD0080PA00X+050970Y+115562X0160Y         S0      
317GND              VIA   -    MD0080PA00X+051155Y+116518X0160Y         S0      
317GND              VIA   -    MD0080PA00X+052888Y+088600X0160Y    R180 S0      
317GND              VIA   -    MD0080PA00X+051962Y+089557X0160Y    R180 S0      
317GND              VIA   -    MD0080PA00X+051962Y+088919X0160Y    R180 S0      
317GND              VIA   -    MD0080PA00X+052518Y+089238X0160Y    R180 S0      
317GND              VIA   -    MD0080PA00X+052703Y+088919X0160Y    R180 S0      
317GND              VIA   -    MD0080PA00X+052703Y+089557X0160Y    R180 S0      
317GND              VIA   -    MD0080PA00X+051962Y+088281X0160Y    R180 S0      
317GND              VIA   -    MD0080PA00X+051778Y+088600X0160Y    R180 S0      
317GND              VIA   -    MD0080PA00X+052333Y+088281X0160Y    R180 S0      
317GND              VIA   -    MD0080PA00X+052518Y+088600X0160Y    R180 S0      
317GND              VIA   -    MD0080PA00X+052518Y+087325X0160Y    R180 S0      
317GND              VIA   -    MD0080PA00X+051592Y+087644X0160Y    R180 S0      
317GND              VIA   -    MD0080PA00X+052518Y+087962X0160Y    R180 S0      
317GND              VIA   -    MD0080PA00X+051962Y+090832X0160Y    R180 S0      
317GND              VIA   -    MD0080PA00X+052518Y+091151X0160Y    R180 S0      
317GND              VIA   -    MD0080PA00X+052518Y+090514X0160Y    R180 S0      
317GND              VIA   -    MD0080PA00X+051962Y+090195X0160Y    R180 S0      
317GND              VIA   -    MD0080PA00X+052518Y+089876X0160Y    R180 S0      
317GND              VIA   -    MD0080PA00X+052703Y+090195X0160Y    R180 S0      
317GND              VIA   -    MD0080PA00X+051962Y+094021X0160Y    R180 S0      
317GND              VIA   -    MD0080PA00X+052703Y+094021X0160Y    R180 S0      
317GND              VIA   -    MD0080PA00X+051962Y+093384X0160Y    R180 S0      
317GND              VIA   -    MD0080PA00X+051962Y+092746X0160Y    R180 S0      
317GND              VIA   -    MD0080PA00X+052518Y+093065X0160Y    R180 S0      
317GND              VIA   -    MD0080PA00X+052703Y+093384X0160Y    R180 S0      
317GND              VIA   -    MD0080PA00X+052703Y+092746X0160Y    R180 S0      
317GND              VIA   -    MD0080PA00X+051962Y+092108X0160Y    R180 S0      
317GND              VIA   -    MD0080PA00X+052518Y+092427X0160Y    R180 S0      
317GND              VIA   -    MD0080PA00X+052703Y+092108X0160Y    R180 S0      
317GND              VIA   -    MD0080PA00X+052703Y+091470X0160Y    R180 S0      
317GND              VIA   -    MD0080PA00X+051962Y+091470X0160Y    R180 S0      
317GND              VIA   -    MD0080PA00X+052518Y+091789X0160Y    R180 S0      
317GND              VIA   -    MD0080PA00X+051962Y+095297X0160Y    R180 S0      
317GND              VIA   -    MD0080PA00X+052518Y+095616X0160Y    R180 S0      
317GND              VIA   -    MD0080PA00X+052703Y+095297X0160Y    R180 S0      
317GND              VIA   -    MD0080PA00X+052518Y+094978X0160Y    R180 S0      
317GND              VIA   -    MD0080PA00X+052518Y+094340X0160Y    R180 S0      
317GND              VIA   -    MD0080PA00X+051962Y+094659X0160Y    R180 S0      
317GND              VIA   -    MD0080PA00X+052703Y+094659X0160Y    R180 S0      
317GND              VIA   -    MD0080PA00X+052518Y+093702X0160Y    R180 S0      
317GND              VIA   -    MD0080PA00X+051962Y+097210X0160Y    R180 S0      
317GND              VIA   -    MD0080PA00X+052518Y+098167X0160Y    R180 S0      
317GND              VIA   -    MD0080PA00X+052518Y+097529X0160Y    R180 S0      
317GND              VIA   -    MD0080PA00X+052703Y+097848X0160Y    R180 S0      
317GND              VIA   -    MD0080PA00X+052703Y+097210X0160Y    R180 S0      
317GND              VIA   -    MD0080PA00X+052518Y+096892X0160Y    R180 S0      
317GND              VIA   -    MD0080PA00X+051962Y+096573X0160Y    R180 S0      
317GND              VIA   -    MD0080PA00X+051962Y+095935X0160Y    R180 S0      
317GND              VIA   -    MD0080PA00X+052518Y+096254X0160Y    R180 S0      
317GND              VIA   -    MD0080PA00X+052703Y+096573X0160Y    R180 S0      
317GND              VIA   -    MD0080PA00X+052703Y+095935X0160Y    R180 S0      
317GND              VIA   -    MD0080PA00X+052518Y+100080X0160Y    R180 S0      
317GND              VIA   -    MD0080PA00X+051962Y+099762X0160Y    R180 S0      
317GND              VIA   -    MD0080PA00X+051962Y+099124X0160Y    R180 S0      
317GND              VIA   -    MD0080PA00X+052518Y+099443X0160Y    R180 S0      
317GND              VIA   -    MD0080PA00X+052518Y+098805X0160Y    R180 S0      
317GND              VIA   -    MD0080PA00X+052703Y+099762X0160Y    R180 S0      
317GND              VIA   -    MD0080PA00X+052703Y+099124X0160Y    R180 S0      
317GND              VIA   -    MD0080PA00X+051962Y+098486X0160Y    R180 S0      
317GND              VIA   -    MD0080PA00X+052333Y+098486X0160Y    R180 S0      
317GND              VIA   -    MD0080PA00X+052703Y+098486X0160Y    R180 S0      
317GND              VIA   -    MD0080PA00X+051962Y+097848X0160Y    R180 S0      
317GND              VIA   -    MD0080PA00X+052148Y+098167X0160Y    R180 S0      
317GND              VIA   -    MD0080PA00X+052821Y+103443X0160Y         S0      
317GND              VIA   -    MD0080PA00X+052821Y+104081X0160Y         S0      
317GND              VIA   -    MD0080PA00X+051526Y+104400X0160Y         S0      
317GND              VIA   -    MD0080PA00X+052081Y+103443X0160Y         S0      
317GND              VIA   -    MD0080PA00X+052081Y+104081X0160Y         S0      
317GND              VIA   -    MD0080PA00X+051526Y+103124X0160Y         S0      
317GND              VIA   -    MD0080PA00X+052636Y+103124X0160Y         S0      
317GND              VIA   -    MD0080PA00X+052636Y+104400X0160Y         S0      
317GND              VIA   -    MD0080PA00X+052636Y+103762X0160Y         S0      
317GND              VIA   -    MD0080PA00X+052821Y+102806X0160Y         S0      
317GND              VIA   -    MD0080PA00X+052081Y+102806X0160Y         S0      
317GND              VIA   -    MD0080PA00X+051962Y+100399X0160Y    R180 S0      
317GND              VIA   -    MD0080PA00X+051962Y+101037X0160Y    R180 S0      
317GND              VIA   -    MD0080PA00X+052518Y+100718X0160Y    R180 S0      
317GND              VIA   -    MD0080PA00X+052703Y+100399X0160Y    R180 S0      
317GND              VIA   -    MD0080PA00X+052703Y+101037X0160Y    R180 S0      
317GND              VIA   -    MD0080PA00X+052821Y+107270X0160Y         S0      
317GND              VIA   -    MD0080PA00X+052821Y+106632X0160Y         S0      
317GND              VIA   -    MD0080PA00X+051526Y+106951X0160Y         S0      
317GND              VIA   -    MD0080PA00X+052081Y+107270X0160Y         S0      
317GND              VIA   -    MD0080PA00X+052081Y+106632X0160Y         S0      
317GND              VIA   -    MD0080PA00X+052636Y+106951X0160Y         S0      
317GND              VIA   -    MD0080PA00X+051526Y+106314X0160Y         S0      
317GND              VIA   -    MD0080PA00X+052636Y+106314X0160Y         S0      
317GND              VIA   -    MD0080PA00X+052821Y+105995X0160Y         S0      
317GND              VIA   -    MD0080PA00X+052821Y+105357X0160Y         S0      
317GND              VIA   -    MD0080PA00X+052821Y+104719X0160Y         S0      
317GND              VIA   -    MD0080PA00X+051710Y+105995X0160Y         S0      
317GND              VIA   -    MD0080PA00X+052081Y+105995X0160Y         S0      
317GND              VIA   -    MD0080PA00X+051896Y+105676X0160Y         S0      
317GND              VIA   -    MD0080PA00X+051526Y+105038X0160Y         S0      
317GND              VIA   -    MD0080PA00X+052081Y+105357X0160Y         S0      
317GND              VIA   -    MD0080PA00X+052636Y+105676X0160Y         S0      
317GND              VIA   -    MD0080PA00X+052636Y+105038X0160Y         S0      
317GND              VIA   -    MD0080PA00X+052081Y+104719X0160Y         S0      
317GND              VIA   -    MD0080PA00X+052821Y+108546X0160Y         S0      
317GND              VIA   -    MD0080PA00X+052821Y+107908X0160Y         S0      
317GND              VIA   -    MD0080PA00X+051526Y+108227X0160Y         S0      
317GND              VIA   -    MD0080PA00X+051526Y+108865X0160Y         S0      
317GND              VIA   -    MD0080PA00X+052081Y+108546X0160Y         S0      
317GND              VIA   -    MD0080PA00X+052636Y+108227X0160Y         S0      
317GND              VIA   -    MD0080PA00X+052636Y+108865X0160Y         S0      
317GND              VIA   -    MD0080PA00X+052081Y+107908X0160Y         S0      
317GND              VIA   -    MD0080PA00X+052636Y+107589X0160Y         S0      
317GND              VIA   -    MD0080PA00X+052821Y+111735X0160Y         S0      
317GND              VIA   -    MD0080PA00X+052821Y+111097X0160Y         S0      
317GND              VIA   -    MD0080PA00X+052081Y+111735X0160Y         S0      
317GND              VIA   -    MD0080PA00X+052636Y+111416X0160Y         S0      
317GND              VIA   -    MD0080PA00X+051526Y+110778X0160Y         S0      
317GND              VIA   -    MD0080PA00X+052081Y+111097X0160Y         S0      
317GND              VIA   -    MD0080PA00X+052636Y+110778X0160Y         S0      
317GND              VIA   -    MD0080PA00X+052821Y+109821X0160Y         S0      
317GND              VIA   -    MD0080PA00X+052821Y+110459X0160Y         S0      
317GND              VIA   -    MD0080PA00X+052821Y+109184X0160Y         S0      
317GND              VIA   -    MD0080PA00X+051526Y+110140X0160Y         S0      
317GND              VIA   -    MD0080PA00X+052081Y+109821X0160Y         S0      
317GND              VIA   -    MD0080PA00X+052081Y+110459X0160Y         S0      
317GND              VIA   -    MD0080PA00X+052636Y+110140X0160Y         S0      
317GND              VIA   -    MD0080PA00X+052081Y+109184X0160Y         S0      
317GND              VIA   -    MD0080PA00X+052636Y+109502X0160Y         S0      
317GND              VIA   -    MD0080PA00X+052821Y+112373X0160Y         S0      
317GND              VIA   -    MD0080PA00X+052081Y+113010X0160Y         S0      
317GND              VIA   -    MD0080PA00X+052636Y+113329X0160Y         S0      
317GND              VIA   -    MD0080PA00X+051526Y+112692X0160Y         S0      
317GND              VIA   -    MD0080PA00X+051526Y+112054X0160Y         S0      
317GND              VIA   -    MD0080PA00X+052081Y+112373X0160Y         S0      
317GND              VIA   -    MD0080PA00X+052636Y+112692X0160Y         S0      
317GND              VIA   -    MD0080PA00X+052636Y+112054X0160Y         S0      
317GND              VIA   -    MD0080PA00X+052267Y+116529X0160Y    R180 S0      
317GND              VIA   -    MD0080PA00X+051897Y+116529X0160Y    R180 S0      
317GND              VIA   -    MD0080PA00X+051527Y+116529X0160Y    R180 S0      
317GND              VIA   -    MD0080PA00X+052637Y+116529X0160Y    R180 S0      
317GND              VIA   -    MD0080PA00X+052821Y+115562X0160Y         S0      
317GND              VIA   -    MD0080PA00X+051710Y+116199X0160Y         S0      
317GND              VIA   -    MD0080PA00X+051526Y+115880X0160Y         S0      
317GND              VIA   -    MD0080PA00X+052266Y+115880X0160Y         S0      
317GND              VIA   -    MD0080PA00X+051710Y+115562X0160Y         S0      
317GND              VIA   -    MD0080PA00X+052081Y+115562X0160Y         S0      
317GND              VIA   -    MD0080PA00X+052636Y+115880X0160Y         S0      
317GND              VIA   -    MD0080PA00X+052636Y+115243X0160Y         S0      
317GND              VIA   -    MD0080PA00X+052821Y+114924X0160Y         S0      
317GND              VIA   -    MD0080PA00X+052821Y+114286X0160Y         S0      
317GND              VIA   -    MD0080PA00X+052821Y+113648X0160Y         S0      
317GND              VIA   -    MD0080PA00X+051526Y+114605X0160Y         S0      
317GND              VIA   -    MD0080PA00X+052081Y+114924X0160Y         S0      
317GND              VIA   -    MD0080PA00X+052636Y+114605X0160Y         S0      
317GND              VIA   -    MD0080PA00X+052081Y+113648X0160Y         S0      
317GND              VIA   -    MD0080PA00X+052636Y+113967X0160Y         S0      
317GND              VIA   -    MD0080PA00X+052081Y+114286X0160Y         S0      
317GND              VIA   -    MD0080PA00X+051526Y+113967X0160Y         S0      
317GND              VIA   -    MD0080PA00X+053443Y+088281X0160Y    R180 S0      
317GND              VIA   -    MD0080PA00X+053258Y+088600X0160Y    R180 S0      
317GND              VIA   -    MD0080PA00X+053813Y+088281X0160Y    R180 S0      
317GND              VIA   -    MD0080PA00X+054368Y+087962X0160Y    R180 S0      
317GND              VIA   -    MD0080PA00X+054183Y+087644X0160Y    R180 S0      
317GND              VIA   -    MD0080PA00X+053258Y+087962X0160Y    R180 S0      
317GND              VIA   -    MD0080PA00X+053998Y+087962X0160Y    R180 S0      
317GND              VIA   -    MD0080PA00X+053443Y+087644X0160Y    R180 S0      
317GND              VIA   -    MD0080PA00X+053258Y+092427X0160Y    R180 S0      
317GND              VIA   -    MD0080PA00X+053813Y+092108X0160Y    R180 S0      
317GND              VIA   -    MD0080PA00X+053258Y+091789X0160Y    R180 S0      
317GND              VIA   -    MD0080PA00X+053998Y+091789X0160Y    R180 S0      
317GND              VIA   -    MD0080PA00X+053258Y+091151X0160Y    R180 S0      
317GND              VIA   -    MD0080PA00X+053258Y+090514X0160Y    R180 S0      
317GND              VIA   -    MD0080PA00X+053813Y+090832X0160Y    R180 S0      
317GND              VIA   -    MD0080PA00X+053998Y+091151X0160Y    R180 S0      
317GND              VIA   -    MD0080PA00X+053258Y+089876X0160Y    R180 S0      
317GND              VIA   -    MD0080PA00X+053998Y+089876X0160Y    R180 S0      
317GND              VIA   -    MD0080PA00X+053813Y+090195X0160Y    R180 S0      
317GND              VIA   -    MD0080PA00X+054368Y+088600X0160Y    R180 S0      
317GND              VIA   -    MD0080PA00X+053258Y+089238X0160Y    R180 S0      
317GND              VIA   -    MD0080PA00X+053998Y+089238X0160Y    R180 S0      
317GND              VIA   -    MD0080PA00X+053813Y+088919X0160Y    R180 S0      
317GND              VIA   -    MD0080PA00X+053258Y+095616X0160Y    R180 S0      
317GND              VIA   -    MD0080PA00X+053998Y+095616X0160Y    R180 S0      
317GND              VIA   -    MD0080PA00X+053258Y+094978X0160Y    R180 S0      
317GND              VIA   -    MD0080PA00X+053258Y+094340X0160Y    R180 S0      
317GND              VIA   -    MD0080PA00X+053813Y+094659X0160Y    R180 S0      
317GND              VIA   -    MD0080PA00X+053998Y+094978X0160Y    R180 S0      
317GND              VIA   -    MD0080PA00X+053258Y+093702X0160Y    R180 S0      
317GND              VIA   -    MD0080PA00X+053813Y+094021X0160Y    R180 S0      
317GND              VIA   -    MD0080PA00X+053998Y+093702X0160Y    R180 S0      
317GND              VIA   -    MD0080PA00X+053258Y+093065X0160Y    R180 S0      
317GND              VIA   -    MD0080PA00X+053998Y+093065X0160Y    R180 S0      
317GND              VIA   -    MD0080PA00X+053813Y+092746X0160Y    R180 S0      
317GND              VIA   -    MD0080PA00X+053443Y+098486X0160Y    R180 S0      
317GND              VIA   -    MD0080PA00X+053813Y+098486X0160Y    R180 S0      
317GND              VIA   -    MD0080PA00X+053258Y+098167X0160Y    R180 S0      
317GND              VIA   -    MD0080PA00X+053628Y+098167X0160Y    R180 S0      
317GND              VIA   -    MD0080PA00X+053813Y+097848X0160Y    R180 S0      
317GND              VIA   -    MD0080PA00X+053258Y+097529X0160Y    R180 S0      
317GND              VIA   -    MD0080PA00X+053998Y+097529X0160Y    R180 S0      
317GND              VIA   -    MD0080PA00X+053258Y+096892X0160Y    R180 S0      
317GND              VIA   -    MD0080PA00X+053998Y+096892X0160Y    R180 S0      
317GND              VIA   -    MD0080PA00X+053258Y+096254X0160Y    R180 S0      
317GND              VIA   -    MD0080PA00X+053813Y+096573X0160Y    R180 S0      
317GND              VIA   -    MD0080PA00X+053813Y+095935X0160Y    R180 S0      
317GND              VIA   -    MD0080PA00X+053931Y+102806X0160Y         S0      
317GND              VIA   -    MD0080PA00X+053258Y+100718X0160Y    R180 S0      
317GND              VIA   -    MD0080PA00X+053813Y+100399X0160Y    R180 S0      
317GND              VIA   -    MD0080PA00X+053998Y+100718X0160Y    R180 S0      
317GND              VIA   -    MD0080PA00X+053258Y+100080X0160Y    R180 S0      
317GND              VIA   -    MD0080PA00X+053813Y+099762X0160Y    R180 S0      
317GND              VIA   -    MD0080PA00X+053998Y+099443X0160Y    R180 S0      
317GND              VIA   -    MD0080PA00X+053258Y+098805X0160Y    R180 S0      
317GND              VIA   -    MD0080PA00X+053998Y+098805X0160Y    R180 S0      
317GND              VIA   -    MD0080PA00X+053258Y+099443X0160Y    R180 S0      
317GND              VIA   -    MD0080PA00X+053376Y+106951X0160Y         S0      
317GND              VIA   -    MD0080PA00X+053931Y+107270X0160Y         S0      
317GND              VIA   -    MD0080PA00X+054116Y+106951X0160Y         S0      
317GND              VIA   -    MD0080PA00X+053376Y+106314X0160Y         S0      
317GND              VIA   -    MD0080PA00X+054116Y+106314X0160Y         S0      
317GND              VIA   -    MD0080PA00X+053191Y+105995X0160Y         S0      
317GND              VIA   -    MD0080PA00X+053931Y+105995X0160Y         S0      
317GND              VIA   -    MD0080PA00X+053376Y+105676X0160Y         S0      
317GND              VIA   -    MD0080PA00X+053376Y+105038X0160Y         S0      
317GND              VIA   -    MD0080PA00X+053931Y+105357X0160Y         S0      
317GND              VIA   -    MD0080PA00X+054116Y+105038X0160Y         S0      
317GND              VIA   -    MD0080PA00X+053006Y+105676X0160Y         S0      
317GND              VIA   -    MD0080PA00X+054301Y+105995X0160Y         S0      
317GND              VIA   -    MD0080PA00X+053376Y+104400X0160Y         S0      
317GND              VIA   -    MD0080PA00X+054116Y+104400X0160Y         S0      
317GND              VIA   -    MD0080PA00X+053376Y+103762X0160Y         S0      
317GND              VIA   -    MD0080PA00X+053931Y+104081X0160Y         S0      
317GND              VIA   -    MD0080PA00X+053931Y+103443X0160Y         S0      
317GND              VIA   -    MD0080PA00X+053376Y+103124X0160Y         S0      
317GND              VIA   -    MD0080PA00X+054116Y+103124X0160Y         S0      
317GND              VIA   -    MD0080PA00X+053376Y+110140X0160Y         S0      
317GND              VIA   -    MD0080PA00X+054116Y+110140X0160Y         S0      
317GND              VIA   -    MD0080PA00X+053931Y+109821X0160Y         S0      
317GND              VIA   -    MD0080PA00X+053376Y+109502X0160Y         S0      
317GND              VIA   -    MD0080PA00X+053931Y+109184X0160Y         S0      
317GND              VIA   -    MD0080PA00X+053376Y+108227X0160Y         S0      
317GND              VIA   -    MD0080PA00X+054116Y+108227X0160Y         S0      
317GND              VIA   -    MD0080PA00X+053376Y+108865X0160Y         S0      
317GND              VIA   -    MD0080PA00X+054116Y+108865X0160Y         S0      
317GND              VIA   -    MD0080PA00X+053931Y+107908X0160Y         S0      
317GND              VIA   -    MD0080PA00X+053376Y+107589X0160Y         S0      
317GND              VIA   -    MD0080PA00X+053376Y+113329X0160Y         S0      
317GND              VIA   -    MD0080PA00X+053931Y+113010X0160Y         S0      
317GND              VIA   -    MD0080PA00X+053376Y+112692X0160Y         S0      
317GND              VIA   -    MD0080PA00X+054116Y+112692X0160Y         S0      
317GND              VIA   -    MD0080PA00X+053376Y+112054X0160Y         S0      
317GND              VIA   -    MD0080PA00X+054116Y+112054X0160Y         S0      
317GND              VIA   -    MD0080PA00X+053376Y+111416X0160Y         S0      
317GND              VIA   -    MD0080PA00X+053931Y+111735X0160Y         S0      
317GND              VIA   -    MD0080PA00X+053931Y+111097X0160Y         S0      
317GND              VIA   -    MD0080PA00X+053376Y+110778X0160Y         S0      
317GND              VIA   -    MD0080PA00X+054116Y+110778X0160Y         S0      
317GND              VIA   -    MD0080PA00X+053007Y+116529X0160Y    R180 S0      
317GND              VIA   -    MD0080PA00X+053377Y+116529X0160Y    R180 S0      
317GND              VIA   -    MD0080PA00X+054301Y+116199X0160Y         S0      
317GND              VIA   -    MD0080PA00X+053376Y+115243X0160Y         S0      
317GND              VIA   -    MD0080PA00X+053561Y+115562X0160Y         S0      
317GND              VIA   -    MD0080PA00X+053931Y+115562X0160Y         S0      
317GND              VIA   -    MD0080PA00X+053006Y+115880X0160Y         S0      
317GND              VIA   -    MD0080PA00X+053376Y+115880X0160Y         S0      
317GND              VIA   -    MD0080PA00X+054301Y+115562X0160Y         S0      
317GND              VIA   -    MD0080PA00X+053931Y+114924X0160Y         S0      
317GND              VIA   -    MD0080PA00X+054116Y+114605X0160Y         S0      
317GND              VIA   -    MD0080PA00X+053376Y+114605X0160Y         S0      
317GND              VIA   -    MD0080PA00X+053376Y+113967X0160Y         S0      
317GND              VIA   -    MD0080PA00X+053931Y+113648X0160Y         S0      
317GND              VIA   -    MD0080PA00X+054116Y+113967X0160Y         S0      
317GND              VIA   -    MD0080PA00X+055108Y+088600X0160Y    R180 S0      
317GND              VIA   -    MD0080PA00X+054553Y+088281X0160Y    R180 S0      
317GND              VIA   -    MD0080PA00X+055848Y+088600X0160Y    R180 S0      
317GND              VIA   -    MD0080PA00X+054554Y+087208X0160Y    R180 S0      
317GND              VIA   -    MD0080PA00X+055108Y+087962X0160Y    R180 S0      
317GND              VIA   -    MD0080PA00X+055663Y+087644X0160Y    R180 S0      
317GND              VIA   -    MD0080PA00X+055293Y+087644X0160Y    R180 S0      
317GND              VIA   -    MD0080PA00X+054553Y+087644X0160Y    R180 S0      
317GND              VIA   -    MD0080PA00X+055293Y+090832X0160Y    R180 S0      
317GND              VIA   -    MD0080PA00X+055108Y+091151X0160Y    R180 S0      
317GND              VIA   -    MD0080PA00X+055108Y+090514X0160Y    R180 S0      
317GND              VIA   -    MD0080PA00X+055848Y+091151X0160Y    R180 S0      
317GND              VIA   -    MD0080PA00X+055848Y+090514X0160Y    R180 S0      
317GND              VIA   -    MD0080PA00X+055108Y+089876X0160Y    R180 S0      
317GND              VIA   -    MD0080PA00X+055293Y+090195X0160Y    R180 S0      
317GND              VIA   -    MD0080PA00X+054553Y+090195X0160Y    R180 S0      
317GND              VIA   -    MD0080PA00X+055848Y+089876X0160Y    R180 S0      
317GND              VIA   -    MD0080PA00X+055293Y+089557X0160Y    R180 S0      
317GND              VIA   -    MD0080PA00X+055108Y+089238X0160Y    R180 S0      
317GND              VIA   -    MD0080PA00X+055293Y+088919X0160Y    R180 S0      
317GND              VIA   -    MD0080PA00X+054553Y+089557X0160Y    R180 S0      
317GND              VIA   -    MD0080PA00X+054553Y+088919X0160Y    R180 S0      
317GND              VIA   -    MD0080PA00X+055848Y+089238X0160Y    R180 S0      
317GND              VIA   -    MD0080PA00X+054923Y+088281X0160Y    R180 S0      
317GND              VIA   -    MD0080PA00X+055478Y+088600X0160Y    R180 S0      
317GND              VIA   -    MD0080PA00X+055293Y+094021X0160Y    R180 S0      
317GND              VIA   -    MD0080PA00X+055108Y+093702X0160Y    R180 S0      
317GND              VIA   -    MD0080PA00X+054553Y+094021X0160Y    R180 S0      
317GND              VIA   -    MD0080PA00X+055848Y+093702X0160Y    R180 S0      
317GND              VIA   -    MD0080PA00X+055108Y+093065X0160Y    R180 S0      
317GND              VIA   -    MD0080PA00X+055293Y+093384X0160Y    R180 S0      
317GND              VIA   -    MD0080PA00X+055293Y+092746X0160Y    R180 S0      
317GND              VIA   -    MD0080PA00X+054553Y+093384X0160Y    R180 S0      
317GND              VIA   -    MD0080PA00X+054553Y+092746X0160Y    R180 S0      
317GND              VIA   -    MD0080PA00X+055848Y+093065X0160Y    R180 S0      
317GND              VIA   -    MD0080PA00X+054553Y+092108X0160Y    R180 S0      
317GND              VIA   -    MD0080PA00X+055293Y+092108X0160Y    R180 S0      
317GND              VIA   -    MD0080PA00X+055108Y+092427X0160Y    R180 S0      
317GND              VIA   -    MD0080PA00X+055848Y+092427X0160Y    R180 S0      
317GND              VIA   -    MD0080PA00X+054553Y+091470X0160Y    R180 S0      
317GND              VIA   -    MD0080PA00X+055293Y+091470X0160Y    R180 S0      
317GND              VIA   -    MD0080PA00X+055108Y+091789X0160Y    R180 S0      
317GND              VIA   -    MD0080PA00X+055848Y+091789X0160Y    R180 S0      
317GND              VIA   -    MD0080PA00X+055108Y+096892X0160Y    R180 S0      
317GND              VIA   -    MD0080PA00X+055848Y+096892X0160Y    R180 S0      
317GND              VIA   -    MD0080PA00X+055293Y+096573X0160Y    R180 S0      
317GND              VIA   -    MD0080PA00X+055108Y+096254X0160Y    R180 S0      
317GND              VIA   -    MD0080PA00X+055293Y+095935X0160Y    R180 S0      
317GND              VIA   -    MD0080PA00X+054553Y+096573X0160Y    R180 S0      
317GND              VIA   -    MD0080PA00X+054553Y+095935X0160Y    R180 S0      
317GND              VIA   -    MD0080PA00X+055848Y+096254X0160Y    R180 S0      
317GND              VIA   -    MD0080PA00X+055108Y+095616X0160Y    R180 S0      
317GND              VIA   -    MD0080PA00X+055293Y+095297X0160Y    R180 S0      
317GND              VIA   -    MD0080PA00X+054553Y+095297X0160Y    R180 S0      
317GND              VIA   -    MD0080PA00X+055848Y+095616X0160Y    R180 S0      
317GND              VIA   -    MD0080PA00X+055293Y+094659X0160Y    R180 S0      
317GND              VIA   -    MD0080PA00X+055108Y+094978X0160Y    R180 S0      
317GND              VIA   -    MD0080PA00X+055108Y+094340X0160Y    R180 S0      
317GND              VIA   -    MD0080PA00X+054553Y+094659X0160Y    R180 S0      
317GND              VIA   -    MD0080PA00X+055848Y+094978X0160Y    R180 S0      
317GND              VIA   -    MD0080PA00X+055848Y+094340X0160Y    R180 S0      
317GND              VIA   -    MD0080PA00X+055108Y+100080X0160Y    R180 S0      
317GND              VIA   -    MD0080PA00X+055848Y+100080X0160Y    R180 S0      
317GND              VIA   -    MD0080PA00X+055108Y+098805X0160Y    R180 S0      
317GND              VIA   -    MD0080PA00X+054553Y+099762X0160Y    R180 S0      
317GND              VIA   -    MD0080PA00X+054553Y+099124X0160Y    R180 S0      
317GND              VIA   -    MD0080PA00X+055293Y+099762X0160Y    R180 S0      
317GND              VIA   -    MD0080PA00X+055108Y+099443X0160Y    R180 S0      
317GND              VIA   -    MD0080PA00X+055293Y+099124X0160Y    R180 S0      
317GND              VIA   -    MD0080PA00X+055848Y+099443X0160Y    R180 S0      
317GND              VIA   -    MD0080PA00X+055848Y+098805X0160Y    R180 S0      
317GND              VIA   -    MD0080PA00X+054553Y+098486X0160Y    R180 S0      
317GND              VIA   -    MD0080PA00X+054923Y+098486X0160Y    R180 S0      
317GND              VIA   -    MD0080PA00X+055293Y+098486X0160Y    R180 S0      
317GND              VIA   -    MD0080PA00X+055293Y+097848X0160Y    R180 S0      
317GND              VIA   -    MD0080PA00X+055108Y+098167X0160Y    R180 S0      
317GND              VIA   -    MD0080PA00X+055293Y+097210X0160Y    R180 S0      
317GND              VIA   -    MD0080PA00X+055108Y+097529X0160Y    R180 S0      
317GND              VIA   -    MD0080PA00X+054738Y+098167X0160Y    R180 S0      
317GND              VIA   -    MD0080PA00X+054553Y+097848X0160Y    R180 S0      
317GND              VIA   -    MD0080PA00X+054553Y+097210X0160Y    R180 S0      
317GND              VIA   -    MD0080PA00X+055848Y+098167X0160Y    R180 S0      
317GND              VIA   -    MD0080PA00X+055848Y+097529X0160Y    R180 S0      
317GND              VIA   -    MD0080PA00X+055966Y+104400X0160Y         S0      
317GND              VIA   -    MD0080PA00X+055966Y+103762X0160Y         S0      
317GND              VIA   -    MD0080PA00X+055966Y+103124X0160Y         S0      
317GND              VIA   -    MD0080PA00X+055226Y+104400X0160Y         S0      
317GND              VIA   -    MD0080PA00X+055411Y+103443X0160Y         S0      
317GND              VIA   -    MD0080PA00X+055226Y+103762X0160Y         S0      
317GND              VIA   -    MD0080PA00X+055411Y+104081X0160Y         S0      
317GND              VIA   -    MD0080PA00X+055226Y+103124X0160Y         S0      
317GND              VIA   -    MD0080PA00X+054671Y+103443X0160Y         S0      
317GND              VIA   -    MD0080PA00X+054671Y+104081X0160Y         S0      
317GND              VIA   -    MD0080PA00X+054671Y+102806X0160Y         S0      
317GND              VIA   -    MD0080PA00X+055411Y+102806X0160Y         S0      
317GND              VIA   -    MD0080PA00X+055293Y+100399X0160Y    R180 S0      
317GND              VIA   -    MD0080PA00X+055108Y+100718X0160Y    R180 S0      
317GND              VIA   -    MD0080PA00X+055293Y+101037X0160Y    R180 S0      
317GND              VIA   -    MD0080PA00X+054553Y+100399X0160Y    R180 S0      
317GND              VIA   -    MD0080PA00X+054553Y+101037X0160Y    R180 S0      
317GND              VIA   -    MD0080PA00X+055848Y+100718X0160Y    R180 S0      
317GND              VIA   -    MD0080PA00X+055966Y+106951X0160Y         S0      
317GND              VIA   -    MD0080PA00X+055966Y+106314X0160Y         S0      
317GND              VIA   -    MD0080PA00X+055411Y+107270X0160Y         S0      
317GND              VIA   -    MD0080PA00X+055411Y+106632X0160Y         S0      
317GND              VIA   -    MD0080PA00X+055226Y+106951X0160Y         S0      
317GND              VIA   -    MD0080PA00X+054671Y+106632X0160Y         S0      
317GND              VIA   -    MD0080PA00X+054671Y+107270X0160Y         S0      
317GND              VIA   -    MD0080PA00X+055226Y+106314X0160Y         S0      
317GND              VIA   -    MD0080PA00X+055966Y+105676X0160Y         S0      
317GND              VIA   -    MD0080PA00X+055966Y+105038X0160Y         S0      
317GND              VIA   -    MD0080PA00X+055781Y+105995X0160Y         S0      
317GND              VIA   -    MD0080PA00X+055411Y+105995X0160Y         S0      
317GND              VIA   -    MD0080PA00X+055226Y+105038X0160Y         S0      
317GND              VIA   -    MD0080PA00X+055411Y+105357X0160Y         S0      
317GND              VIA   -    MD0080PA00X+055596Y+105676X0160Y         S0      
317GND              VIA   -    MD0080PA00X+055226Y+105676X0160Y         S0      
317GND              VIA   -    MD0080PA00X+054671Y+105995X0160Y         S0      
317GND              VIA   -    MD0080PA00X+054671Y+105357X0160Y         S0      
317GND              VIA   -    MD0080PA00X+054486Y+105676X0160Y         S0      
317GND              VIA   -    MD0080PA00X+055411Y+104719X0160Y         S0      
317GND              VIA   -    MD0080PA00X+054671Y+104719X0160Y         S0      
317GND              VIA   -    MD0080PA00X+055966Y+108227X0160Y         S0      
317GND              VIA   -    MD0080PA00X+055966Y+108865X0160Y         S0      
317GND              VIA   -    MD0080PA00X+055966Y+107589X0160Y         S0      
317GND              VIA   -    MD0080PA00X+055226Y+108227X0160Y         S0      
317GND              VIA   -    MD0080PA00X+055411Y+108546X0160Y         S0      
317GND              VIA   -    MD0080PA00X+055226Y+108865X0160Y         S0      
317GND              VIA   -    MD0080PA00X+054671Y+108546X0160Y         S0      
317GND              VIA   -    MD0080PA00X+055411Y+107908X0160Y         S0      
317GND              VIA   -    MD0080PA00X+054671Y+107908X0160Y         S0      
317GND              VIA   -    MD0080PA00X+055226Y+107589X0160Y         S0      
317GND              VIA   -    MD0080PA00X+055966Y+111416X0160Y         S0      
317GND              VIA   -    MD0080PA00X+055966Y+110778X0160Y         S0      
317GND              VIA   -    MD0080PA00X+054671Y+111735X0160Y         S0      
317GND              VIA   -    MD0080PA00X+055226Y+111416X0160Y         S0      
317GND              VIA   -    MD0080PA00X+055411Y+111735X0160Y         S0      
317GND              VIA   -    MD0080PA00X+054671Y+111097X0160Y         S0      
317GND              VIA   -    MD0080PA00X+055411Y+111097X0160Y         S0      
317GND              VIA   -    MD0080PA00X+055226Y+110778X0160Y         S0      
317GND              VIA   -    MD0080PA00X+055966Y+110140X0160Y         S0      
317GND              VIA   -    MD0080PA00X+055966Y+109502X0160Y         S0      
317GND              VIA   -    MD0080PA00X+055411Y+110459X0160Y         S0      
317GND              VIA   -    MD0080PA00X+054671Y+109821X0160Y         S0      
317GND              VIA   -    MD0080PA00X+054671Y+110459X0160Y         S0      
317GND              VIA   -    MD0080PA00X+055411Y+109821X0160Y         S0      
317GND              VIA   -    MD0080PA00X+055226Y+110140X0160Y         S0      
317GND              VIA   -    MD0080PA00X+055226Y+109502X0160Y         S0      
317GND              VIA   -    MD0080PA00X+055411Y+109184X0160Y         S0      
317GND              VIA   -    MD0080PA00X+054671Y+109184X0160Y         S0      
317GND              VIA   -    MD0080PA00X+055966Y+113329X0160Y         S0      
317GND              VIA   -    MD0080PA00X+055966Y+112692X0160Y         S0      
317GND              VIA   -    MD0080PA00X+055966Y+112054X0160Y         S0      
317GND              VIA   -    MD0080PA00X+055411Y+113010X0160Y         S0      
317GND              VIA   -    MD0080PA00X+055226Y+113329X0160Y         S0      
317GND              VIA   -    MD0080PA00X+055226Y+112692X0160Y         S0      
317GND              VIA   -    MD0080PA00X+055226Y+112054X0160Y         S0      
317GND              VIA   -    MD0080PA00X+055411Y+112373X0160Y         S0      
317GND              VIA   -    MD0080PA00X+054671Y+112373X0160Y         S0      
317GND              VIA   -    MD0080PA00X+055966Y+115880X0160Y         S0      
317GND              VIA   -    MD0080PA00X+055966Y+115243X0160Y         S0      
317GND              VIA   -    MD0080PA00X+055411Y+116199X0160Y         S0      
317GND              VIA   -    MD0080PA00X+054671Y+115562X0160Y         S0      
317GND              VIA   -    MD0080PA00X+054856Y+115880X0160Y         S0      
317GND              VIA   -    MD0080PA00X+055226Y+115880X0160Y         S0      
317GND              VIA   -    MD0080PA00X+055596Y+115880X0160Y         S0      
317GND              VIA   -    MD0080PA00X+055226Y+115243X0160Y         S0      
317GND              VIA   -    MD0080PA00X+055411Y+115562X0160Y         S0      
317GND              VIA   -    MD0080PA00X+055596Y+116518X0160Y         S0      
317GND              VIA   -    MD0080PA00X+055966Y+114605X0160Y         S0      
317GND              VIA   -    MD0080PA00X+055966Y+113967X0160Y         S0      
317GND              VIA   -    MD0080PA00X+055411Y+114924X0160Y         S0      
317GND              VIA   -    MD0080PA00X+055226Y+114605X0160Y         S0      
317GND              VIA   -    MD0080PA00X+054671Y+114924X0160Y         S0      
317GND              VIA   -    MD0080PA00X+054671Y+114286X0160Y         S0      
317GND              VIA   -    MD0080PA00X+055411Y+114286X0160Y         S0      
317GND              VIA   -    MD0080PA00X+054671Y+113648X0160Y         S0      
317GND              VIA   -    MD0080PA00X+055411Y+113648X0160Y         S0      
317GND              VIA   -    MD0080PA00X+055226Y+113967X0160Y         S0      
317GND              VIA   -    MD0080PA00X+056588Y+091151X0160Y    R180 S0      
317GND              VIA   -    MD0080PA00X+057144Y+090832X0160Y    R180 S0      
317GND              VIA   -    MD0080PA00X+056403Y+090832X0160Y    R180 S0      
317GND              VIA   -    MD0080PA00X+056588Y+089876X0160Y    R180 S0      
317GND              VIA   -    MD0080PA00X+057144Y+090195X0160Y    R180 S0      
317GND              VIA   -    MD0080PA00X+056403Y+090195X0160Y    R180 S0      
317GND              VIA   -    MD0080PA00X+057144Y+089557X0160Y    R180 S0      
317GND              VIA   -    MD0080PA00X+056588Y+089238X0160Y    R180 S0      
317GND              VIA   -    MD0080PA00X+056403Y+088919X0160Y    R180 S0      
317GND              VIA   -    MD0080PA00X+057144Y+088919X0160Y    R180 S0      
317GND              VIA   -    MD0080PA00X+057144Y+088281X0160Y    R180 S0      
317GND              VIA   -    MD0080PA00X+056959Y+088600X0160Y    R180 S0      
317GND              VIA   -    MD0080PA00X+056403Y+088281X0160Y    R180 S0      
317GND              VIA   -    MD0080PA00X+056033Y+088281X0160Y    R180 S0      
317GND              VIA   -    MD0080PA00X+056959Y+087325X0160Y    R180 S0      
317GND              VIA   -    MD0080PA00X+056218Y+087962X0160Y    R180 S0      
317GND              VIA   -    MD0080PA00X+056588Y+095616X0160Y    R180 S0      
317GND              VIA   -    MD0080PA00X+057144Y+095297X0160Y    R180 S0      
317GND              VIA   -    MD0080PA00X+057144Y+094659X0160Y    R180 S0      
317GND              VIA   -    MD0080PA00X+056403Y+094659X0160Y    R180 S0      
317GND              VIA   -    MD0080PA00X+056588Y+094978X0160Y    R180 S0      
317GND              VIA   -    MD0080PA00X+057144Y+094021X0160Y    R180 S0      
317GND              VIA   -    MD0080PA00X+056403Y+094021X0160Y    R180 S0      
317GND              VIA   -    MD0080PA00X+056588Y+093702X0160Y    R180 S0      
317GND              VIA   -    MD0080PA00X+057144Y+093384X0160Y    R180 S0      
317GND              VIA   -    MD0080PA00X+056588Y+093065X0160Y    R180 S0      
317GND              VIA   -    MD0080PA00X+057144Y+092746X0160Y    R180 S0      
317GND              VIA   -    MD0080PA00X+056403Y+092746X0160Y    R180 S0      
317GND              VIA   -    MD0080PA00X+057144Y+092108X0160Y    R180 S0      
317GND              VIA   -    MD0080PA00X+056403Y+092108X0160Y    R180 S0      
317GND              VIA   -    MD0080PA00X+057144Y+091470X0160Y    R180 S0      
317GND              VIA   -    MD0080PA00X+056588Y+091789X0160Y    R180 S0      
317GND              VIA   -    MD0080PA00X+056588Y+098805X0160Y    R180 S0      
317GND              VIA   -    MD0080PA00X+057144Y+098486X0160Y    R180 S0      
317GND              VIA   -    MD0080PA00X+056403Y+098486X0160Y    R180 S0      
317GND              VIA   -    MD0080PA00X+056033Y+098486X0160Y    R180 S0      
317GND              VIA   -    MD0080PA00X+056774Y+098486X0160Y    R180 S0      
317GND              VIA   -    MD0080PA00X+057144Y+097848X0160Y    R180 S0      
317GND              VIA   -    MD0080PA00X+056403Y+097848X0160Y    R180 S0      
317GND              VIA   -    MD0080PA00X+057144Y+097210X0160Y    R180 S0      
317GND              VIA   -    MD0080PA00X+056588Y+097529X0160Y    R180 S0      
317GND              VIA   -    MD0080PA00X+056218Y+098167X0160Y    R180 S0      
317GND              VIA   -    MD0080PA00X+056588Y+096892X0160Y    R180 S0      
317GND              VIA   -    MD0080PA00X+057144Y+096573X0160Y    R180 S0      
317GND              VIA   -    MD0080PA00X+056403Y+096573X0160Y    R180 S0      
317GND              VIA   -    MD0080PA00X+057144Y+095935X0160Y    R180 S0      
317GND              VIA   -    MD0080PA00X+056403Y+095935X0160Y    R180 S0      
317GND              VIA   -    MD0080PA00X+056892Y+105995X0160Y         S0      
317GND              VIA   -    MD0080PA00X+057262Y+105995X0160Y         S0      
317GND              VIA   -    MD0080PA00X+056522Y+105357X0160Y         S0      
317GND              VIA   -    MD0080PA00X+057077Y+105676X0160Y         S0      
317GND              VIA   -    MD0080PA00X+057262Y+105357X0160Y         S0      
317GND              VIA   -    MD0080PA00X+056707Y+105038X0160Y         S0      
317GND              VIA   -    MD0080PA00X+057262Y+104719X0160Y         S0      
317GND              VIA   -    MD0080PA00X+056707Y+104400X0160Y         S0      
317GND              VIA   -    MD0080PA00X+057262Y+104081X0160Y         S0      
317GND              VIA   -    MD0080PA00X+057262Y+103443X0160Y         S0      
317GND              VIA   -    MD0080PA00X+056522Y+104081X0160Y         S0      
317GND              VIA   -    MD0080PA00X+056522Y+103443X0160Y         S0      
317GND              VIA   -    MD0080PA00X+056707Y+103124X0160Y         S0      
317GND              VIA   -    MD0080PA00X+057262Y+102806X0160Y         S0      
317GND              VIA   -    MD0080PA00X+056522Y+102806X0160Y         S0      
317GND              VIA   -    MD0080PA00X+057144Y+100399X0160Y    R180 S0      
317GND              VIA   -    MD0080PA00X+056403Y+100399X0160Y    R180 S0      
317GND              VIA   -    MD0080PA00X+056588Y+100718X0160Y    R180 S0      
317GND              VIA   -    MD0080PA00X+057144Y+101037X0160Y    R180 S0      
317GND              VIA   -    MD0080PA00X+057144Y+099762X0160Y    R180 S0      
317GND              VIA   -    MD0080PA00X+056403Y+099762X0160Y    R180 S0      
317GND              VIA   -    MD0080PA00X+056588Y+099443X0160Y    R180 S0      
317GND              VIA   -    MD0080PA00X+057144Y+099124X0160Y    R180 S0      
317GND              VIA   -    MD0080PA00X+056959Y+098805X0160Y    R180 S0      
317GND              VIA   -    MD0080PA00X+056522Y+109821X0160Y         S0      
317GND              VIA   -    MD0080PA00X+056707Y+110140X0160Y         S0      
317GND              VIA   -    MD0080PA00X+057262Y+109821X0160Y         S0      
317GND              VIA   -    MD0080PA00X+057262Y+110459X0160Y         S0      
317GND              VIA   -    MD0080PA00X+056522Y+109184X0160Y         S0      
317GND              VIA   -    MD0080PA00X+057262Y+109184X0160Y         S0      
317GND              VIA   -    MD0080PA00X+056707Y+108227X0160Y         S0      
317GND              VIA   -    MD0080PA00X+057262Y+108546X0160Y         S0      
317GND              VIA   -    MD0080PA00X+056707Y+108865X0160Y         S0      
317GND              VIA   -    MD0080PA00X+057262Y+107908X0160Y         S0      
317GND              VIA   -    MD0080PA00X+056522Y+107908X0160Y         S0      
317GND              VIA   -    MD0080PA00X+056522Y+107270X0160Y         S0      
317GND              VIA   -    MD0080PA00X+056707Y+106951X0160Y         S0      
317GND              VIA   -    MD0080PA00X+057262Y+107270X0160Y         S0      
317GND              VIA   -    MD0080PA00X+057262Y+106632X0160Y         S0      
317GND              VIA   -    MD0080PA00X+056707Y+106314X0160Y         S0      
317GND              VIA   -    MD0080PA00X+056522Y+105995X0160Y         S0      
317GND              VIA   -    MD0080PA00X+056522Y+113648X0160Y         S0      
317GND              VIA   -    MD0080PA00X+056707Y+113967X0160Y         S0      
317GND              VIA   -    MD0080PA00X+057262Y+114286X0160Y         S0      
317GND              VIA   -    MD0080PA00X+056522Y+113010X0160Y         S0      
317GND              VIA   -    MD0080PA00X+057262Y+113010X0160Y         S0      
317GND              VIA   -    MD0080PA00X+056707Y+112692X0160Y         S0      
317GND              VIA   -    MD0080PA00X+056707Y+112054X0160Y         S0      
317GND              VIA   -    MD0080PA00X+057262Y+112373X0160Y         S0      
317GND              VIA   -    MD0080PA00X+056522Y+111735X0160Y         S0      
317GND              VIA   -    MD0080PA00X+057262Y+111735X0160Y         S0      
317GND              VIA   -    MD0080PA00X+056522Y+111097X0160Y         S0      
317GND              VIA   -    MD0080PA00X+057262Y+111097X0160Y         S0      
317GND              VIA   -    MD0080PA00X+056707Y+110778X0160Y         S0      
317GND              VIA   -    MD0080PA00X+056522Y+116199X0160Y         S0      
317GND              VIA   -    MD0080PA00X+056152Y+115562X0160Y         S0      
317GND              VIA   -    MD0080PA00X+057262Y+115562X0160Y         S0      
317GND              VIA   -    MD0080PA00X+056892Y+115562X0160Y         S0      
317GND              VIA   -    MD0080PA00X+056522Y+115562X0160Y         S0      
317GND              VIA   -    MD0080PA00X+057447Y+115880X0160Y         S0      
317GND              VIA   -    MD0080PA00X+056707Y+114605X0160Y         S0      
317GND              VIA   -    MD0080PA00X+057262Y+114924X0160Y         S0      
317GND              VIA   -    MD0080PA00X+056522Y+114924X0160Y         S0      
317GND              VIA   -    MD0080PA00X+057262Y+113648X0160Y         S0      
317GND              VIA   -    MD0080PA00X+057817Y+115880X0160Y         S0      
317GND              VIA   -    MD0080PA00X+057891Y+115138X0160Y         S0      
317GND              VIA   -    MD0080PA00X+057891Y+114500X0160Y         S0      
317GND              VIA   -    MD0080PA00X+057891Y+113862X0160Y         S0      
317GND              VIA   -    MD0080PA00X+057891Y+113225X0160Y         S0      
317GND              VIA   -    MD0080PA00X+057891Y+112587X0160Y         S0      
317GND              VIA   -    MD0080PA00X+057891Y+111949X0160Y         S0      
317GND              VIA   -    MD0080PA00X+057891Y+111311X0160Y         S0      
317GND              VIA   -    MD0080PA00X+057891Y+110673X0160Y         S0      
317GND              VIA   -    MD0080PA00X+057891Y+110036X0160Y         S0      
317GND              VIA   -    MD0080PA00X+057891Y+109398X0160Y         S0      
317GND              VIA   -    MD0080PA00X+057891Y+108122X0160Y         S0      
317GND              VIA   -    MD0080PA00X+057891Y+108760X0160Y         S0      
317GND              VIA   -    MD0080PA00X+057891Y+106847X0160Y         S0      
317GND              VIA   -    MD0080PA00X+057891Y+107484X0160Y         S0      
317GND              VIA   -    MD0080PA00X+057891Y+106209X0160Y         S0      
317GND              VIA   -    MD0080PA00X+057891Y+105571X0160Y         S0      
317GND              VIA   -    MD0080PA00X+057891Y+104933X0160Y         S0      
317GND              VIA   -    MD0080PA00X+057891Y+104295X0160Y         S0      
317GND              VIA   -    MD0080PA00X+057891Y+103658X0160Y         S0      
317GND              VIA   -    MD0080PA00X+057891Y+103020X0160Y         S0      
317GND              VIA   -    MD0080PA00X+057773Y+100185X0160Y         S0      
317GND              VIA   -    MD0080PA00X+057773Y+100823X0160Y         S0      
317GND              VIA   -    MD0080PA00X+057773Y+099547X0160Y         S0      
317GND              VIA   -    MD0080PA00X+057773Y+098910X0160Y         S0      
317GND              VIA   -    MD0080PA00X+057773Y+098272X0160Y         S0      
317GND              VIA   -    MD0080PA00X+057773Y+097634X0160Y         S0      
317GND              VIA   -    MD0080PA00X+057773Y+096996X0160Y         S0      
317GND              VIA   -    MD0080PA00X+057773Y+096358X0160Y         S0      
317GND              VIA   -    MD0080PA00X+057773Y+095721X0160Y         S0      
317GND              VIA   -    MD0080PA00X+057773Y+095083X0160Y         S0      
317GND              VIA   -    MD0080PA00X+057773Y+094445X0160Y         S0      
317GND              VIA   -    MD0080PA00X+057773Y+093807X0160Y         S0      
317GND              VIA   -    MD0080PA00X+057773Y+093169X0160Y         S0      
317GND              VIA   -    MD0080PA00X+057773Y+092532X0160Y         S0      
317GND              VIA   -    MD0080PA00X+057773Y+091894X0160Y         S0      
317GND              VIA   -    MD0080PA00X+057773Y+091256X0160Y         S0      
317GND              VIA   -    MD0080PA00X+057773Y+090618X0160Y         S0      
317GND              VIA   -    MD0080PA00X+057699Y+089876X0160Y    R180 S0      
317GND              VIA   -    MD0080PA00X+057699Y+089238X0160Y    R180 S0      
317GND              VIA   -    MD0080PA00X+057699Y+088600X0160Y    R180 S0      
317GND              VIA   -    MD0080PA00X+057514Y+088281X0160Y    R180 S0      
317GND              VIA   -    MD0080PA00X+057699Y+087962X0160Y    R180 S0      
317GND              VIA   -    MD0080PA00X+127856Y+094445X0160Y    R180 S0      
317GND              VIA   -    MD0080PA00X+128485Y+094021X0160Y    R180 S0      
317GND              VIA   -    MD0080PA00X+127856Y+093807X0160Y    R180 S0      
317GND              VIA   -    MD0080PA00X+127856Y+093169X0160Y    R180 S0      
317GND              VIA   -    MD0080PA00X+128485Y+093384X0160Y    R180 S0      
317GND              VIA   -    MD0080PA00X+128485Y+092746X0160Y    R180 S0      
317GND              VIA   -    MD0080PA00X+127856Y+092532X0160Y    R180 S0      
317GND              VIA   -    MD0080PA00X+128485Y+092108X0160Y    R180 S0      
317GND              VIA   -    MD0080PA00X+127856Y+091894X0160Y    R180 S0      
317GND              VIA   -    MD0080PA00X+128485Y+091470X0160Y    R180 S0      
317GND              VIA   -    MD0080PA00X+127856Y+091256X0160Y    R180 S0      
317GND              VIA   -    MD0080PA00X+127856Y+090618X0160Y    R180 S0      
317GND              VIA   -    MD0080PA00X+128485Y+090832X0160Y    R180 S0      
317GND              VIA   -    MD0080PA00X+127930Y+089876X0160Y    R180 S0      
317GND              VIA   -    MD0080PA00X+128485Y+090195X0160Y    R180 S0      
317GND              VIA   -    MD0080PA00X+127930Y+089238X0160Y    R180 S0      
317GND              VIA   -    MD0080PA00X+128485Y+088919X0160Y    R180 S0      
317GND              VIA   -    MD0080PA00X+127930Y+088600X0160Y    R180 S0      
317GND              VIA   -    MD0080PA00X+128115Y+088281X0160Y    R180 S0      
317GND              VIA   -    MD0080PA00X+128670Y+088600X0160Y    R180 S0      
317GND              VIA   -    MD0080PA00X+128485Y+088281X0160Y    R180 S0      
317GND              VIA   -    MD0080PA00X+128485Y+089557X0160Y    R180 S0      
317GND              VIA   -    MD0080PA00X+127930Y+087962X0160Y    R180 S0      
317GND              VIA   -    MD0080PA00X+128670Y+087962X0160Y    R180 S0      
317GND              VIA   -    MD0080PA00X+128670Y+087324X0160Y    R180 S0      
317GND              VIA   -    MD0080PA00X+128603Y+114924X0160Y         S0      
317GND              VIA   -    MD0080PA00X+127974Y+114500X0160Y    R180 S0      
317GND              VIA   -    MD0080PA00X+128603Y+114286X0160Y         S0      
317GND              VIA   -    MD0080PA00X+128603Y+113648X0160Y         S0      
317GND              VIA   -    MD0080PA00X+127974Y+113862X0160Y    R180 S0      
317GND              VIA   -    MD0080PA00X+127974Y+113224X0160Y    R180 S0      
317GND              VIA   -    MD0080PA00X+128603Y+113010X0160Y         S0      
317GND              VIA   -    MD0080PA00X+128603Y+112372X0160Y         S0      
317GND              VIA   -    MD0080PA00X+127974Y+112587X0160Y    R180 S0      
317GND              VIA   -    MD0080PA00X+128603Y+111735X0160Y         S0      
317GND              VIA   -    MD0080PA00X+127974Y+111949X0160Y    R180 S0      
317GND              VIA   -    MD0080PA00X+127974Y+111311X0160Y    R180 S0      
317GND              VIA   -    MD0080PA00X+128603Y+111097X0160Y         S0      
317GND              VIA   -    MD0080PA00X+127974Y+110673X0160Y    R180 S0      
317GND              VIA   -    MD0080PA00X+128603Y+110459X0160Y         S0      
317GND              VIA   -    MD0080PA00X+128603Y+109821X0160Y         S0      
317GND              VIA   -    MD0080PA00X+127974Y+110036X0160Y    R180 S0      
317GND              VIA   -    MD0080PA00X+128603Y+109184X0160Y         S0      
317GND              VIA   -    MD0080PA00X+127974Y+109398X0160Y    R180 S0      
317GND              VIA   -    MD0080PA00X+128603Y+108546X0160Y         S0      
317GND              VIA   -    MD0080PA00X+127974Y+108760X0160Y    R180 S0      
317GND              VIA   -    MD0080PA00X+127974Y+108122X0160Y    R180 S0      
317GND              VIA   -    MD0080PA00X+128603Y+107908X0160Y         S0      
317GND              VIA   -    MD0080PA00X+128603Y+107270X0160Y         S0      
317GND              VIA   -    MD0080PA00X+128603Y+106632X0160Y         S0      
317GND              VIA   -    MD0080PA00X+127974Y+107484X0160Y    R180 S0      
317GND              VIA   -    MD0080PA00X+127974Y+106846X0160Y    R180 S0      
317GND              VIA   -    MD0080PA00X+127974Y+106209X0160Y    R180 S0      
317GND              VIA   -    MD0080PA00X+127974Y+104933X0160Y    R180 S0      
317GND              VIA   -    MD0080PA00X+127974Y+105571X0160Y    R180 S0      
317GND              VIA   -    MD0080PA00X+128603Y+105994X0160Y         S0      
317GND              VIA   -    MD0080PA00X+128973Y+105994X0160Y         S0      
317GND              VIA   -    MD0080PA00X+128788Y+105676X0160Y         S0      
317GND              VIA   -    MD0080PA00X+128603Y+105357X0160Y         S0      
317GND              VIA   -    MD0080PA00X+128603Y+104719X0160Y         S0      
317GND              VIA   -    MD0080PA00X+127974Y+103658X0160Y    R180 S0      
317GND              VIA   -    MD0080PA00X+127974Y+104295X0160Y    R180 S0      
317GND              VIA   -    MD0080PA00X+128603Y+104081X0160Y         S0      
317GND              VIA   -    MD0080PA00X+128603Y+103443X0160Y         S0      
317GND              VIA   -    MD0080PA00X+128603Y+102806X0160Y         S0      
317GND              VIA   -    MD0080PA00X+127974Y+103020X0160Y    R180 S0      
317GND              VIA   -    MD0080PA00X+127856Y+100185X0160Y    R180 S0      
317GND              VIA   -    MD0080PA00X+127856Y+100823X0160Y    R180 S0      
317GND              VIA   -    MD0080PA00X+128485Y+100399X0160Y    R180 S0      
317GND              VIA   -    MD0080PA00X+128485Y+101037X0160Y    R180 S0      
317GND              VIA   -    MD0080PA00X+128485Y+099762X0160Y    R180 S0      
317GND              VIA   -    MD0080PA00X+127856Y+098910X0160Y    R180 S0      
317GND              VIA   -    MD0080PA00X+128670Y+098805X0160Y    R180 S0      
317GND              VIA   -    MD0080PA00X+128485Y+099124X0160Y    R180 S0      
317GND              VIA   -    MD0080PA00X+127856Y+099547X0160Y    R180 S0      
317GND              VIA   -    MD0080PA00X+128855Y+098486X0160Y    R180 S0      
317GND              VIA   -    MD0080PA00X+128485Y+098486X0160Y    R180 S0      
317GND              VIA   -    MD0080PA00X+127856Y+098272X0160Y    R180 S0      
317GND              VIA   -    MD0080PA00X+128485Y+097848X0160Y    R180 S0      
317GND              VIA   -    MD0080PA00X+127856Y+097634X0160Y    R180 S0      
317GND              VIA   -    MD0080PA00X+128485Y+097210X0160Y    R180 S0      
317GND              VIA   -    MD0080PA00X+127856Y+096996X0160Y    R180 S0      
317GND              VIA   -    MD0080PA00X+127856Y+096358X0160Y    R180 S0      
317GND              VIA   -    MD0080PA00X+128485Y+096572X0160Y    R180 S0      
317GND              VIA   -    MD0080PA00X+127856Y+095720X0160Y    R180 S0      
317GND              VIA   -    MD0080PA00X+128485Y+095935X0160Y    R180 S0      
317GND              VIA   -    MD0080PA00X+128485Y+095297X0160Y    R180 S0      
317GND              VIA   -    MD0080PA00X+127856Y+095083X0160Y    R180 S0      
317GND              VIA   -    MD0080PA00X+128485Y+094659X0160Y    R180 S0      
317GND              VIA   -    MD0080PA00X+128788Y+116518X0160Y         S0      
317GND              VIA   -    MD0080PA00X+128418Y+115880X0160Y         S0      
317GND              VIA   -    MD0080PA00X+128603Y+115561X0160Y         S0      
317GND              VIA   -    MD0080PA00X+128973Y+115561X0160Y         S0      
317GND              VIA   -    MD0080PA00X+127974Y+115776X0160Y    R180 S0      
317GND              VIA   -    MD0080PA00X+127974Y+115138X0160Y    R180 S0      
317GND              VIA   -    MD0080PA00X+129595Y+087643X0160Y    R180 S0      
317GND              VIA   -    MD0080PA00X+129410Y+087962X0160Y    R180 S0      
317GND              VIA   -    MD0080PA00X+130335Y+087643X0160Y    R180 S0      
317GND              VIA   -    MD0080PA00X+130150Y+087962X0160Y    R180 S0      
317GND              VIA   -    MD0080PA00X+129040Y+087324X0160Y    R180 S0      
317GND              VIA   -    MD0080PA00X+130335Y+090832X0160Y    R180 S0      
317GND              VIA   -    MD0080PA00X+129780Y+091151X0160Y    R180 S0      
317GND              VIA   -    MD0080PA00X+129780Y+090513X0160Y    R180 S0      
317GND              VIA   -    MD0080PA00X+129225Y+090832X0160Y    R180 S0      
317GND              VIA   -    MD0080PA00X+130335Y+090195X0160Y    R180 S0      
317GND              VIA   -    MD0080PA00X+129780Y+089876X0160Y    R180 S0      
317GND              VIA   -    MD0080PA00X+129225Y+090195X0160Y    R180 S0      
317GND              VIA   -    MD0080PA00X+129040Y+091151X0160Y    R180 S0      
317GND              VIA   -    MD0080PA00X+129040Y+089876X0160Y    R180 S0      
317GND              VIA   -    MD0080PA00X+129780Y+089238X0160Y    R180 S0      
317GND              VIA   -    MD0080PA00X+130335Y+088919X0160Y    R180 S0      
317GND              VIA   -    MD0080PA00X+129225Y+088919X0160Y    R180 S0      
317GND              VIA   -    MD0080PA00X+129595Y+088281X0160Y    R180 S0      
317GND              VIA   -    MD0080PA00X+130150Y+088600X0160Y    R180 S0      
317GND              VIA   -    MD0080PA00X+129780Y+088600X0160Y    R180 S0      
317GND              VIA   -    MD0080PA00X+129225Y+088281X0160Y    R180 S0      
317GND              VIA   -    MD0080PA00X+129040Y+089238X0160Y    R180 S0      
317GND              VIA   -    MD0080PA00X+129040Y+088600X0160Y    R180 S0      
317GND              VIA   -    MD0080PA00X+130335Y+089557X0160Y    R180 S0      
317GND              VIA   -    MD0080PA00X+129040Y+093702X0160Y    R180 S0      
317GND              VIA   -    MD0080PA00X+129040Y+093065X0160Y    R180 S0      
317GND              VIA   -    MD0080PA00X+129225Y+092108X0160Y    R180 S0      
317GND              VIA   -    MD0080PA00X+129780Y+092427X0160Y    R180 S0      
317GND              VIA   -    MD0080PA00X+130335Y+092108X0160Y    R180 S0      
317GND              VIA   -    MD0080PA00X+130335Y+091470X0160Y    R180 S0      
317GND              VIA   -    MD0080PA00X+129780Y+091789X0160Y    R180 S0      
317GND              VIA   -    MD0080PA00X+129040Y+091789X0160Y    R180 S0      
317GND              VIA   -    MD0080PA00X+129780Y+095616X0160Y    R180 S0      
317GND              VIA   -    MD0080PA00X+130335Y+095297X0160Y    R180 S0      
317GND              VIA   -    MD0080PA00X+129780Y+094340X0160Y    R180 S0      
317GND              VIA   -    MD0080PA00X+129225Y+094659X0160Y    R180 S0      
317GND              VIA   -    MD0080PA00X+130335Y+094659X0160Y    R180 S0      
317GND              VIA   -    MD0080PA00X+129780Y+094978X0160Y    R180 S0      
317GND              VIA   -    MD0080PA00X+129040Y+095616X0160Y    R180 S0      
317GND              VIA   -    MD0080PA00X+129040Y+094978X0160Y    R180 S0      
317GND              VIA   -    MD0080PA00X+129225Y+094021X0160Y    R180 S0      
317GND              VIA   -    MD0080PA00X+129780Y+093702X0160Y    R180 S0      
317GND              VIA   -    MD0080PA00X+130335Y+094021X0160Y    R180 S0      
317GND              VIA   -    MD0080PA00X+129225Y+092746X0160Y    R180 S0      
317GND              VIA   -    MD0080PA00X+130335Y+093384X0160Y    R180 S0      
317GND              VIA   -    MD0080PA00X+130335Y+092746X0160Y    R180 S0      
317GND              VIA   -    MD0080PA00X+129780Y+093065X0160Y    R180 S0      
317GND              VIA   -    MD0080PA00X+129225Y+098486X0160Y    R180 S0      
317GND              VIA   -    MD0080PA00X+129595Y+098486X0160Y    R180 S0      
317GND              VIA   -    MD0080PA00X+130335Y+098486X0160Y    R180 S0      
317GND              VIA   -    MD0080PA00X+129225Y+097848X0160Y    R180 S0      
317GND              VIA   -    MD0080PA00X+129410Y+098167X0160Y    R180 S0      
317GND              VIA   -    MD0080PA00X+130335Y+097848X0160Y    R180 S0      
317GND              VIA   -    MD0080PA00X+130335Y+097210X0160Y    R180 S0      
317GND              VIA   -    MD0080PA00X+129780Y+097529X0160Y    R180 S0      
317GND              VIA   -    MD0080PA00X+129780Y+098167X0160Y    R180 S0      
317GND              VIA   -    MD0080PA00X+129040Y+097529X0160Y    R180 S0      
317GND              VIA   -    MD0080PA00X+129780Y+096891X0160Y    R180 S0      
317GND              VIA   -    MD0080PA00X+129225Y+096572X0160Y    R180 S0      
317GND              VIA   -    MD0080PA00X+129225Y+095935X0160Y    R180 S0      
317GND              VIA   -    MD0080PA00X+130335Y+096572X0160Y    R180 S0      
317GND              VIA   -    MD0080PA00X+130335Y+095935X0160Y    R180 S0      
317GND              VIA   -    MD0080PA00X+129780Y+096254X0160Y    R180 S0      
317GND              VIA   -    MD0080PA00X+129040Y+096891X0160Y    R180 S0      
317GND              VIA   -    MD0080PA00X+130453Y+102806X0160Y         S0      
317GND              VIA   -    MD0080PA00X+129225Y+100399X0160Y    R180 S0      
317GND              VIA   -    MD0080PA00X+130335Y+100399X0160Y    R180 S0      
317GND              VIA   -    MD0080PA00X+130335Y+101037X0160Y    R180 S0      
317GND              VIA   -    MD0080PA00X+129780Y+100718X0160Y    R180 S0      
317GND              VIA   -    MD0080PA00X+129225Y+101037X0160Y    R180 S0      
317GND              VIA   -    MD0080PA00X+129040Y+100718X0160Y    R180 S0      
317GND              VIA   -    MD0080PA00X+129780Y+100080X0160Y    R180 S0      
317GND              VIA   -    MD0080PA00X+129225Y+099762X0160Y    R180 S0      
317GND              VIA   -    MD0080PA00X+130335Y+099762X0160Y    R180 S0      
317GND              VIA   -    MD0080PA00X+130335Y+099124X0160Y    R180 S0      
317GND              VIA   -    MD0080PA00X+129780Y+098805X0160Y    R180 S0      
317GND              VIA   -    MD0080PA00X+129780Y+099443X0160Y    R180 S0      
317GND              VIA   -    MD0080PA00X+129040Y+099443X0160Y    R180 S0      
317GND              VIA   -    MD0080PA00X+129040Y+098805X0160Y    R180 S0      
317GND              VIA   -    MD0080PA00X+130453Y+105994X0160Y         S0      
317GND              VIA   -    MD0080PA00X+130083Y+105994X0160Y         S0      
317GND              VIA   -    MD0080PA00X+129898Y+105676X0160Y         S0      
317GND              VIA   -    MD0080PA00X+130268Y+105676X0160Y         S0      
317GND              VIA   -    MD0080PA00X+129898Y+105038X0160Y         S0      
317GND              VIA   -    MD0080PA00X+130453Y+105357X0160Y         S0      
317GND              VIA   -    MD0080PA00X+129343Y+105994X0160Y         S0      
317GND              VIA   -    MD0080PA00X+129343Y+105357X0160Y         S0      
317GND              VIA   -    MD0080PA00X+129158Y+105038X0160Y         S0      
317GND              VIA   -    MD0080PA00X+130453Y+104719X0160Y         S0      
317GND              VIA   -    MD0080PA00X+129158Y+104400X0160Y         S0      
317GND              VIA   -    MD0080PA00X+129158Y+103124X0160Y         S0      
317GND              VIA   -    MD0080PA00X+129898Y+103124X0160Y         S0      
317GND              VIA   -    MD0080PA00X+130453Y+104081X0160Y         S0      
317GND              VIA   -    MD0080PA00X+130453Y+103443X0160Y         S0      
317GND              VIA   -    MD0080PA00X+129898Y+103762X0160Y         S0      
317GND              VIA   -    MD0080PA00X+129898Y+104400X0160Y         S0      
317GND              VIA   -    MD0080PA00X+129343Y+104081X0160Y         S0      
317GND              VIA   -    MD0080PA00X+129343Y+103443X0160Y         S0      
317GND              VIA   -    MD0080PA00X+129158Y+108865X0160Y         S0      
317GND              VIA   -    MD0080PA00X+129898Y+108227X0160Y         S0      
317GND              VIA   -    MD0080PA00X+129158Y+108227X0160Y         S0      
317GND              VIA   -    MD0080PA00X+129898Y+108865X0160Y         S0      
317GND              VIA   -    MD0080PA00X+130453Y+108546X0160Y         S0      
317GND              VIA   -    MD0080PA00X+130453Y+107908X0160Y         S0      
317GND              VIA   -    MD0080PA00X+129343Y+107908X0160Y         S0      
317GND              VIA   -    MD0080PA00X+129898Y+107589X0160Y         S0      
317GND              VIA   -    MD0080PA00X+129898Y+106951X0160Y         S0      
317GND              VIA   -    MD0080PA00X+130453Y+106632X0160Y         S0      
317GND              VIA   -    MD0080PA00X+130453Y+107270X0160Y         S0      
317GND              VIA   -    MD0080PA00X+129343Y+107270X0160Y         S0      
317GND              VIA   -    MD0080PA00X+129158Y+106951X0160Y         S0      
317GND              VIA   -    MD0080PA00X+129158Y+106313X0160Y         S0      
317GND              VIA   -    MD0080PA00X+129898Y+106313X0160Y         S0      
317GND              VIA   -    MD0080PA00X+130453Y+111735X0160Y         S0      
317GND              VIA   -    MD0080PA00X+129898Y+111416X0160Y         S0      
317GND              VIA   -    MD0080PA00X+129343Y+111735X0160Y         S0      
317GND              VIA   -    MD0080PA00X+130453Y+111097X0160Y         S0      
317GND              VIA   -    MD0080PA00X+129343Y+111097X0160Y         S0      
317GND              VIA   -    MD0080PA00X+129158Y+110778X0160Y         S0      
317GND              VIA   -    MD0080PA00X+129898Y+110778X0160Y         S0      
317GND              VIA   -    MD0080PA00X+129158Y+110140X0160Y         S0      
317GND              VIA   -    MD0080PA00X+130453Y+110459X0160Y         S0      
317GND              VIA   -    MD0080PA00X+130453Y+109821X0160Y         S0      
317GND              VIA   -    MD0080PA00X+129898Y+110140X0160Y         S0      
317GND              VIA   -    MD0080PA00X+129343Y+109821X0160Y         S0      
317GND              VIA   -    MD0080PA00X+129898Y+109502X0160Y         S0      
317GND              VIA   -    MD0080PA00X+130453Y+109184X0160Y         S0      
317GND              VIA   -    MD0080PA00X+129343Y+109184X0160Y         S0      
317GND              VIA   -    MD0080PA00X+129343Y+113010X0160Y         S0      
317GND              VIA   -    MD0080PA00X+129898Y+113329X0160Y         S0      
317GND              VIA   -    MD0080PA00X+130453Y+113010X0160Y         S0      
317GND              VIA   -    MD0080PA00X+129898Y+112691X0160Y         S0      
317GND              VIA   -    MD0080PA00X+129158Y+112691X0160Y         S0      
317GND              VIA   -    MD0080PA00X+130453Y+112372X0160Y         S0      
317GND              VIA   -    MD0080PA00X+129898Y+112054X0160Y         S0      
317GND              VIA   -    MD0080PA00X+129158Y+112054X0160Y         S0      
317GND              VIA   -    MD0080PA00X+133044Y+113010X0160Y         S0      
317GND              VIA   -    MD0080PA00X+129713Y+116199X0160Y         S0      
317GND              VIA   -    MD0080PA00X+130453Y+116199X0160Y         S0      
317GND              VIA   -    MD0080PA00X+129898Y+115880X0160Y         S0      
317GND              VIA   -    MD0080PA00X+130268Y+115880X0160Y         S0      
317GND              VIA   -    MD0080PA00X+129713Y+115561X0160Y         S0      
317GND              VIA   -    MD0080PA00X+129898Y+115242X0160Y         S0      
317GND              VIA   -    MD0080PA00X+130453Y+115561X0160Y         S0      
317GND              VIA   -    MD0080PA00X+129343Y+115561X0160Y         S0      
317GND              VIA   -    MD0080PA00X+130453Y+114924X0160Y         S0      
317GND              VIA   -    MD0080PA00X+129898Y+114605X0160Y         S0      
317GND              VIA   -    MD0080PA00X+129343Y+114924X0160Y         S0      
317GND              VIA   -    MD0080PA00X+129158Y+114605X0160Y         S0      
317GND              VIA   -    MD0080PA00X+130453Y+114286X0160Y         S0      
317GND              VIA   -    MD0080PA00X+129343Y+113648X0160Y         S0      
317GND              VIA   -    MD0080PA00X+129158Y+113967X0160Y         S0      
317GND              VIA   -    MD0080PA00X+129898Y+113967X0160Y         S0      
317GND              VIA   -    MD0080PA00X+130453Y+113648X0160Y         S0      
317GND              VIA   -    MD0080PA00X+131630Y+089238X0160Y    R180 S0      
317GND              VIA   -    MD0080PA00X+131815Y+088919X0160Y    R180 S0      
317GND              VIA   -    MD0080PA00X+131075Y+088919X0160Y    R180 S0      
317GND              VIA   -    MD0080PA00X+131815Y+088281X0160Y    R180 S0      
317GND              VIA   -    MD0080PA00X+131630Y+088600X0160Y    R180 S0      
317GND              VIA   -    MD0080PA00X+131260Y+088600X0160Y    R180 S0      
317GND              VIA   -    MD0080PA00X+131075Y+088281X0160Y    R180 S0      
317GND              VIA   -    MD0080PA00X+130520Y+089238X0160Y    R180 S0      
317GND              VIA   -    MD0080PA00X+130520Y+088600X0160Y    R180 S0      
317GND              VIA   -    MD0080PA00X+130705Y+088281X0160Y    R180 S0      
317GND              VIA   -    MD0080PA00X+131075Y+089557X0160Y    R180 S0      
317GND              VIA   -    MD0080PA00X+130890Y+087962X0160Y    R180 S0      
317GND              VIA   -    MD0080PA00X+130890Y+087324X0160Y    R180 S0      
317GND              VIA   -    MD0080PA00X+131445Y+087643X0160Y    R180 S0      
317GND              VIA   -    MD0080PA00X+131075Y+092108X0160Y    R180 S0      
317GND              VIA   -    MD0080PA00X+131815Y+092108X0160Y    R180 S0      
317GND              VIA   -    MD0080PA00X+131630Y+091789X0160Y    R180 S0      
317GND              VIA   -    MD0080PA00X+131075Y+091470X0160Y    R180 S0      
317GND              VIA   -    MD0080PA00X+130520Y+092427X0160Y    R180 S0      
317GND              VIA   -    MD0080PA00X+130520Y+091789X0160Y    R180 S0      
317GND              VIA   -    MD0080PA00X+131815Y+090832X0160Y    R180 S0      
317GND              VIA   -    MD0080PA00X+131630Y+091151X0160Y    R180 S0      
317GND              VIA   -    MD0080PA00X+131630Y+089876X0160Y    R180 S0      
317GND              VIA   -    MD0080PA00X+131815Y+090195X0160Y    R180 S0      
317GND              VIA   -    MD0080PA00X+131075Y+090195X0160Y    R180 S0      
317GND              VIA   -    MD0080PA00X+130520Y+091151X0160Y    R180 S0      
317GND              VIA   -    MD0080PA00X+130520Y+090513X0160Y    R180 S0      
317GND              VIA   -    MD0080PA00X+130520Y+089876X0160Y    R180 S0      
317GND              VIA   -    MD0080PA00X+131075Y+096572X0160Y    R180 S0      
317GND              VIA   -    MD0080PA00X+131075Y+095935X0160Y    R180 S0      
317GND              VIA   -    MD0080PA00X+130520Y+096891X0160Y    R180 S0      
317GND              VIA   -    MD0080PA00X+130520Y+096254X0160Y    R180 S0      
317GND              VIA   -    MD0080PA00X+131630Y+095616X0160Y    R180 S0      
317GND              VIA   -    MD0080PA00X+131075Y+095297X0160Y    R180 S0      
317GND              VIA   -    MD0080PA00X+131815Y+094659X0160Y    R180 S0      
317GND              VIA   -    MD0080PA00X+131630Y+094978X0160Y    R180 S0      
317GND              VIA   -    MD0080PA00X+131075Y+094659X0160Y    R180 S0      
317GND              VIA   -    MD0080PA00X+130520Y+095616X0160Y    R180 S0      
317GND              VIA   -    MD0080PA00X+130520Y+094978X0160Y    R180 S0      
317GND              VIA   -    MD0080PA00X+130520Y+094340X0160Y    R180 S0      
317GND              VIA   -    MD0080PA00X+131815Y+094021X0160Y    R180 S0      
317GND              VIA   -    MD0080PA00X+131075Y+094021X0160Y    R180 S0      
317GND              VIA   -    MD0080PA00X+131630Y+093702X0160Y    R180 S0      
317GND              VIA   -    MD0080PA00X+131630Y+093065X0160Y    R180 S0      
317GND              VIA   -    MD0080PA00X+131815Y+092746X0160Y    R180 S0      
317GND              VIA   -    MD0080PA00X+131075Y+093384X0160Y    R180 S0      
317GND              VIA   -    MD0080PA00X+131075Y+092746X0160Y    R180 S0      
317GND              VIA   -    MD0080PA00X+130520Y+093702X0160Y    R180 S0      
317GND              VIA   -    MD0080PA00X+130520Y+093065X0160Y    R180 S0      
317GND              VIA   -    MD0080PA00X+131630Y+099443X0160Y    R180 S0      
317GND              VIA   -    MD0080PA00X+131815Y+099762X0160Y    R180 S0      
317GND              VIA   -    MD0080PA00X+131630Y+098805X0160Y    R180 S0      
317GND              VIA   -    MD0080PA00X+131075Y+099762X0160Y    R180 S0      
317GND              VIA   -    MD0080PA00X+131075Y+099124X0160Y    R180 S0      
317GND              VIA   -    MD0080PA00X+130520Y+100080X0160Y    R180 S0      
317GND              VIA   -    MD0080PA00X+130520Y+099443X0160Y    R180 S0      
317GND              VIA   -    MD0080PA00X+130520Y+098805X0160Y    R180 S0      
317GND              VIA   -    MD0080PA00X+131815Y+098486X0160Y    R180 S0      
317GND              VIA   -    MD0080PA00X+131075Y+098486X0160Y    R180 S0      
317GND              VIA   -    MD0080PA00X+130890Y+098167X0160Y    R180 S0      
317GND              VIA   -    MD0080PA00X+131815Y+097848X0160Y    R180 S0      
317GND              VIA   -    MD0080PA00X+131630Y+097529X0160Y    R180 S0      
317GND              VIA   -    MD0080PA00X+131075Y+097848X0160Y    R180 S0      
317GND              VIA   -    MD0080PA00X+131075Y+097210X0160Y    R180 S0      
317GND              VIA   -    MD0080PA00X+130705Y+098486X0160Y    R180 S0      
317GND              VIA   -    MD0080PA00X+130520Y+098167X0160Y    R180 S0      
317GND              VIA   -    MD0080PA00X+130520Y+097529X0160Y    R180 S0      
317GND              VIA   -    MD0080PA00X+131630Y+096891X0160Y    R180 S0      
317GND              VIA   -    MD0080PA00X+131815Y+096572X0160Y    R180 S0      
317GND              VIA   -    MD0080PA00X+131815Y+095935X0160Y    R180 S0      
317GND              VIA   -    MD0080PA00X+131193Y+105357X0160Y         S0      
317GND              VIA   -    MD0080PA00X+131934Y+105357X0160Y         S0      
317GND              VIA   -    MD0080PA00X+131748Y+105038X0160Y         S0      
317GND              VIA   -    MD0080PA00X+131934Y+105994X0160Y         S0      
317GND              VIA   -    MD0080PA00X+131563Y+105994X0160Y         S0      
317GND              VIA   -    MD0080PA00X+131193Y+105994X0160Y         S0      
317GND              VIA   -    MD0080PA00X+131378Y+105676X0160Y         S0      
317GND              VIA   -    MD0080PA00X+131193Y+104719X0160Y         S0      
317GND              VIA   -    MD0080PA00X+130638Y+105676X0160Y         S0      
317GND              VIA   -    MD0080PA00X+130638Y+105038X0160Y         S0      
317GND              VIA   -    MD0080PA00X+131193Y+103443X0160Y         S0      
317GND              VIA   -    MD0080PA00X+131748Y+104400X0160Y         S0      
317GND              VIA   -    MD0080PA00X+131748Y+103124X0160Y         S0      
317GND              VIA   -    MD0080PA00X+131934Y+104081X0160Y         S0      
317GND              VIA   -    MD0080PA00X+131193Y+104081X0160Y         S0      
317GND              VIA   -    MD0080PA00X+131934Y+103443X0160Y         S0      
317GND              VIA   -    MD0080PA00X+130638Y+103124X0160Y         S0      
317GND              VIA   -    MD0080PA00X+130638Y+103762X0160Y         S0      
317GND              VIA   -    MD0080PA00X+130638Y+104400X0160Y         S0      
317GND              VIA   -    MD0080PA00X+131193Y+102806X0160Y         S0      
317GND              VIA   -    MD0080PA00X+131815Y+100399X0160Y    R180 S0      
317GND              VIA   -    MD0080PA00X+131630Y+100718X0160Y    R180 S0      
317GND              VIA   -    MD0080PA00X+131815Y+101037X0160Y    R180 S0      
317GND              VIA   -    MD0080PA00X+131075Y+101037X0160Y    R180 S0      
317GND              VIA   -    MD0080PA00X+131075Y+100399X0160Y    R180 S0      
317GND              VIA   -    MD0080PA00X+130520Y+100718X0160Y    R180 S0      
317GND              VIA   -    MD0080PA00X+131748Y+108227X0160Y         S0      
317GND              VIA   -    MD0080PA00X+131748Y+108865X0160Y         S0      
317GND              VIA   -    MD0080PA00X+131193Y+108546X0160Y         S0      
317GND              VIA   -    MD0080PA00X+131193Y+107908X0160Y         S0      
317GND              VIA   -    MD0080PA00X+131934Y+107908X0160Y         S0      
317GND              VIA   -    MD0080PA00X+130638Y+108227X0160Y         S0      
317GND              VIA   -    MD0080PA00X+130638Y+108865X0160Y         S0      
317GND              VIA   -    MD0080PA00X+130638Y+107589X0160Y         S0      
317GND              VIA   -    MD0080PA00X+131193Y+107270X0160Y         S0      
317GND              VIA   -    MD0080PA00X+131193Y+106632X0160Y         S0      
317GND              VIA   -    MD0080PA00X+131748Y+106951X0160Y         S0      
317GND              VIA   -    MD0080PA00X+131934Y+107270X0160Y         S0      
317GND              VIA   -    MD0080PA00X+131748Y+106313X0160Y         S0      
317GND              VIA   -    MD0080PA00X+130638Y+106951X0160Y         S0      
317GND              VIA   -    MD0080PA00X+130638Y+106313X0160Y         S0      
317GND              VIA   -    MD0080PA00X+131934Y+111735X0160Y         S0      
317GND              VIA   -    MD0080PA00X+131193Y+111735X0160Y         S0      
317GND              VIA   -    MD0080PA00X+131193Y+111097X0160Y         S0      
317GND              VIA   -    MD0080PA00X+131934Y+111097X0160Y         S0      
317GND              VIA   -    MD0080PA00X+131748Y+110778X0160Y         S0      
317GND              VIA   -    MD0080PA00X+130638Y+111416X0160Y         S0      
317GND              VIA   -    MD0080PA00X+130638Y+110778X0160Y         S0      
317GND              VIA   -    MD0080PA00X+131193Y+110459X0160Y         S0      
317GND              VIA   -    MD0080PA00X+131748Y+110140X0160Y         S0      
317GND              VIA   -    MD0080PA00X+131934Y+109821X0160Y         S0      
317GND              VIA   -    MD0080PA00X+131193Y+109821X0160Y         S0      
317GND              VIA   -    MD0080PA00X+131193Y+109184X0160Y         S0      
317GND              VIA   -    MD0080PA00X+131934Y+109184X0160Y         S0      
317GND              VIA   -    MD0080PA00X+130638Y+110140X0160Y         S0      
317GND              VIA   -    MD0080PA00X+130638Y+109502X0160Y         S0      
317GND              VIA   -    MD0080PA00X+131008Y+115880X0160Y         S0      
317GND              VIA   -    MD0080PA00X+131193Y+115561X0160Y         S0      
317GND              VIA   -    MD0080PA00X+131563Y+115561X0160Y         S0      
317GND              VIA   -    MD0080PA00X+131934Y+115561X0160Y         S0      
317GND              VIA   -    MD0080PA00X+130638Y+115880X0160Y         S0      
317GND              VIA   -    MD0080PA00X+130638Y+115242X0160Y         S0      
317GND              VIA   -    MD0080PA00X+131193Y+114924X0160Y         S0      
317GND              VIA   -    MD0080PA00X+131934Y+114924X0160Y         S0      
317GND              VIA   -    MD0080PA00X+131748Y+114605X0160Y         S0      
317GND              VIA   -    MD0080PA00X+131193Y+114286X0160Y         S0      
317GND              VIA   -    MD0080PA00X+131193Y+113648X0160Y         S0      
317GND              VIA   -    MD0080PA00X+131748Y+113967X0160Y         S0      
317GND              VIA   -    MD0080PA00X+131934Y+113648X0160Y         S0      
317GND              VIA   -    MD0080PA00X+130638Y+114605X0160Y         S0      
317GND              VIA   -    MD0080PA00X+130638Y+113967X0160Y         S0      
317GND              VIA   -    MD0080PA00X+131934Y+113010X0160Y         S0      
317GND              VIA   -    MD0080PA00X+131748Y+112691X0160Y         S0      
317GND              VIA   -    MD0080PA00X+131193Y+112372X0160Y         S0      
317GND              VIA   -    MD0080PA00X+131748Y+112054X0160Y         S0      
317GND              VIA   -    MD0080PA00X+130638Y+113329X0160Y         S0      
317GND              VIA   -    MD0080PA00X+130638Y+112691X0160Y         S0      
317GND              VIA   -    MD0080PA00X+130638Y+112054X0160Y         S0      
317GND              VIA   -    MD0080PA00X+131378Y+116518X0160Y         S0      
317GND              VIA   -    MD0080PA00X+130638Y+116518X0160Y         S0      
317GND              VIA   -    MD0080PA00X+131193Y+116199X0160Y         S0      
317GND              VIA   -    MD0080PA00X+131934Y+116199X0160Y         S0      
317GND              VIA   -    MD0080PA00X+131378Y+115880X0160Y         S0      
317GND              VIA   -    MD0080PA00X+131748Y+115880X0160Y         S0      
317GND              VIA   -    MD0080PA00X+133111Y+087962X0160Y    R180 S0      
317GND              VIA   -    MD0080PA00X+132556Y+087643X0160Y    R180 S0      
317GND              VIA   -    MD0080PA00X+133111Y+087324X0160Y    R180 S0      
317GND              VIA   -    MD0080PA00X+132000Y+087962X0160Y    R180 S0      
317GND              VIA   -    MD0080PA00X+133111Y+090513X0160Y    R180 S0      
317GND              VIA   -    MD0080PA00X+132370Y+090513X0160Y    R180 S0      
317GND              VIA   -    MD0080PA00X+132370Y+091151X0160Y    R180 S0      
317GND              VIA   -    MD0080PA00X+133111Y+091151X0160Y    R180 S0      
317GND              VIA   -    MD0080PA00X+132926Y+090195X0160Y    R180 S0      
317GND              VIA   -    MD0080PA00X+133111Y+089876X0160Y    R180 S0      
317GND              VIA   -    MD0080PA00X+132370Y+089876X0160Y    R180 S0      
317GND              VIA   -    MD0080PA00X+132926Y+089557X0160Y    R180 S0      
317GND              VIA   -    MD0080PA00X+133111Y+089238X0160Y    R180 S0      
317GND              VIA   -    MD0080PA00X+132926Y+088919X0160Y    R180 S0      
317GND              VIA   -    MD0080PA00X+132370Y+089238X0160Y    R180 S0      
317GND              VIA   -    MD0080PA00X+132741Y+088600X0160Y    R180 S0      
317GND              VIA   -    MD0080PA00X+133111Y+088600X0160Y    R180 S0      
317GND              VIA   -    MD0080PA00X+133296Y+088281X0160Y    R180 S0      
317GND              VIA   -    MD0080PA00X+132926Y+088281X0160Y    R180 S0      
317GND              VIA   -    MD0080PA00X+132370Y+088600X0160Y    R180 S0      
317GND              VIA   -    MD0080PA00X+132186Y+088281X0160Y    R180 S0      
317GND              VIA   -    MD0080PA00X+133111Y+092427X0160Y    R180 S0      
317GND              VIA   -    MD0080PA00X+132926Y+092108X0160Y    R180 S0      
317GND              VIA   -    MD0080PA00X+132370Y+092427X0160Y    R180 S0      
317GND              VIA   -    MD0080PA00X+133111Y+091789X0160Y    R180 S0      
317GND              VIA   -    MD0080PA00X+132370Y+091789X0160Y    R180 S0      
317GND              VIA   -    MD0080PA00X+132926Y+091470X0160Y    R180 S0      
317GND              VIA   -    MD0080PA00X+132370Y+095616X0160Y    R180 S0      
317GND              VIA   -    MD0080PA00X+133111Y+095616X0160Y    R180 S0      
317GND              VIA   -    MD0080PA00X+132926Y+095297X0160Y    R180 S0      
317GND              VIA   -    MD0080PA00X+132370Y+094978X0160Y    R180 S0      
317GND              VIA   -    MD0080PA00X+132370Y+094340X0160Y    R180 S0      
317GND              VIA   -    MD0080PA00X+133111Y+094978X0160Y    R180 S0      
317GND              VIA   -    MD0080PA00X+132926Y+094659X0160Y    R180 S0      
317GND              VIA   -    MD0080PA00X+133111Y+094340X0160Y    R180 S0      
317GND              VIA   -    MD0080PA00X+132370Y+093702X0160Y    R180 S0      
317GND              VIA   -    MD0080PA00X+132926Y+094021X0160Y    R180 S0      
317GND              VIA   -    MD0080PA00X+133111Y+093702X0160Y    R180 S0      
317GND              VIA   -    MD0080PA00X+132926Y+092746X0160Y    R180 S0      
317GND              VIA   -    MD0080PA00X+132370Y+093065X0160Y    R180 S0      
317GND              VIA   -    MD0080PA00X+132926Y+093384X0160Y    R180 S0      
317GND              VIA   -    MD0080PA00X+133111Y+093065X0160Y    R180 S0      
317GND              VIA   -    MD0080PA00X+133296Y+098486X0160Y    R180 S0      
317GND              VIA   -    MD0080PA00X+132926Y+098486X0160Y    R180 S0      
317GND              VIA   -    MD0080PA00X+133481Y+098167X0160Y    R180 S0      
317GND              VIA   -    MD0080PA00X+133111Y+098167X0160Y    R180 S0      
317GND              VIA   -    MD0080PA00X+132926Y+097848X0160Y    R180 S0      
317GND              VIA   -    MD0080PA00X+133111Y+097529X0160Y    R180 S0      
317GND              VIA   -    MD0080PA00X+132926Y+097210X0160Y    R180 S0      
317GND              VIA   -    MD0080PA00X+132370Y+098167X0160Y    R180 S0      
317GND              VIA   -    MD0080PA00X+132370Y+097529X0160Y    R180 S0      
317GND              VIA   -    MD0080PA00X+132186Y+098486X0160Y    R180 S0      
317GND              VIA   -    MD0080PA00X+132000Y+098167X0160Y    R180 S0      
317GND              VIA   -    MD0080PA00X+132370Y+096891X0160Y    R180 S0      
317GND              VIA   -    MD0080PA00X+133111Y+096891X0160Y    R180 S0      
317GND              VIA   -    MD0080PA00X+132370Y+096254X0160Y    R180 S0      
317GND              VIA   -    MD0080PA00X+132926Y+096572X0160Y    R180 S0      
317GND              VIA   -    MD0080PA00X+133111Y+096254X0160Y    R180 S0      
317GND              VIA   -    MD0080PA00X+132926Y+095935X0160Y    R180 S0      
317GND              VIA   -    MD0080PA00X+133044Y+102806X0160Y         S0      
317GND              VIA   -    MD0080PA00X+132926Y+101037X0160Y    R180 S0      
317GND              VIA   -    MD0080PA00X+133111Y+100718X0160Y    R180 S0      
317GND              VIA   -    MD0080PA00X+132926Y+100399X0160Y    R180 S0      
317GND              VIA   -    MD0080PA00X+132370Y+100718X0160Y    R180 S0      
317GND              VIA   -    MD0080PA00X+133111Y+100080X0160Y    R180 S0      
317GND              VIA   -    MD0080PA00X+133111Y+099443X0160Y    R180 S0      
317GND              VIA   -    MD0080PA00X+132926Y+099124X0160Y    R180 S0      
317GND              VIA   -    MD0080PA00X+133111Y+098805X0160Y    R180 S0      
317GND              VIA   -    MD0080PA00X+132926Y+099762X0160Y    R180 S0      
317GND              VIA   -    MD0080PA00X+132370Y+099443X0160Y    R180 S0      
317GND              VIA   -    MD0080PA00X+132370Y+098805X0160Y    R180 S0      
317GND              VIA   -    MD0080PA00X+132370Y+100080X0160Y    R180 S0      
317GND              VIA   -    MD0080PA00X+133044Y+105994X0160Y         S0      
317GND              VIA   -    MD0080PA00X+132674Y+105994X0160Y         S0      
317GND              VIA   -    MD0080PA00X+133229Y+105676X0160Y         S0      
317GND              VIA   -    MD0080PA00X+132859Y+105676X0160Y         S0      
317GND              VIA   -    MD0080PA00X+133044Y+105357X0160Y         S0      
317GND              VIA   -    MD0080PA00X+133229Y+105038X0160Y         S0      
317GND              VIA   -    MD0080PA00X+132489Y+105676X0160Y         S0      
317GND              VIA   -    MD0080PA00X+132489Y+105038X0160Y         S0      
317GND              VIA   -    MD0080PA00X+133044Y+104719X0160Y         S0      
317GND              VIA   -    MD0080PA00X+133044Y+104081X0160Y         S0      
317GND              VIA   -    MD0080PA00X+133229Y+103762X0160Y         S0      
317GND              VIA   -    MD0080PA00X+133044Y+103443X0160Y         S0      
317GND              VIA   -    MD0080PA00X+133229Y+104400X0160Y         S0      
317GND              VIA   -    MD0080PA00X+132489Y+103762X0160Y         S0      
317GND              VIA   -    MD0080PA00X+132489Y+104400X0160Y         S0      
317GND              VIA   -    MD0080PA00X+133229Y+103124X0160Y         S0      
317GND              VIA   -    MD0080PA00X+132489Y+103124X0160Y         S0      
317GND              VIA   -    MD0080PA00X+133229Y+108227X0160Y         S0      
317GND              VIA   -    MD0080PA00X+132489Y+108227X0160Y         S0      
317GND              VIA   -    MD0080PA00X+133229Y+108865X0160Y         S0      
317GND              VIA   -    MD0080PA00X+133044Y+108546X0160Y         S0      
317GND              VIA   -    MD0080PA00X+132489Y+108865X0160Y         S0      
317GND              VIA   -    MD0080PA00X+133044Y+107908X0160Y         S0      
317GND              VIA   -    MD0080PA00X+133229Y+107589X0160Y         S0      
317GND              VIA   -    MD0080PA00X+132489Y+107589X0160Y         S0      
317GND              VIA   -    MD0080PA00X+133044Y+107270X0160Y         S0      
317GND              VIA   -    MD0080PA00X+133229Y+106951X0160Y         S0      
317GND              VIA   -    MD0080PA00X+133044Y+106632X0160Y         S0      
317GND              VIA   -    MD0080PA00X+132489Y+106951X0160Y         S0      
317GND              VIA   -    MD0080PA00X+132489Y+106313X0160Y         S0      
317GND              VIA   -    MD0080PA00X+133229Y+106313X0160Y         S0      
317GND              VIA   -    MD0080PA00X+133044Y+111735X0160Y         S0      
317GND              VIA   -    MD0080PA00X+133229Y+111416X0160Y         S0      
317GND              VIA   -    MD0080PA00X+132489Y+111416X0160Y         S0      
317GND              VIA   -    MD0080PA00X+133044Y+111097X0160Y         S0      
317GND              VIA   -    MD0080PA00X+133229Y+110778X0160Y         S0      
317GND              VIA   -    MD0080PA00X+132489Y+110778X0160Y         S0      
317GND              VIA   -    MD0080PA00X+133044Y+110459X0160Y         S0      
317GND              VIA   -    MD0080PA00X+133229Y+110140X0160Y         S0      
317GND              VIA   -    MD0080PA00X+133044Y+109821X0160Y         S0      
317GND              VIA   -    MD0080PA00X+132489Y+110140X0160Y         S0      
317GND              VIA   -    MD0080PA00X+133229Y+109502X0160Y         S0      
317GND              VIA   -    MD0080PA00X+132489Y+109502X0160Y         S0      
317GND              VIA   -    MD0080PA00X+133044Y+109184X0160Y         S0      
317GND              VIA   -    MD0080PA00X+132489Y+116518X0160Y         S0      
317GND              VIA   -    MD0080PA00X+133044Y+116199X0160Y         S0      
317GND              VIA   -    MD0080PA00X+132489Y+115880X0160Y         S0      
317GND              VIA   -    MD0080PA00X+132859Y+115880X0160Y         S0      
317GND              VIA   -    MD0080PA00X+133229Y+115880X0160Y         S0      
317GND              VIA   -    MD0080PA00X+132489Y+115242X0160Y         S0      
317GND              VIA   -    MD0080PA00X+133044Y+115561X0160Y         S0      
317GND              VIA   -    MD0080PA00X+133229Y+115242X0160Y         S0      
317GND              VIA   -    MD0080PA00X+132304Y+116199X0160Y         S0      
317GND              VIA   -    MD0080PA00X+132304Y+115561X0160Y         S0      
317GND              VIA   -    MD0080PA00X+132489Y+114605X0160Y         S0      
317GND              VIA   -    MD0080PA00X+133044Y+114924X0160Y         S0      
317GND              VIA   -    MD0080PA00X+133229Y+114605X0160Y         S0      
317GND              VIA   -    MD0080PA00X+133044Y+114286X0160Y         S0      
317GND              VIA   -    MD0080PA00X+133229Y+113967X0160Y         S0      
317GND              VIA   -    MD0080PA00X+133044Y+113648X0160Y         S0      
317GND              VIA   -    MD0080PA00X+132489Y+113967X0160Y         S0      
317GND              VIA   -    MD0080PA00X+133229Y+113329X0160Y         S0      
317GND              VIA   -    MD0080PA00X+132489Y+113329X0160Y         S0      
317GND              VIA   -    MD0080PA00X+133229Y+112691X0160Y         S0      
317GND              VIA   -    MD0080PA00X+132489Y+112691X0160Y         S0      
317GND              VIA   -    MD0080PA00X+133044Y+112372X0160Y         S0      
317GND              VIA   -    MD0080PA00X+133229Y+112054X0160Y         S0      
317GND              VIA   -    MD0080PA00X+132489Y+112054X0160Y         S0      
317GND              VIA   -    MD0080PA00X+133229Y+116518X0160Y         S0      
317GND              VIA   -    MD0080PA00X+134961Y+087962X0160Y    R180 S0      
317GND              VIA   -    MD0080PA00X+134591Y+087962X0160Y    R180 S0      
317GND              VIA   -    MD0080PA00X+133666Y+087643X0160Y    R180 S0      
317GND              VIA   -    MD0080PA00X+134961Y+091151X0160Y    R180 S0      
317GND              VIA   -    MD0080PA00X+134221Y+091151X0160Y    R180 S0      
317GND              VIA   -    MD0080PA00X+134961Y+090513X0160Y    R180 S0      
317GND              VIA   -    MD0080PA00X+134406Y+090195X0160Y    R180 S0      
317GND              VIA   -    MD0080PA00X+134961Y+089876X0160Y    R180 S0      
317GND              VIA   -    MD0080PA00X+134221Y+089876X0160Y    R180 S0      
317GND              VIA   -    MD0080PA00X+133666Y+090832X0160Y    R180 S0      
317GND              VIA   -    MD0080PA00X+133666Y+090195X0160Y    R180 S0      
317GND              VIA   -    MD0080PA00X+134961Y+089238X0160Y    R180 S0      
317GND              VIA   -    MD0080PA00X+134221Y+089238X0160Y    R180 S0      
317GND              VIA   -    MD0080PA00X+134406Y+088919X0160Y    R180 S0      
317GND              VIA   -    MD0080PA00X+134406Y+088281X0160Y    R180 S0      
317GND              VIA   -    MD0080PA00X+134961Y+088600X0160Y    R180 S0      
317GND              VIA   -    MD0080PA00X+134221Y+088600X0160Y    R180 S0      
317GND              VIA   -    MD0080PA00X+133666Y+089557X0160Y    R180 S0      
317GND              VIA   -    MD0080PA00X+133666Y+088919X0160Y    R180 S0      
317GND              VIA   -    MD0080PA00X+133666Y+088281X0160Y    R180 S0      
317GND              VIA   -    MD0080PA00X+133851Y+088600X0160Y    R180 S0      
317GND              VIA   -    MD0080PA00X+134961Y+092427X0160Y    R180 S0      
317GND              VIA   -    MD0080PA00X+134406Y+092108X0160Y    R180 S0      
317GND              VIA   -    MD0080PA00X+134961Y+091789X0160Y    R180 S0      
317GND              VIA   -    MD0080PA00X+134221Y+091789X0160Y    R180 S0      
317GND              VIA   -    MD0080PA00X+133666Y+092108X0160Y    R180 S0      
317GND              VIA   -    MD0080PA00X+133666Y+091470X0160Y    R180 S0      
317GND              VIA   -    MD0080PA00X+133666Y+095297X0160Y    R180 S0      
317GND              VIA   -    MD0080PA00X+133666Y+094659X0160Y    R180 S0      
317GND              VIA   -    MD0080PA00X+134961Y+093702X0160Y    R180 S0      
317GND              VIA   -    MD0080PA00X+134221Y+093702X0160Y    R180 S0      
317GND              VIA   -    MD0080PA00X+134406Y+094021X0160Y    R180 S0      
317GND              VIA   -    MD0080PA00X+134961Y+093065X0160Y    R180 S0      
317GND              VIA   -    MD0080PA00X+134221Y+093065X0160Y    R180 S0      
317GND              VIA   -    MD0080PA00X+134406Y+092746X0160Y    R180 S0      
317GND              VIA   -    MD0080PA00X+133666Y+094021X0160Y    R180 S0      
317GND              VIA   -    MD0080PA00X+133666Y+092746X0160Y    R180 S0      
317GND              VIA   -    MD0080PA00X+133666Y+093384X0160Y    R180 S0      
317GND              VIA   -    MD0080PA00X+134221Y+096891X0160Y    R180 S0      
317GND              VIA   -    MD0080PA00X+134961Y+096891X0160Y    R180 S0      
317GND              VIA   -    MD0080PA00X+134406Y+096572X0160Y    R180 S0      
317GND              VIA   -    MD0080PA00X+134961Y+096254X0160Y    R180 S0      
317GND              VIA   -    MD0080PA00X+134406Y+095935X0160Y    R180 S0      
317GND              VIA   -    MD0080PA00X+133666Y+095935X0160Y    R180 S0      
317GND              VIA   -    MD0080PA00X+133666Y+096572X0160Y    R180 S0      
317GND              VIA   -    MD0080PA00X+134221Y+095616X0160Y    R180 S0      
317GND              VIA   -    MD0080PA00X+134961Y+095616X0160Y    R180 S0      
317GND              VIA   -    MD0080PA00X+134221Y+094978X0160Y    R180 S0      
317GND              VIA   -    MD0080PA00X+134961Y+094978X0160Y    R180 S0      
317GND              VIA   -    MD0080PA00X+134406Y+094659X0160Y    R180 S0      
317GND              VIA   -    MD0080PA00X+134961Y+094340X0160Y    R180 S0      
317GND              VIA   -    MD0080PA00X+134961Y+100080X0160Y    R180 S0      
317GND              VIA   -    MD0080PA00X+134221Y+098805X0160Y    R180 S0      
317GND              VIA   -    MD0080PA00X+134406Y+099762X0160Y    R180 S0      
317GND              VIA   -    MD0080PA00X+134221Y+099443X0160Y    R180 S0      
317GND              VIA   -    MD0080PA00X+134961Y+099443X0160Y    R180 S0      
317GND              VIA   -    MD0080PA00X+134961Y+098805X0160Y    R180 S0      
317GND              VIA   -    MD0080PA00X+133666Y+099124X0160Y    R180 S0      
317GND              VIA   -    MD0080PA00X+133666Y+099762X0160Y    R180 S0      
317GND              VIA   -    MD0080PA00X+134776Y+098486X0160Y    R180 S0      
317GND              VIA   -    MD0080PA00X+134406Y+098486X0160Y    R180 S0      
317GND              VIA   -    MD0080PA00X+134591Y+098167X0160Y    R180 S0      
317GND              VIA   -    MD0080PA00X+134961Y+098167X0160Y    R180 S0      
317GND              VIA   -    MD0080PA00X+134406Y+097848X0160Y    R180 S0      
317GND              VIA   -    MD0080PA00X+134221Y+097529X0160Y    R180 S0      
317GND              VIA   -    MD0080PA00X+134961Y+097529X0160Y    R180 S0      
317GND              VIA   -    MD0080PA00X+133666Y+098486X0160Y    R180 S0      
317GND              VIA   -    MD0080PA00X+133666Y+097848X0160Y    R180 S0      
317GND              VIA   -    MD0080PA00X+133666Y+097210X0160Y    R180 S0      
317GND              VIA   -    MD0080PA00X+133784Y+102806X0160Y         S0      
317GND              VIA   -    MD0080PA00X+134961Y+100718X0160Y    R180 S0      
317GND              VIA   -    MD0080PA00X+134221Y+100718X0160Y    R180 S0      
317GND              VIA   -    MD0080PA00X+134406Y+100399X0160Y    R180 S0      
317GND              VIA   -    MD0080PA00X+133666Y+100399X0160Y    R180 S0      
317GND              VIA   -    MD0080PA00X+134406Y+101037X0160Y    R180 S0      
317GND              VIA   -    MD0080PA00X+133666Y+101037X0160Y    R180 S0      
317GND              VIA   -    MD0080PA00X+134524Y+105994X0160Y         S0      
317GND              VIA   -    MD0080PA00X+134154Y+105994X0160Y         S0      
317GND              VIA   -    MD0080PA00X+134524Y+105357X0160Y         S0      
317GND              VIA   -    MD0080PA00X+134339Y+105038X0160Y         S0      
317GND              VIA   -    MD0080PA00X+133969Y+105676X0160Y         S0      
317GND              VIA   -    MD0080PA00X+133784Y+105994X0160Y         S0      
317GND              VIA   -    MD0080PA00X+133784Y+105357X0160Y         S0      
317GND              VIA   -    MD0080PA00X+133784Y+104719X0160Y         S0      
317GND              VIA   -    MD0080PA00X+134524Y+103443X0160Y         S0      
317GND              VIA   -    MD0080PA00X+134524Y+104081X0160Y         S0      
317GND              VIA   -    MD0080PA00X+134339Y+104400X0160Y         S0      
317GND              VIA   -    MD0080PA00X+134339Y+103124X0160Y         S0      
317GND              VIA   -    MD0080PA00X+133784Y+103443X0160Y         S0      
317GND              VIA   -    MD0080PA00X+133784Y+104081X0160Y         S0      
317GND              VIA   -    MD0080PA00X+134524Y+107270X0160Y         S0      
317GND              VIA   -    MD0080PA00X+134339Y+106951X0160Y         S0      
317GND              VIA   -    MD0080PA00X+134339Y+106313X0160Y         S0      
317GND              VIA   -    MD0080PA00X+133784Y+106632X0160Y         S0      
317GND              VIA   -    MD0080PA00X+133784Y+107270X0160Y         S0      
317GND              VIA   -    MD0080PA00X+134339Y+108227X0160Y         S0      
317GND              VIA   -    MD0080PA00X+134339Y+108865X0160Y         S0      
317GND              VIA   -    MD0080PA00X+134524Y+107908X0160Y         S0      
317GND              VIA   -    MD0080PA00X+133784Y+108546X0160Y         S0      
317GND              VIA   -    MD0080PA00X+133784Y+107908X0160Y         S0      
317GND              VIA   -    MD0080PA00X+134524Y+111735X0160Y         S0      
317GND              VIA   -    MD0080PA00X+134524Y+111097X0160Y         S0      
317GND              VIA   -    MD0080PA00X+134339Y+110778X0160Y         S0      
317GND              VIA   -    MD0080PA00X+133784Y+111735X0160Y         S0      
317GND              VIA   -    MD0080PA00X+133784Y+111097X0160Y         S0      
317GND              VIA   -    MD0080PA00X+134524Y+109821X0160Y         S0      
317GND              VIA   -    MD0080PA00X+134339Y+110140X0160Y         S0      
317GND              VIA   -    MD0080PA00X+134524Y+109184X0160Y         S0      
317GND              VIA   -    MD0080PA00X+133784Y+110459X0160Y         S0      
317GND              VIA   -    MD0080PA00X+133784Y+109821X0160Y         S0      
317GND              VIA   -    MD0080PA00X+133784Y+109184X0160Y         S0      
317GND              VIA   -    MD0080PA00X+134524Y+113010X0160Y         S0      
317GND              VIA   -    MD0080PA00X+134339Y+112691X0160Y         S0      
317GND              VIA   -    MD0080PA00X+134339Y+112054X0160Y         S0      
317GND              VIA   -    MD0080PA00X+133784Y+113010X0160Y         S0      
317GND              VIA   -    MD0080PA00X+133784Y+112372X0160Y         S0      
317GND              VIA   -    MD0080PA00X+133969Y+116518X0160Y         S0      
317GND              VIA   -    MD0080PA00X+134524Y+115561X0160Y         S0      
317GND              VIA   -    MD0080PA00X+134894Y+115561X0160Y         S0      
317GND              VIA   -    MD0080PA00X+133969Y+115880X0160Y         S0      
317GND              VIA   -    MD0080PA00X+134154Y+115561X0160Y         S0      
317GND              VIA   -    MD0080PA00X+133784Y+116199X0160Y         S0      
317GND              VIA   -    MD0080PA00X+133599Y+115880X0160Y         S0      
317GND              VIA   -    MD0080PA00X+133784Y+115561X0160Y         S0      
317GND              VIA   -    MD0080PA00X+134339Y+114605X0160Y         S0      
317GND              VIA   -    MD0080PA00X+134524Y+114924X0160Y         S0      
317GND              VIA   -    MD0080PA00X+134524Y+113648X0160Y         S0      
317GND              VIA   -    MD0080PA00X+134339Y+113967X0160Y         S0      
317GND              VIA   -    MD0080PA00X+133784Y+114924X0160Y         S0      
317GND              VIA   -    MD0080PA00X+133784Y+114286X0160Y         S0      
317GND              VIA   -    MD0080PA00X+133784Y+113648X0160Y         S0      
317GND              VIA   -    MD0080PA00X+135886Y+088919X0160Y    R180 S0      
317GND              VIA   -    MD0080PA00X+136256Y+088919X0160Y    R180 S0      
317GND              VIA   -    MD0080PA00X+135516Y+089557X0160Y    R180 S0      
317GND              VIA   -    MD0080PA00X+135701Y+089238X0160Y    R180 S0      
317GND              VIA   -    MD0080PA00X+135516Y+088281X0160Y    R180 S0      
317GND              VIA   -    MD0080PA00X+136071Y+088600X0160Y    R180 S0      
317GND              VIA   -    MD0080PA00X+136441Y+088600X0160Y    R180 S0      
317GND              VIA   -    MD0080PA00X+135886Y+088281X0160Y    R180 S0      
317GND              VIA   -    MD0080PA00X+136256Y+088281X0160Y    R180 S0      
317GND              VIA   -    MD0080PA00X+135331Y+088600X0160Y    R180 S0      
317GND              VIA   -    MD0080PA00X+136256Y+087643X0160Y    R180 S0      
317GND              VIA   -    MD0080PA00X+136071Y+087324X0160Y    R180 S0      
317GND              VIA   -    MD0080PA00X+136441Y+087962X0160Y    R180 S0      
317GND              VIA   -    MD0080PA00X+135331Y+087962X0160Y    R180 S0      
317GND              VIA   -    MD0080PA00X+135146Y+087643X0160Y    R180 S0      
317GND              VIA   -    MD0080PA00X+135516Y+090832X0160Y    R180 S0      
317GND              VIA   -    MD0080PA00X+135701Y+091151X0160Y    R180 S0      
317GND              VIA   -    MD0080PA00X+135701Y+090513X0160Y    R180 S0      
317GND              VIA   -    MD0080PA00X+135886Y+090195X0160Y    R180 S0      
317GND              VIA   -    MD0080PA00X+136256Y+090195X0160Y    R180 S0      
317GND              VIA   -    MD0080PA00X+135701Y+089876X0160Y    R180 S0      
317GND              VIA   -    MD0080PA00X+135516Y+094021X0160Y    R180 S0      
317GND              VIA   -    MD0080PA00X+135701Y+093065X0160Y    R180 S0      
317GND              VIA   -    MD0080PA00X+135886Y+092746X0160Y    R180 S0      
317GND              VIA   -    MD0080PA00X+136256Y+092746X0160Y    R180 S0      
317GND              VIA   -    MD0080PA00X+135516Y+093384X0160Y    R180 S0      
317GND              VIA   -    MD0080PA00X+135886Y+093384X0160Y    R180 S0      
317GND              VIA   -    MD0080PA00X+136256Y+093384X0160Y    R180 S0      
317GND              VIA   -    MD0080PA00X+135701Y+092427X0160Y    R180 S0      
317GND              VIA   -    MD0080PA00X+135516Y+092108X0160Y    R180 S0      
317GND              VIA   -    MD0080PA00X+135701Y+091789X0160Y    R180 S0      
317GND              VIA   -    MD0080PA00X+136256Y+091470X0160Y    R180 S0      
317GND              VIA   -    MD0080PA00X+135886Y+091470X0160Y    R180 S0      
317GND              VIA   -    MD0080PA00X+135701Y+096891X0160Y    R180 S0      
317GND              VIA   -    MD0080PA00X+135516Y+096572X0160Y    R180 S0      
317GND              VIA   -    MD0080PA00X+135701Y+096254X0160Y    R180 S0      
317GND              VIA   -    MD0080PA00X+136256Y+095935X0160Y    R180 S0      
317GND              VIA   -    MD0080PA00X+135886Y+095935X0160Y    R180 S0      
317GND              VIA   -    MD0080PA00X+135516Y+095297X0160Y    R180 S0      
317GND              VIA   -    MD0080PA00X+135701Y+095616X0160Y    R180 S0      
317GND              VIA   -    MD0080PA00X+135701Y+094978X0160Y    R180 S0      
317GND              VIA   -    MD0080PA00X+136256Y+094659X0160Y    R180 S0      
317GND              VIA   -    MD0080PA00X+135886Y+094659X0160Y    R180 S0      
317GND              VIA   -    MD0080PA00X+135701Y+094340X0160Y    R180 S0      
317GND              VIA   -    MD0080PA00X+136071Y+100080X0160Y    R180 S0      
317GND              VIA   -    MD0080PA00X+136071Y+098805X0160Y    R180 S0      
317GND              VIA   -    MD0080PA00X+136071Y+099443X0160Y    R180 S0      
317GND              VIA   -    MD0080PA00X+136256Y+099762X0160Y    R180 S0      
317GND              VIA   -    MD0080PA00X+136256Y+099124X0160Y    R180 S0      
317GND              VIA   -    MD0080PA00X+135516Y+099762X0160Y    R180 S0      
317GND              VIA   -    MD0080PA00X+135516Y+099124X0160Y    R180 S0      
317GND              VIA   -    MD0080PA00X+135516Y+098486X0160Y    R180 S0      
317GND              VIA   -    MD0080PA00X+136256Y+098486X0160Y    R180 S0      
317GND              VIA   -    MD0080PA00X+135516Y+097848X0160Y    R180 S0      
317GND              VIA   -    MD0080PA00X+136071Y+098167X0160Y    R180 S0      
317GND              VIA   -    MD0080PA00X+135701Y+097529X0160Y    R180 S0      
317GND              VIA   -    MD0080PA00X+136256Y+097210X0160Y    R180 S0      
317GND              VIA   -    MD0080PA00X+135886Y+097210X0160Y    R180 S0      
317GND              VIA   -    MD0080PA00X+136374Y+105357X0160Y         S0      
317GND              VIA   -    MD0080PA00X+135634Y+105994X0160Y         S0      
317GND              VIA   -    MD0080PA00X+136189Y+105038X0160Y         S0      
317GND              VIA   -    MD0080PA00X+135634Y+105357X0160Y         S0      
317GND              VIA   -    MD0080PA00X+136374Y+104719X0160Y         S0      
317GND              VIA   -    MD0080PA00X+135634Y+104719X0160Y         S0      
317GND              VIA   -    MD0080PA00X+135264Y+105994X0160Y         S0      
317GND              VIA   -    MD0080PA00X+135079Y+105038X0160Y         S0      
317GND              VIA   -    MD0080PA00X+135079Y+105676X0160Y         S0      
317GND              VIA   -    MD0080PA00X+135449Y+105676X0160Y         S0      
317GND              VIA   -    MD0080PA00X+136189Y+103124X0160Y         S0      
317GND              VIA   -    MD0080PA00X+136189Y+103762X0160Y         S0      
317GND              VIA   -    MD0080PA00X+136189Y+104400X0160Y         S0      
317GND              VIA   -    MD0080PA00X+136374Y+104081X0160Y         S0      
317GND              VIA   -    MD0080PA00X+136374Y+103443X0160Y         S0      
317GND              VIA   -    MD0080PA00X+135634Y+104081X0160Y         S0      
317GND              VIA   -    MD0080PA00X+135634Y+103443X0160Y         S0      
317GND              VIA   -    MD0080PA00X+135079Y+103762X0160Y         S0      
317GND              VIA   -    MD0080PA00X+135079Y+104400X0160Y         S0      
317GND              VIA   -    MD0080PA00X+135079Y+103124X0160Y         S0      
317GND              VIA   -    MD0080PA00X+136374Y+102806X0160Y         S0      
317GND              VIA   -    MD0080PA00X+135634Y+102806X0160Y         S0      
317GND              VIA   -    MD0080PA00X+135516Y+100399X0160Y    R180 S0      
317GND              VIA   -    MD0080PA00X+136256Y+100399X0160Y    R180 S0      
317GND              VIA   -    MD0080PA00X+136071Y+100718X0160Y    R180 S0      
317GND              VIA   -    MD0080PA00X+135886Y+101037X0160Y    R180 S0      
317GND              VIA   -    MD0080PA00X+136004Y+106632X0160Y         S0      
317GND              VIA   -    MD0080PA00X+135819Y+106951X0160Y         S0      
317GND              VIA   -    MD0080PA00X+136374Y+106632X0160Y         S0      
317GND              VIA   -    MD0080PA00X+135634Y+107270X0160Y         S0      
317GND              VIA   -    MD0080PA00X+135819Y+106313X0160Y         S0      
317GND              VIA   -    MD0080PA00X+135079Y+106951X0160Y         S0      
317GND              VIA   -    MD0080PA00X+135079Y+106313X0160Y         S0      
317GND              VIA   -    MD0080PA00X+135819Y+108227X0160Y         S0      
317GND              VIA   -    MD0080PA00X+135819Y+108865X0160Y         S0      
317GND              VIA   -    MD0080PA00X+135634Y+108546X0160Y         S0      
317GND              VIA   -    MD0080PA00X+136004Y+107908X0160Y         S0      
317GND              VIA   -    MD0080PA00X+136374Y+107908X0160Y         S0      
317GND              VIA   -    MD0080PA00X+135819Y+107589X0160Y         S0      
317GND              VIA   -    MD0080PA00X+135079Y+108865X0160Y         S0      
317GND              VIA   -    MD0080PA00X+135079Y+108227X0160Y         S0      
317GND              VIA   -    MD0080PA00X+135079Y+107589X0160Y         S0      
317GND              VIA   -    MD0080PA00X+136004Y+110459X0160Y         S0      
317GND              VIA   -    MD0080PA00X+136374Y+110459X0160Y         S0      
317GND              VIA   -    MD0080PA00X+135634Y+109821X0160Y         S0      
317GND              VIA   -    MD0080PA00X+135819Y+109502X0160Y         S0      
317GND              VIA   -    MD0080PA00X+136004Y+109184X0160Y         S0      
317GND              VIA   -    MD0080PA00X+136374Y+109184X0160Y         S0      
317GND              VIA   -    MD0080PA00X+135634Y+110459X0160Y         S0      
317GND              VIA   -    MD0080PA00X+135079Y+110140X0160Y         S0      
317GND              VIA   -    MD0080PA00X+135079Y+109502X0160Y         S0      
317GND              VIA   -    MD0080PA00X+135819Y+111416X0160Y         S0      
317GND              VIA   -    MD0080PA00X+135634Y+111735X0160Y         S0      
317GND              VIA   -    MD0080PA00X+136374Y+111097X0160Y         S0      
317GND              VIA   -    MD0080PA00X+136004Y+111097X0160Y         S0      
317GND              VIA   -    MD0080PA00X+135819Y+110778X0160Y         S0      
317GND              VIA   -    MD0080PA00X+135079Y+111416X0160Y         S0      
317GND              VIA   -    MD0080PA00X+135079Y+110778X0160Y         S0      
317GND              VIA   -    MD0080PA00X+135819Y+114605X0160Y         S0      
317GND              VIA   -    MD0080PA00X+136004Y+114924X0160Y         S0      
317GND              VIA   -    MD0080PA00X+136374Y+114924X0160Y         S0      
317GND              VIA   -    MD0080PA00X+135634Y+114286X0160Y         S0      
317GND              VIA   -    MD0080PA00X+136004Y+113648X0160Y         S0      
317GND              VIA   -    MD0080PA00X+136374Y+113648X0160Y         S0      
317GND              VIA   -    MD0080PA00X+135819Y+113967X0160Y         S0      
317GND              VIA   -    MD0080PA00X+135079Y+114605X0160Y         S0      
317GND              VIA   -    MD0080PA00X+135079Y+113967X0160Y         S0      
317GND              VIA   -    MD0080PA00X+135819Y+113329X0160Y         S0      
317GND              VIA   -    MD0080PA00X+135634Y+113010X0160Y         S0      
317GND              VIA   -    MD0080PA00X+135819Y+112054X0160Y         S0      
317GND              VIA   -    MD0080PA00X+136004Y+112372X0160Y         S0      
317GND              VIA   -    MD0080PA00X+136374Y+112372X0160Y         S0      
317GND              VIA   -    MD0080PA00X+135819Y+112691X0160Y         S0      
317GND              VIA   -    MD0080PA00X+135079Y+113329X0160Y         S0      
317GND              VIA   -    MD0080PA00X+135079Y+112691X0160Y         S0      
317GND              VIA   -    MD0080PA00X+135079Y+112054X0160Y         S0      
317GND              VIA   -    MD0080PA00X+136374Y+116199X0160Y         S0      
317GND              VIA   -    MD0080PA00X+136004Y+115561X0160Y         S0      
317GND              VIA   -    MD0080PA00X+136374Y+115561X0160Y         S0      
317GND              VIA   -    MD0080PA00X+135634Y+115561X0160Y         S0      
317GND              VIA   -    MD0080PA00X+135264Y+116199X0160Y         S0      
317GND              VIA   -    MD0080PA00X+135079Y+115880X0160Y         S0      
317GND              VIA   -    MD0080PA00X+135079Y+115242X0160Y         S0      
317GND              VIA   -    MD0080PA00X+135449Y+115880X0160Y         S0      
317GND              VIA   -    MD0080PA00X+137922Y+091151X0160Y    R180 S0      
317GND              VIA   -    MD0080PA00X+137737Y+090832X0160Y    R180 S0      
317GND              VIA   -    MD0080PA00X+137922Y+090513X0160Y    R180 S0      
317GND              VIA   -    MD0080PA00X+137367Y+090195X0160Y    R180 S0      
317GND              VIA   -    MD0080PA00X+137737Y+090195X0160Y    R180 S0      
317GND              VIA   -    MD0080PA00X+137922Y+089876X0160Y    R180 S0      
317GND              VIA   -    MD0080PA00X+136626Y+090832X0160Y    R180 S0      
317GND              VIA   -    MD0080PA00X+136812Y+091151X0160Y    R180 S0      
317GND              VIA   -    MD0080PA00X+136812Y+090513X0160Y    R180 S0      
317GND              VIA   -    MD0080PA00X+136626Y+090195X0160Y    R180 S0      
317GND              VIA   -    MD0080PA00X+136996Y+090195X0160Y    R180 S0      
317GND              VIA   -    MD0080PA00X+136812Y+089876X0160Y    R180 S0      
317GND              VIA   -    MD0080PA00X+137367Y+088919X0160Y    R180 S0      
317GND              VIA   -    MD0080PA00X+137737Y+089557X0160Y    R180 S0      
317GND              VIA   -    MD0080PA00X+137922Y+089238X0160Y    R180 S0      
317GND              VIA   -    MD0080PA00X+137737Y+088281X0160Y    R180 S0      
317GND              VIA   -    MD0080PA00X+137367Y+088281X0160Y    R180 S0      
317GND              VIA   -    MD0080PA00X+136626Y+089557X0160Y    R180 S0      
317GND              VIA   -    MD0080PA00X+136812Y+089238X0160Y    R180 S0      
317GND              VIA   -    MD0080PA00X+136996Y+088919X0160Y    R180 S0      
317GND              VIA   -    MD0080PA00X+136626Y+088281X0160Y    R180 S0      
317GND              VIA   -    MD0080PA00X+136996Y+088281X0160Y    R180 S0      
317GND              VIA   -    MD0080PA00X+137552Y+087962X0160Y    R180 S0      
317GND              VIA   -    MD0080PA00X+137552Y+087324X0160Y    R180 S0      
317GND              VIA   -    MD0080PA00X+137367Y+087643X0160Y    R180 S0      
317GND              VIA   -    MD0080PA00X+137922Y+096891X0160Y    R180 S0      
317GND              VIA   -    MD0080PA00X+137922Y+096254X0160Y    R180 S0      
317GND              VIA   -    MD0080PA00X+137737Y+095935X0160Y    R180 S0      
317GND              VIA   -    MD0080PA00X+137737Y+096572X0160Y    R180 S0      
317GND              VIA   -    MD0080PA00X+137367Y+095935X0160Y    R180 S0      
317GND              VIA   -    MD0080PA00X+136812Y+096891X0160Y    R180 S0      
317GND              VIA   -    MD0080PA00X+136626Y+096572X0160Y    R180 S0      
317GND              VIA   -    MD0080PA00X+136812Y+096254X0160Y    R180 S0      
317GND              VIA   -    MD0080PA00X+136996Y+095935X0160Y    R180 S0      
317GND              VIA   -    MD0080PA00X+136626Y+095935X0160Y    R180 S0      
317GND              VIA   -    MD0080PA00X+137922Y+095616X0160Y    R180 S0      
317GND              VIA   -    MD0080PA00X+137737Y+095297X0160Y    R180 S0      
317GND              VIA   -    MD0080PA00X+137922Y+094978X0160Y    R180 S0      
317GND              VIA   -    MD0080PA00X+137737Y+094659X0160Y    R180 S0      
317GND              VIA   -    MD0080PA00X+137367Y+094659X0160Y    R180 S0      
317GND              VIA   -    MD0080PA00X+137922Y+094340X0160Y    R180 S0      
317GND              VIA   -    MD0080PA00X+136626Y+095297X0160Y    R180 S0      
317GND              VIA   -    MD0080PA00X+136812Y+095616X0160Y    R180 S0      
317GND              VIA   -    MD0080PA00X+136626Y+094659X0160Y    R180 S0      
317GND              VIA   -    MD0080PA00X+136812Y+094978X0160Y    R180 S0      
317GND              VIA   -    MD0080PA00X+136996Y+094659X0160Y    R180 S0      
317GND              VIA   -    MD0080PA00X+136812Y+094340X0160Y    R180 S0      
317GND              VIA   -    MD0080PA00X+137737Y+094021X0160Y    R180 S0      
317GND              VIA   -    MD0080PA00X+137367Y+093384X0160Y    R180 S0      
317GND              VIA   -    MD0080PA00X+137737Y+093384X0160Y    R180 S0      
317GND              VIA   -    MD0080PA00X+137922Y+093065X0160Y    R180 S0      
317GND              VIA   -    MD0080PA00X+137367Y+092746X0160Y    R180 S0      
317GND              VIA   -    MD0080PA00X+137737Y+092746X0160Y    R180 S0      
317GND              VIA   -    MD0080PA00X+136626Y+094021X0160Y    R180 S0      
317GND              VIA   -    MD0080PA00X+136626Y+092746X0160Y    R180 S0      
317GND              VIA   -    MD0080PA00X+136996Y+093384X0160Y    R180 S0      
317GND              VIA   -    MD0080PA00X+136812Y+093065X0160Y    R180 S0      
317GND              VIA   -    MD0080PA00X+136996Y+092746X0160Y    R180 S0      
317GND              VIA   -    MD0080PA00X+136626Y+093384X0160Y    R180 S0      
317GND              VIA   -    MD0080PA00X+137922Y+092427X0160Y    R180 S0      
317GND              VIA   -    MD0080PA00X+137737Y+092108X0160Y    R180 S0      
317GND              VIA   -    MD0080PA00X+137922Y+091789X0160Y    R180 S0      
317GND              VIA   -    MD0080PA00X+137367Y+091470X0160Y    R180 S0      
317GND              VIA   -    MD0080PA00X+137737Y+091470X0160Y    R180 S0      
317GND              VIA   -    MD0080PA00X+136626Y+092108X0160Y    R180 S0      
317GND              VIA   -    MD0080PA00X+136812Y+092427X0160Y    R180 S0      
317GND              VIA   -    MD0080PA00X+136626Y+091470X0160Y    R180 S0      
317GND              VIA   -    MD0080PA00X+136812Y+091789X0160Y    R180 S0      
317GND              VIA   -    MD0080PA00X+136996Y+091470X0160Y    R180 S0      
317GND              VIA   -    MD0080PA00X+137855Y+105994X0160Y         S0      
317GND              VIA   -    MD0080PA00X+137115Y+105357X0160Y         S0      
317GND              VIA   -    MD0080PA00X+137670Y+105676X0160Y         S0      
317GND              VIA   -    MD0080PA00X+137855Y+104719X0160Y         S0      
317GND              VIA   -    MD0080PA00X+137115Y+104719X0160Y         S0      
317GND              VIA   -    MD0080PA00X+136930Y+105038X0160Y         S0      
317GND              VIA   -    MD0080PA00X+136930Y+105676X0160Y         S0      
317GND              VIA   -    MD0080PA00X+136744Y+105994X0160Y         S0      
317GND              VIA   -    MD0080PA00X+137670Y+104400X0160Y         S0      
317GND              VIA   -    MD0080PA00X+137670Y+103124X0160Y         S0      
317GND              VIA   -    MD0080PA00X+137485Y+103443X0160Y         S0      
317GND              VIA   -    MD0080PA00X+137115Y+104081X0160Y         S0      
317GND              VIA   -    MD0080PA00X+137855Y+104081X0160Y         S0      
317GND              VIA   -    MD0080PA00X+137670Y+103762X0160Y         S0      
317GND              VIA   -    MD0080PA00X+137115Y+103443X0160Y         S0      
317GND              VIA   -    MD0080PA00X+136930Y+103124X0160Y         S0      
317GND              VIA   -    MD0080PA00X+136930Y+103762X0160Y         S0      
317GND              VIA   -    MD0080PA00X+136930Y+104400X0160Y         S0      
317GND              VIA   -    MD0080PA00X+137485Y+102806X0160Y         S0      
317GND              VIA   -    MD0080PA00X+137115Y+102806X0160Y         S0      
317GND              VIA   -    MD0080PA00X+137737Y+100399X0160Y    R180 S0      
317GND              VIA   -    MD0080PA00X+137182Y+100718X0160Y    R180 S0      
317GND              VIA   -    MD0080PA00X+137552Y+100718X0160Y    R180 S0      
317GND              VIA   -    MD0080PA00X+137367Y+101037X0160Y    R180 S0      
317GND              VIA   -    MD0080PA00X+136626Y+101037X0160Y    R180 S0      
317GND              VIA   -    MD0080PA00X+136812Y+100718X0160Y    R180 S0      
317GND              VIA   -    MD0080PA00X+136996Y+100399X0160Y    R180 S0      
317GND              VIA   -    MD0080PA00X+137552Y+100080X0160Y    R180 S0      
317GND              VIA   -    MD0080PA00X+137552Y+098805X0160Y    R180 S0      
317GND              VIA   -    MD0080PA00X+137737Y+099762X0160Y    R180 S0      
317GND              VIA   -    MD0080PA00X+137737Y+099124X0160Y    R180 S0      
317GND              VIA   -    MD0080PA00X+137552Y+099443X0160Y    R180 S0      
317GND              VIA   -    MD0080PA00X+136812Y+100080X0160Y    R180 S0      
317GND              VIA   -    MD0080PA00X+136812Y+098805X0160Y    R180 S0      
317GND              VIA   -    MD0080PA00X+136812Y+099443X0160Y    R180 S0      
317GND              VIA   -    MD0080PA00X+136996Y+099762X0160Y    R180 S0      
317GND              VIA   -    MD0080PA00X+136996Y+099124X0160Y    R180 S0      
317GND              VIA   -    MD0080PA00X+137737Y+098486X0160Y    R180 S0      
317GND              VIA   -    MD0080PA00X+137737Y+097848X0160Y    R180 S0      
317GND              VIA   -    MD0080PA00X+137552Y+098167X0160Y    R180 S0      
317GND              VIA   -    MD0080PA00X+137922Y+097529X0160Y    R180 S0      
317GND              VIA   -    MD0080PA00X+137737Y+097210X0160Y    R180 S0      
317GND              VIA   -    MD0080PA00X+137367Y+097210X0160Y    R180 S0      
317GND              VIA   -    MD0080PA00X+136996Y+098486X0160Y    R180 S0      
317GND              VIA   -    MD0080PA00X+136626Y+097848X0160Y    R180 S0      
317GND              VIA   -    MD0080PA00X+136626Y+097210X0160Y    R180 S0      
317GND              VIA   -    MD0080PA00X+136812Y+098167X0160Y    R180 S0      
317GND              VIA   -    MD0080PA00X+136812Y+097529X0160Y    R180 S0      
317GND              VIA   -    MD0080PA00X+136996Y+097210X0160Y    R180 S0      
317GND              VIA   -    MD0080PA00X+137855Y+107270X0160Y         S0      
317GND              VIA   -    MD0080PA00X+137485Y+106632X0160Y         S0      
317GND              VIA   -    MD0080PA00X+137855Y+106632X0160Y         S0      
317GND              VIA   -    MD0080PA00X+137115Y+106632X0160Y         S0      
317GND              VIA   -    MD0080PA00X+136744Y+107270X0160Y         S0      
317GND              VIA   -    MD0080PA00X+136744Y+106632X0160Y         S0      
317GND              VIA   -    MD0080PA00X+136930Y+106951X0160Y         S0      
317GND              VIA   -    MD0080PA00X+136930Y+106313X0160Y         S0      
317GND              VIA   -    MD0080PA00X+137670Y+105038X0160Y         S0      
317GND              VIA   -    MD0080PA00X+137855Y+105357X0160Y         S0      
317GND              VIA   -    MD0080PA00X+137855Y+110459X0160Y         S0      
317GND              VIA   -    MD0080PA00X+137855Y+109821X0160Y         S0      
317GND              VIA   -    MD0080PA00X+137485Y+110459X0160Y         S0      
317GND              VIA   -    MD0080PA00X+137115Y+110459X0160Y         S0      
317GND              VIA   -    MD0080PA00X+137485Y+109184X0160Y         S0      
317GND              VIA   -    MD0080PA00X+137855Y+109184X0160Y         S0      
317GND              VIA   -    MD0080PA00X+137115Y+109184X0160Y         S0      
317GND              VIA   -    MD0080PA00X+136744Y+109821X0160Y         S0      
317GND              VIA   -    MD0080PA00X+136744Y+110459X0160Y         S0      
317GND              VIA   -    MD0080PA00X+136930Y+109502X0160Y         S0      
317GND              VIA   -    MD0080PA00X+136744Y+109184X0160Y         S0      
317GND              VIA   -    MD0080PA00X+137855Y+108546X0160Y         S0      
317GND              VIA   -    MD0080PA00X+137485Y+107908X0160Y         S0      
317GND              VIA   -    MD0080PA00X+137855Y+107908X0160Y         S0      
317GND              VIA   -    MD0080PA00X+137115Y+107908X0160Y         S0      
317GND              VIA   -    MD0080PA00X+136930Y+108227X0160Y         S0      
317GND              VIA   -    MD0080PA00X+136744Y+108546X0160Y         S0      
317GND              VIA   -    MD0080PA00X+136930Y+108865X0160Y         S0      
317GND              VIA   -    MD0080PA00X+136744Y+107908X0160Y         S0      
317GND              VIA   -    MD0080PA00X+136930Y+107589X0160Y         S0      
317GND              VIA   -    MD0080PA00X+137855Y+111735X0160Y         S0      
317GND              VIA   -    MD0080PA00X+137485Y+111097X0160Y         S0      
317GND              VIA   -    MD0080PA00X+137855Y+111097X0160Y         S0      
317GND              VIA   -    MD0080PA00X+137115Y+111097X0160Y         S0      
317GND              VIA   -    MD0080PA00X+136744Y+111735X0160Y         S0      
317GND              VIA   -    MD0080PA00X+136930Y+111416X0160Y         S0      
317GND              VIA   -    MD0080PA00X+136744Y+111097X0160Y         S0      
317GND              VIA   -    MD0080PA00X+136930Y+110778X0160Y         S0      
317GND              VIA   -    MD0080PA00X+137855Y+113010X0160Y         S0      
317GND              VIA   -    MD0080PA00X+137855Y+112372X0160Y         S0      
317GND              VIA   -    MD0080PA00X+137115Y+112372X0160Y         S0      
317GND              VIA   -    MD0080PA00X+137485Y+112372X0160Y         S0      
317GND              VIA   -    MD0080PA00X+136930Y+113329X0160Y         S0      
317GND              VIA   -    MD0080PA00X+136744Y+112372X0160Y         S0      
317GND              VIA   -    MD0080PA00X+136930Y+112054X0160Y         S0      
317GND              VIA   -    MD0080PA00X+136930Y+112691X0160Y         S0      
317GND              VIA   -    MD0080PA00X+137485Y+116199X0160Y         S0      
317GND              VIA   -    MD0080PA00X+137670Y+116518X0160Y         S0      
317GND              VIA   -    MD0080PA00X+137670Y+115880X0160Y         S0      
317GND              VIA   -    MD0080PA00X+137485Y+115561X0160Y         S0      
317GND              VIA   -    MD0080PA00X+137855Y+115561X0160Y         S0      
317GND              VIA   -    MD0080PA00X+137115Y+115561X0160Y         S0      
317GND              VIA   -    MD0080PA00X+136560Y+115880X0160Y         S0      
317GND              VIA   -    MD0080PA00X+136744Y+115561X0160Y         S0      
317GND              VIA   -    MD0080PA00X+137485Y+114924X0160Y         S0      
317GND              VIA   -    MD0080PA00X+137115Y+114924X0160Y         S0      
317GND              VIA   -    MD0080PA00X+137855Y+114286X0160Y         S0      
317GND              VIA   -    MD0080PA00X+137855Y+113648X0160Y         S0      
317GND              VIA   -    MD0080PA00X+137115Y+113648X0160Y         S0      
317GND              VIA   -    MD0080PA00X+137485Y+113648X0160Y         S0      
317GND              VIA   -    MD0080PA00X+136930Y+114605X0160Y         S0      
317GND              VIA   -    MD0080PA00X+136744Y+114286X0160Y         S0      
317GND              VIA   -    MD0080PA00X+136744Y+113648X0160Y         S0      
317GND              VIA   -    MD0080PA00X+136930Y+113967X0160Y         S0      
317GND              VIA   -    MD0080PA00X+139032Y+089238X0160Y    R180 S0      
317GND              VIA   -    MD0080PA00X+139217Y+088919X0160Y    R180 S0      
317GND              VIA   -    MD0080PA00X+138847Y+089557X0160Y    R180 S0      
317GND              VIA   -    MD0080PA00X+138847Y+088281X0160Y    R180 S0      
317GND              VIA   -    MD0080PA00X+139217Y+088281X0160Y    R180 S0      
317GND              VIA   -    MD0080PA00X+138477Y+088919X0160Y    R180 S0      
317GND              VIA   -    MD0080PA00X+138107Y+088919X0160Y    R180 S0      
317GND              VIA   -    MD0080PA00X+138107Y+088281X0160Y    R180 S0      
317GND              VIA   -    MD0080PA00X+138477Y+088281X0160Y    R180 S0      
317GND              VIA   -    MD0080PA00X+139402Y+087324X0160Y    R180 S0      
317GND              VIA   -    MD0080PA00X+138477Y+087643X0160Y    R180 S0      
317GND              VIA   -    MD0080PA00X+138292Y+087324X0160Y    R180 S0      
317GND              VIA   -    MD0080PA00X+138662Y+087962X0160Y    R180 S0      
317GND              VIA   -    MD0080PA00X+139032Y+093702X0160Y    R180 S0      
317GND              VIA   -    MD0080PA00X+138847Y+094021X0160Y    R180 S0      
317GND              VIA   -    MD0080PA00X+139217Y+093384X0160Y    R180 S0      
317GND              VIA   -    MD0080PA00X+139032Y+093065X0160Y    R180 S0      
317GND              VIA   -    MD0080PA00X+139217Y+092746X0160Y    R180 S0      
317GND              VIA   -    MD0080PA00X+138847Y+093384X0160Y    R180 S0      
317GND              VIA   -    MD0080PA00X+138847Y+092746X0160Y    R180 S0      
317GND              VIA   -    MD0080PA00X+138477Y+092746X0160Y    R180 S0      
317GND              VIA   -    MD0080PA00X+138107Y+092746X0160Y    R180 S0      
317GND              VIA   -    MD0080PA00X+139032Y+092427X0160Y    R180 S0      
317GND              VIA   -    MD0080PA00X+138847Y+092108X0160Y    R180 S0      
317GND              VIA   -    MD0080PA00X+139217Y+091470X0160Y    R180 S0      
317GND              VIA   -    MD0080PA00X+138847Y+091470X0160Y    R180 S0      
317GND              VIA   -    MD0080PA00X+139032Y+091789X0160Y    R180 S0      
317GND              VIA   -    MD0080PA00X+138477Y+091470X0160Y    R180 S0      
317GND              VIA   -    MD0080PA00X+138107Y+091470X0160Y    R180 S0      
317GND              VIA   -    MD0080PA00X+139032Y+090513X0160Y    R180 S0      
317GND              VIA   -    MD0080PA00X+139032Y+091151X0160Y    R180 S0      
317GND              VIA   -    MD0080PA00X+138847Y+090832X0160Y    R180 S0      
317GND              VIA   -    MD0080PA00X+139217Y+090195X0160Y    R180 S0      
317GND              VIA   -    MD0080PA00X+139032Y+089876X0160Y    R180 S0      
317GND              VIA   -    MD0080PA00X+138847Y+090195X0160Y    R180 S0      
317GND              VIA   -    MD0080PA00X+138477Y+090195X0160Y    R180 S0      
317GND              VIA   -    MD0080PA00X+138107Y+090195X0160Y    R180 S0      
317GND              VIA   -    MD0080PA00X+138106Y+101036X0160Y    R180 S0      
317GND              VIA   -    MD0080PA00X+139216Y+099761X0160Y    R180 S0      
317GND              VIA   -    MD0080PA00X+138476Y+099761X0160Y    R180 S0      
317GND              VIA   -    MD0080PA00X+139032Y+098805X0160Y    R180 S0      
317GND              VIA   -    MD0080PA00X+139217Y+099124X0160Y    R180 S0      
317GND              VIA   -    MD0080PA00X+138292Y+098805X0160Y    R180 S0      
317GND              VIA   -    MD0080PA00X+138477Y+099124X0160Y    R180 S0      
317GND              VIA   -    MD0080PA00X+139217Y+098486X0160Y    R180 S0      
317GND              VIA   -    MD0080PA00X+139032Y+097529X0160Y    R180 S0      
317GND              VIA   -    MD0080PA00X+139032Y+098167X0160Y    R180 S0      
317GND              VIA   -    MD0080PA00X+139217Y+097210X0160Y    R180 S0      
317GND              VIA   -    MD0080PA00X+138847Y+097210X0160Y    R180 S0      
317GND              VIA   -    MD0080PA00X+138477Y+098486X0160Y    R180 S0      
317GND              VIA   -    MD0080PA00X+138292Y+098167X0160Y    R180 S0      
317GND              VIA   -    MD0080PA00X+138477Y+097210X0160Y    R180 S0      
317GND              VIA   -    MD0080PA00X+138107Y+097210X0160Y    R180 S0      
317GND              VIA   -    MD0080PA00X+138847Y+097848X0160Y    R180 S0      
317GND              VIA   -    MD0080PA00X+139032Y+096891X0160Y    R180 S0      
317GND              VIA   -    MD0080PA00X+139032Y+096254X0160Y    R180 S0      
317GND              VIA   -    MD0080PA00X+139217Y+095935X0160Y    R180 S0      
317GND              VIA   -    MD0080PA00X+138847Y+095935X0160Y    R180 S0      
317GND              VIA   -    MD0080PA00X+138847Y+096572X0160Y    R180 S0      
317GND              VIA   -    MD0080PA00X+138477Y+095935X0160Y    R180 S0      
317GND              VIA   -    MD0080PA00X+138107Y+095935X0160Y    R180 S0      
317GND              VIA   -    MD0080PA00X+139032Y+095616X0160Y    R180 S0      
317GND              VIA   -    MD0080PA00X+138847Y+095297X0160Y    R180 S0      
317GND              VIA   -    MD0080PA00X+139032Y+094978X0160Y    R180 S0      
317GND              VIA   -    MD0080PA00X+139217Y+094659X0160Y    R180 S0      
317GND              VIA   -    MD0080PA00X+139032Y+094340X0160Y    R180 S0      
317GND              VIA   -    MD0080PA00X+138847Y+094659X0160Y    R180 S0      
317GND              VIA   -    MD0080PA00X+138477Y+094659X0160Y    R180 S0      
317GND              VIA   -    MD0080PA00X+138107Y+094659X0160Y    R180 S0      
317GND              VIA   -    MD0080PA00X+139335Y+106632X0160Y         S0      
317GND              VIA   -    MD0080PA00X+139150Y+106313X0160Y         S0      
317GND              VIA   -    MD0080PA00X+138040Y+106951X0160Y         S0      
317GND              VIA   -    MD0080PA00X+138225Y+106632X0160Y         S0      
317GND              VIA   -    MD0080PA00X+138595Y+106632X0160Y         S0      
317GND              VIA   -    MD0080PA00X+138040Y+106313X0160Y         S0      
317GND              VIA   -    MD0080PA00X+139150Y+105038X0160Y         S0      
317GND              VIA   -    MD0080PA00X+139150Y+105676X0160Y         S0      
317GND              VIA   -    MD0080PA00X+138965Y+105994X0160Y         S0      
317GND              VIA   -    MD0080PA00X+139335Y+105357X0160Y         S0      
317GND              VIA   -    MD0080PA00X+139335Y+104719X0160Y         S0      
317GND              VIA   -    MD0080PA00X+138410Y+105038X0160Y         S0      
317GND              VIA   -    MD0080PA00X+138410Y+105676X0160Y         S0      
317GND              VIA   -    MD0080PA00X+138595Y+105357X0160Y         S0      
317GND              VIA   -    MD0080PA00X+138595Y+104719X0160Y         S0      
317GND              VIA   -    MD0080PA00X+138594Y+104082X0160Y         S0      
317GND              VIA   -    MD0080PA00X+139334Y+104082X0160Y         S0      
317GND              VIA   -    MD0080PA00X+138594Y+103444X0160Y         S0      
317GND              VIA   -    MD0080PA00X+138594Y+102806X0160Y         S0      
317GND              VIA   -    MD0080PA00X+138661Y+100717X0160Y    R180 S0      
317GND              VIA   -    MD0080PA00X+139150Y+108227X0160Y         S0      
317GND              VIA   -    MD0080PA00X+138965Y+108546X0160Y         S0      
317GND              VIA   -    MD0080PA00X+139150Y+108865X0160Y         S0      
317GND              VIA   -    MD0080PA00X+138965Y+107908X0160Y         S0      
317GND              VIA   -    MD0080PA00X+139335Y+107908X0160Y         S0      
317GND              VIA   -    MD0080PA00X+139150Y+107589X0160Y         S0      
317GND              VIA   -    MD0080PA00X+138040Y+108227X0160Y         S0      
317GND              VIA   -    MD0080PA00X+138040Y+108865X0160Y         S0      
317GND              VIA   -    MD0080PA00X+138225Y+107908X0160Y         S0      
317GND              VIA   -    MD0080PA00X+138595Y+107908X0160Y         S0      
317GND              VIA   -    MD0080PA00X+138040Y+107589X0160Y         S0      
317GND              VIA   -    MD0080PA00X+138965Y+107270X0160Y         S0      
317GND              VIA   -    MD0080PA00X+139150Y+106951X0160Y         S0      
317GND              VIA   -    MD0080PA00X+138965Y+106632X0160Y         S0      
317GND              VIA   -    MD0080PA00X+139150Y+111416X0160Y         S0      
317GND              VIA   -    MD0080PA00X+138965Y+111735X0160Y         S0      
317GND              VIA   -    MD0080PA00X+139150Y+110778X0160Y         S0      
317GND              VIA   -    MD0080PA00X+138965Y+111097X0160Y         S0      
317GND              VIA   -    MD0080PA00X+139335Y+111097X0160Y         S0      
317GND              VIA   -    MD0080PA00X+138040Y+111416X0160Y         S0      
317GND              VIA   -    MD0080PA00X+138040Y+110778X0160Y         S0      
317GND              VIA   -    MD0080PA00X+138225Y+111097X0160Y         S0      
317GND              VIA   -    MD0080PA00X+138595Y+111097X0160Y         S0      
317GND              VIA   -    MD0080PA00X+138965Y+110459X0160Y         S0      
317GND              VIA   -    MD0080PA00X+139335Y+110459X0160Y         S0      
317GND              VIA   -    MD0080PA00X+138965Y+109821X0160Y         S0      
317GND              VIA   -    MD0080PA00X+139150Y+110140X0160Y         S0      
317GND              VIA   -    MD0080PA00X+139150Y+109502X0160Y         S0      
317GND              VIA   -    MD0080PA00X+138965Y+109184X0160Y         S0      
317GND              VIA   -    MD0080PA00X+139335Y+109184X0160Y         S0      
317GND              VIA   -    MD0080PA00X+138040Y+109502X0160Y         S0      
317GND              VIA   -    MD0080PA00X+138225Y+109184X0160Y         S0      
317GND              VIA   -    MD0080PA00X+138595Y+109184X0160Y         S0      
317GND              VIA   -    MD0080PA00X+139150Y+114605X0160Y         S0      
317GND              VIA   -    MD0080PA00X+139335Y+114924X0160Y         S0      
317GND              VIA   -    MD0080PA00X+138965Y+114286X0160Y         S0      
317GND              VIA   -    MD0080PA00X+138965Y+113648X0160Y         S0      
317GND              VIA   -    MD0080PA00X+139335Y+113648X0160Y         S0      
317GND              VIA   -    MD0080PA00X+139150Y+113967X0160Y         S0      
317GND              VIA   -    MD0080PA00X+138040Y+114605X0160Y         S0      
317GND              VIA   -    MD0080PA00X+138225Y+114924X0160Y         S0      
317GND              VIA   -    MD0080PA00X+138595Y+114924X0160Y         S0      
317GND              VIA   -    MD0080PA00X+138225Y+113648X0160Y         S0      
317GND              VIA   -    MD0080PA00X+138595Y+113648X0160Y         S0      
317GND              VIA   -    MD0080PA00X+138040Y+113967X0160Y         S0      
317GND              VIA   -    MD0080PA00X+138965Y+113010X0160Y         S0      
317GND              VIA   -    MD0080PA00X+139150Y+113329X0160Y         S0      
317GND              VIA   -    MD0080PA00X+139150Y+112691X0160Y         S0      
317GND              VIA   -    MD0080PA00X+139150Y+112054X0160Y         S0      
317GND              VIA   -    MD0080PA00X+138965Y+112372X0160Y         S0      
317GND              VIA   -    MD0080PA00X+139335Y+112372X0160Y         S0      
317GND              VIA   -    MD0080PA00X+138040Y+113329X0160Y         S0      
317GND              VIA   -    MD0080PA00X+138040Y+112691X0160Y         S0      
317GND              VIA   -    MD0080PA00X+138040Y+112054X0160Y         S0      
317GND              VIA   -    MD0080PA00X+138225Y+112372X0160Y         S0      
317GND              VIA   -    MD0080PA00X+138595Y+112372X0160Y         S0      
317GND              VIA   -    MD0080PA00X+138965Y+115561X0160Y         S0      
317GND              VIA   -    MD0080PA00X+139335Y+115561X0160Y         S0      
317GND              VIA   -    MD0080PA00X+138780Y+115880X0160Y         S0      
317GND              VIA   -    MD0080PA00X+138595Y+116199X0160Y         S0      
317GND              VIA   -    MD0080PA00X+138225Y+115561X0160Y         S0      
317GND              VIA   -    MD0080PA00X+138595Y+115561X0160Y         S0      
317GND              VIA   -    MD0080PA00X+140142Y+089876X0160Y    R180 S0      
317GND              VIA   -    MD0080PA00X+140697Y+088919X0160Y    R180 S0      
317GND              VIA   -    MD0080PA00X+140327Y+088919X0160Y    R180 S0      
317GND              VIA   -    MD0080PA00X+140697Y+088281X0160Y    R180 S0      
317GND              VIA   -    MD0080PA00X+140327Y+088281X0160Y    R180 S0      
317GND              VIA   -    MD0080PA00X+139587Y+088919X0160Y    R180 S0      
317GND              VIA   -    MD0080PA00X+139957Y+089557X0160Y    R180 S0      
317GND              VIA   -    MD0080PA00X+140142Y+089238X0160Y    R180 S0      
317GND              VIA   -    MD0080PA00X+139587Y+088281X0160Y    R180 S0      
317GND              VIA   -    MD0080PA00X+139957Y+088281X0160Y    R180 S0      
317GND              VIA   -    MD0080PA00X+140882Y+087962X0160Y    R180 S0      
317GND              VIA   -    MD0080PA00X+139587Y+087643X0160Y    R180 S0      
317GND              VIA   -    MD0080PA00X+139772Y+087962X0160Y    R180 S0      
317GND              VIA   -    MD0080PA00X+139772Y+087324X0160Y    R180 S0      
317GND              VIA   -    MD0080PA00X+139587Y+094659X0160Y    R180 S0      
317GND              VIA   -    MD0080PA00X+140882Y+093702X0160Y    R180 S0      
317GND              VIA   -    MD0080PA00X+140512Y+093702X0160Y    R180 S0      
317GND              VIA   -    MD0080PA00X+140882Y+093065X0160Y    R180 S0      
317GND              VIA   -    MD0080PA00X+140512Y+093065X0160Y    R180 S0      
317GND              VIA   -    MD0080PA00X+140142Y+093702X0160Y    R180 S0      
317GND              VIA   -    MD0080PA00X+139957Y+094021X0160Y    R180 S0      
317GND              VIA   -    MD0080PA00X+139957Y+093384X0160Y    R180 S0      
317GND              VIA   -    MD0080PA00X+140142Y+093065X0160Y    R180 S0      
317GND              VIA   -    MD0080PA00X+139957Y+092746X0160Y    R180 S0      
317GND              VIA   -    MD0080PA00X+139587Y+093384X0160Y    R180 S0      
317GND              VIA   -    MD0080PA00X+139587Y+092746X0160Y    R180 S0      
317GND              VIA   -    MD0080PA00X+140882Y+091789X0160Y    R180 S0      
317GND              VIA   -    MD0080PA00X+140512Y+091789X0160Y    R180 S0      
317GND              VIA   -    MD0080PA00X+140142Y+092427X0160Y    R180 S0      
317GND              VIA   -    MD0080PA00X+139957Y+092108X0160Y    R180 S0      
317GND              VIA   -    MD0080PA00X+139587Y+091470X0160Y    R180 S0      
317GND              VIA   -    MD0080PA00X+140142Y+091789X0160Y    R180 S0      
317GND              VIA   -    MD0080PA00X+139957Y+091470X0160Y    R180 S0      
317GND              VIA   -    MD0080PA00X+140882Y+090513X0160Y    R180 S0      
317GND              VIA   -    MD0080PA00X+140512Y+090513X0160Y    R180 S0      
317GND              VIA   -    MD0080PA00X+140142Y+091151X0160Y    R180 S0      
317GND              VIA   -    MD0080PA00X+140142Y+090513X0160Y    R180 S0      
317GND              VIA   -    MD0080PA00X+139587Y+090195X0160Y    R180 S0      
317GND              VIA   -    MD0080PA00X+139957Y+090195X0160Y    R180 S0      
317GND              VIA   -    MD0080PA00X+140074Y+104082X0160Y         S0      
317GND              VIA   -    MD0080PA00X+139956Y+099761X0160Y    R180 S0      
317GND              VIA   -    MD0080PA00X+140696Y+099761X0160Y    R180 S0      
317GND              VIA   -    MD0080PA00X+140512Y+098805X0160Y    R180 S0      
317GND              VIA   -    MD0080PA00X+140697Y+099124X0160Y    R180 S0      
317GND              VIA   -    MD0080PA00X+139772Y+098805X0160Y    R180 S0      
317GND              VIA   -    MD0080PA00X+139957Y+099124X0160Y    R180 S0      
317GND              VIA   -    MD0080PA00X+140697Y+098486X0160Y    R180 S0      
317GND              VIA   -    MD0080PA00X+140512Y+097529X0160Y    R180 S0      
317GND              VIA   -    MD0080PA00X+140882Y+097529X0160Y    R180 S0      
317GND              VIA   -    MD0080PA00X+140512Y+098167X0160Y    R180 S0      
317GND              VIA   -    MD0080PA00X+139957Y+098486X0160Y    R180 S0      
317GND              VIA   -    MD0080PA00X+140142Y+097529X0160Y    R180 S0      
317GND              VIA   -    MD0080PA00X+139957Y+097210X0160Y    R180 S0      
317GND              VIA   -    MD0080PA00X+139587Y+097210X0160Y    R180 S0      
317GND              VIA   -    MD0080PA00X+139957Y+097848X0160Y    R180 S0      
317GND              VIA   -    MD0080PA00X+139772Y+098167X0160Y    R180 S0      
317GND              VIA   -    MD0080PA00X+140512Y+096254X0160Y    R180 S0      
317GND              VIA   -    MD0080PA00X+140882Y+096254X0160Y    R180 S0      
317GND              VIA   -    MD0080PA00X+140142Y+096891X0160Y    R180 S0      
317GND              VIA   -    MD0080PA00X+140142Y+096254X0160Y    R180 S0      
317GND              VIA   -    MD0080PA00X+139957Y+095935X0160Y    R180 S0      
317GND              VIA   -    MD0080PA00X+139587Y+095935X0160Y    R180 S0      
317GND              VIA   -    MD0080PA00X+139957Y+096572X0160Y    R180 S0      
317GND              VIA   -    MD0080PA00X+140512Y+094978X0160Y    R180 S0      
317GND              VIA   -    MD0080PA00X+140882Y+094978X0160Y    R180 S0      
317GND              VIA   -    MD0080PA00X+140142Y+095616X0160Y    R180 S0      
317GND              VIA   -    MD0080PA00X+139957Y+095297X0160Y    R180 S0      
317GND              VIA   -    MD0080PA00X+140142Y+094978X0160Y    R180 S0      
317GND              VIA   -    MD0080PA00X+139957Y+094659X0160Y    R180 S0      
317GND              VIA   -    MD0080PA00X+140142Y+094340X0160Y    R180 S0      
317GND              VIA   -    MD0080PA00X+140630Y+105038X0160Y         S0      
317GND              VIA   -    MD0080PA00X+140630Y+105676X0160Y         S0      
317GND              VIA   -    MD0080PA00X+140815Y+105357X0160Y         S0      
317GND              VIA   -    MD0080PA00X+140815Y+104719X0160Y         S0      
317GND              VIA   -    MD0080PA00X+139890Y+105038X0160Y         S0      
317GND              VIA   -    MD0080PA00X+140075Y+105994X0160Y         S0      
317GND              VIA   -    MD0080PA00X+140075Y+105357X0160Y         S0      
317GND              VIA   -    MD0080PA00X+139890Y+105676X0160Y         S0      
317GND              VIA   -    MD0080PA00X+140075Y+104719X0160Y         S0      
317GND              VIA   -    MD0080PA00X+140630Y+106313X0160Y         S0      
317GND              VIA   -    MD0080PA00X+140075Y+107270X0160Y         S0      
317GND              VIA   -    MD0080PA00X+140075Y+106632X0160Y         S0      
317GND              VIA   -    MD0080PA00X+139705Y+106632X0160Y         S0      
317GND              VIA   -    MD0080PA00X+140260Y+106951X0160Y         S0      
317GND              VIA   -    MD0080PA00X+140260Y+106313X0160Y         S0      
317GND              VIA   -    MD0080PA00X+140630Y+108865X0160Y         S0      
317GND              VIA   -    MD0080PA00X+140630Y+107589X0160Y         S0      
317GND              VIA   -    MD0080PA00X+140075Y+108546X0160Y         S0      
317GND              VIA   -    MD0080PA00X+140260Y+108227X0160Y         S0      
317GND              VIA   -    MD0080PA00X+140260Y+108865X0160Y         S0      
317GND              VIA   -    MD0080PA00X+139705Y+107908X0160Y         S0      
317GND              VIA   -    MD0080PA00X+140075Y+107908X0160Y         S0      
317GND              VIA   -    MD0080PA00X+140260Y+107589X0160Y         S0      
317GND              VIA   -    MD0080PA00X+140630Y+110140X0160Y         S0      
317GND              VIA   -    MD0080PA00X+140075Y+109821X0160Y         S0      
317GND              VIA   -    MD0080PA00X+139705Y+110459X0160Y         S0      
317GND              VIA   -    MD0080PA00X+140075Y+110459X0160Y         S0      
317GND              VIA   -    MD0080PA00X+140260Y+110140X0160Y         S0      
317GND              VIA   -    MD0080PA00X+139705Y+109184X0160Y         S0      
317GND              VIA   -    MD0080PA00X+140075Y+109184X0160Y         S0      
317GND              VIA   -    MD0080PA00X+140260Y+109502X0160Y         S0      
317GND              VIA   -    MD0080PA00X+140630Y+110778X0160Y         S0      
317GND              VIA   -    MD0080PA00X+140075Y+111735X0160Y         S0      
317GND              VIA   -    MD0080PA00X+140260Y+111416X0160Y         S0      
317GND              VIA   -    MD0080PA00X+140075Y+111097X0160Y         S0      
317GND              VIA   -    MD0080PA00X+139705Y+111097X0160Y         S0      
317GND              VIA   -    MD0080PA00X+140260Y+110778X0160Y         S0      
317GND              VIA   -    MD0080PA00X+140630Y+113329X0160Y         S0      
317GND              VIA   -    MD0080PA00X+140630Y+112054X0160Y         S0      
317GND              VIA   -    MD0080PA00X+140260Y+113329X0160Y         S0      
317GND              VIA   -    MD0080PA00X+140075Y+112372X0160Y         S0      
317GND              VIA   -    MD0080PA00X+139705Y+112372X0160Y         S0      
317GND              VIA   -    MD0080PA00X+140260Y+112691X0160Y         S0      
317GND              VIA   -    MD0080PA00X+140260Y+112054X0160Y         S0      
317GND              VIA   -    MD0080PA00X+140630Y+115880X0160Y         S0      
317GND              VIA   -    MD0080PA00X+139890Y+116518X0160Y         S0      
317GND              VIA   -    MD0080PA00X+139705Y+116199X0160Y         S0      
317GND              VIA   -    MD0080PA00X+140075Y+115561X0160Y         S0      
317GND              VIA   -    MD0080PA00X+139705Y+115561X0160Y         S0      
317GND              VIA   -    MD0080PA00X+139890Y+115880X0160Y         S0      
317GND              VIA   -    MD0080PA00X+140445Y+114924X0160Y         S0      
317GND              VIA   -    MD0080PA00X+140815Y+114924X0160Y         S0      
317GND              VIA   -    MD0080PA00X+139705Y+114924X0160Y         S0      
317GND              VIA   -    MD0080PA00X+140260Y+114605X0160Y         S0      
317GND              VIA   -    MD0080PA00X+140075Y+114286X0160Y         S0      
317GND              VIA   -    MD0080PA00X+140075Y+113648X0160Y         S0      
317GND              VIA   -    MD0080PA00X+139705Y+113648X0160Y         S0      
317GND              VIA   -    MD0080PA00X+140260Y+113967X0160Y         S0      
317GND              VIA   -    MD0080PA00X+142360Y+093702X0160Y    R180 S0      
317GND              VIA   -    MD0080PA00X+142175Y+093384X0160Y    R180 S0      
317GND              VIA   -    MD0080PA00X+142175Y+092746X0160Y    R180 S0      
317GND              VIA   -    MD0080PA00X+142360Y+093065X0160Y    R180 S0      
317GND              VIA   -    MD0080PA00X+141067Y+094021X0160Y    R180 S0      
317GND              VIA   -    MD0080PA00X+141067Y+093384X0160Y    R180 S0      
317GND              VIA   -    MD0080PA00X+141067Y+092746X0160Y    R180 S0      
317GND              VIA   -    MD0080PA00X+142175Y+092108X0160Y    R180 S0      
317GND              VIA   -    MD0080PA00X+142175Y+091470X0160Y    R180 S0      
317GND              VIA   -    MD0080PA00X+142360Y+091789X0160Y    R180 S0      
317GND              VIA   -    MD0080PA00X+141067Y+092108X0160Y    R180 S0      
317GND              VIA   -    MD0080PA00X+141067Y+091470X0160Y    R180 S0      
317GND              VIA   -    MD0080PA00X+142175Y+090832X0160Y    R180 S0      
317GND              VIA   -    MD0080PA00X+142360Y+090513X0160Y    R180 S0      
317GND              VIA   -    MD0080PA00X+142175Y+090195X0160Y    R180 S0      
317GND              VIA   -    MD0080PA00X+141067Y+090832X0160Y    R180 S0      
317GND              VIA   -    MD0080PA00X+141067Y+090195X0160Y    R180 S0      
317GND              VIA   -    MD0080PA00X+142175Y+088919X0160Y    R180 S0      
317GND              VIA   -    MD0080PA00X+142175Y+089557X0160Y    R180 S0      
317GND              VIA   -    MD0080PA00X+142175Y+088281X0160Y    R180 S0      
317GND              VIA   -    MD0080PA00X+141067Y+089557X0160Y    R180 S0      
317GND              VIA   -    MD0080PA00X+141067Y+088919X0160Y    R180 S0      
317GND              VIA   -    MD0080PA00X+141067Y+088281X0160Y    R180 S0      
317GND              VIA   -    MD0080PA00X+142175Y+087643X0160Y    R180 S0      
317GND              VIA   -    MD0080PA00X+142360Y+087962X0160Y    R180 S0      
317GND              VIA   -    MD0080PA00X+141067Y+087643X0160Y    R180 S0      
317GND              VIA   -    MD0080PA00X+141000Y+110140X0160Y         S0      
317GND              VIA   -    MD0080PA00X+141186Y+109821X0160Y         S0      
317GND              VIA   -    MD0080PA00X+141186Y+110459X0160Y         S0      
317GND              VIA   -    MD0080PA00X+141186Y+109184X0160Y         S0      
317GND              VIA   -    MD0080PA00X+142293Y+108546X0160Y         S0      
317GND              VIA   -    MD0080PA00X+142293Y+107908X0160Y         S0      
317GND              VIA   -    MD0080PA00X+141000Y+108865X0160Y         S0      
317GND              VIA   -    MD0080PA00X+141186Y+108546X0160Y         S0      
317GND              VIA   -    MD0080PA00X+141186Y+107908X0160Y         S0      
317GND              VIA   -    MD0080PA00X+141000Y+107589X0160Y         S0      
317GND              VIA   -    MD0080PA00X+142293Y+106632X0160Y         S0      
317GND              VIA   -    MD0080PA00X+142293Y+107270X0160Y         S0      
317GND              VIA   -    MD0080PA00X+141186Y+107270X0160Y         S0      
317GND              VIA   -    MD0080PA00X+141186Y+106632X0160Y         S0      
317GND              VIA   -    MD0080PA00X+141000Y+106313X0160Y         S0      
317GND              VIA   -    MD0080PA00X+142293Y+105357X0160Y         S0      
317GND              VIA   -    MD0080PA00X+142293Y+105994X0160Y         S0      
317GND              VIA   -    MD0080PA00X+142293Y+104719X0160Y         S0      
317GND              VIA   -    MD0080PA00X+141186Y+105994X0160Y         S0      
317GND              VIA   -    MD0080PA00X+142176Y+099761X0160Y    R180 S0      
317GND              VIA   -    MD0080PA00X+142175Y+099124X0160Y    R180 S0      
317GND              VIA   -    MD0080PA00X+142360Y+098805X0160Y    R180 S0      
317GND              VIA   -    MD0080PA00X+142175Y+098486X0160Y    R180 S0      
317GND              VIA   -    MD0080PA00X+142175Y+097848X0160Y    R180 S0      
317GND              VIA   -    MD0080PA00X+142175Y+097210X0160Y    R180 S0      
317GND              VIA   -    MD0080PA00X+142360Y+097529X0160Y    R180 S0      
317GND              VIA   -    MD0080PA00X+142360Y+098167X0160Y    R180 S0      
317GND              VIA   -    MD0080PA00X+141067Y+097848X0160Y    R180 S0      
317GND              VIA   -    MD0080PA00X+141067Y+097210X0160Y    R180 S0      
317GND              VIA   -    MD0080PA00X+142175Y+096572X0160Y    R180 S0      
317GND              VIA   -    MD0080PA00X+142175Y+095935X0160Y    R180 S0      
317GND              VIA   -    MD0080PA00X+142360Y+096254X0160Y    R180 S0      
317GND              VIA   -    MD0080PA00X+141067Y+096572X0160Y    R180 S0      
317GND              VIA   -    MD0080PA00X+141067Y+095935X0160Y    R180 S0      
317GND              VIA   -    MD0080PA00X+142175Y+095297X0160Y    R180 S0      
317GND              VIA   -    MD0080PA00X+142175Y+094659X0160Y    R180 S0      
317GND              VIA   -    MD0080PA00X+142360Y+094978X0160Y    R180 S0      
317GND              VIA   -    MD0080PA00X+141067Y+095297X0160Y    R180 S0      
317GND              VIA   -    MD0080PA00X+141067Y+094659X0160Y    R180 S0      
317GND              VIA   -    MD0080PA00X+142175Y+094021X0160Y    R180 S0      
317GND              VIA   -    MD0080PA00X+142293Y+116199X0160Y         S0      
317GND              VIA   -    MD0080PA00X+142293Y+115561X0160Y         S0      
317GND              VIA   -    MD0080PA00X+141186Y+116199X0160Y         S0      
317GND              VIA   -    MD0080PA00X+141186Y+115561X0160Y         S0      
317GND              VIA   -    MD0080PA00X+142293Y+114924X0160Y         S0      
317GND              VIA   -    MD0080PA00X+142293Y+114286X0160Y         S0      
317GND              VIA   -    MD0080PA00X+142293Y+113648X0160Y         S0      
317GND              VIA   -    MD0080PA00X+141186Y+114924X0160Y         S0      
317GND              VIA   -    MD0080PA00X+141186Y+114286X0160Y         S0      
317GND              VIA   -    MD0080PA00X+141186Y+113648X0160Y         S0      
317GND              VIA   -    MD0080PA00X+142293Y+113010X0160Y         S0      
317GND              VIA   -    MD0080PA00X+142293Y+112372X0160Y         S0      
317GND              VIA   -    MD0080PA00X+141000Y+113329X0160Y         S0      
317GND              VIA   -    MD0080PA00X+141186Y+113010X0160Y         S0      
317GND              VIA   -    MD0080PA00X+141000Y+112054X0160Y         S0      
317GND              VIA   -    MD0080PA00X+141186Y+112372X0160Y         S0      
317GND              VIA   -    MD0080PA00X+142293Y+111735X0160Y         S0      
317GND              VIA   -    MD0080PA00X+142293Y+111097X0160Y         S0      
317GND              VIA   -    MD0080PA00X+141186Y+111735X0160Y         S0      
317GND              VIA   -    MD0080PA00X+141186Y+111097X0160Y         S0      
317GND              VIA   -    MD0080PA00X+141000Y+110778X0160Y         S0      
317GND              VIA   -    MD0080PA00X+142293Y+109821X0160Y         S0      
317GND              VIA   -    MD0080PA00X+142293Y+110459X0160Y         S0      
317GND              VIA   -    MD0080PA00X+142293Y+109184X0160Y         S0      
317GND              VIA   -    MD0080PA00X+143655Y+088919X0160Y    R180 S0      
317GND              VIA   -    MD0080PA00X+143285Y+089557X0160Y    R180 S0      
317GND              VIA   -    MD0080PA00X+143100Y+089238X0160Y    R180 S0      
317GND              VIA   -    MD0080PA00X+142915Y+088919X0160Y    R180 S0      
317GND              VIA   -    MD0080PA00X+142545Y+088919X0160Y    R180 S0      
317GND              VIA   -    MD0080PA00X+142915Y+088281X0160Y    R180 S0      
317GND              VIA   -    MD0080PA00X+143655Y+087643X0160Y    R180 S0      
317GND              VIA   -    MD0080PA00X+143655Y+090195X0160Y    R180 S0      
317GND              VIA   -    MD0080PA00X+142730Y+090513X0160Y    R180 S0      
317GND              VIA   -    MD0080PA00X+143100Y+090513X0160Y    R180 S0      
317GND              VIA   -    MD0080PA00X+143100Y+091151X0160Y    R180 S0      
317GND              VIA   -    MD0080PA00X+143100Y+089876X0160Y    R180 S0      
317GND              VIA   -    MD0080PA00X+143285Y+090195X0160Y    R180 S0      
317GND              VIA   -    MD0080PA00X+143655Y+093384X0160Y    R180 S0      
317GND              VIA   -    MD0080PA00X+143655Y+092746X0160Y    R180 S0      
317GND              VIA   -    MD0080PA00X+142730Y+093702X0160Y    R180 S0      
317GND              VIA   -    MD0080PA00X+143100Y+093702X0160Y    R180 S0      
317GND              VIA   -    MD0080PA00X+143285Y+094021X0160Y    R180 S0      
317GND              VIA   -    MD0080PA00X+143285Y+093384X0160Y    R180 S0      
317GND              VIA   -    MD0080PA00X+142730Y+093065X0160Y    R180 S0      
317GND              VIA   -    MD0080PA00X+143100Y+093065X0160Y    R180 S0      
317GND              VIA   -    MD0080PA00X+143285Y+092746X0160Y    R180 S0      
317GND              VIA   -    MD0080PA00X+143655Y+091470X0160Y    R180 S0      
317GND              VIA   -    MD0080PA00X+143100Y+092427X0160Y    R180 S0      
317GND              VIA   -    MD0080PA00X+143285Y+092108X0160Y    R180 S0      
317GND              VIA   -    MD0080PA00X+142730Y+091789X0160Y    R180 S0      
317GND              VIA   -    MD0080PA00X+143100Y+091789X0160Y    R180 S0      
317GND              VIA   -    MD0080PA00X+143285Y+091470X0160Y    R180 S0      
317GND              VIA   -    MD0080PA00X+143655Y+094659X0160Y    R180 S0      
317GND              VIA   -    MD0080PA00X+143100Y+095616X0160Y    R180 S0      
317GND              VIA   -    MD0080PA00X+143285Y+095297X0160Y    R180 S0      
317GND              VIA   -    MD0080PA00X+143285Y+094659X0160Y    R180 S0      
317GND              VIA   -    MD0080PA00X+142730Y+094978X0160Y    R180 S0      
317GND              VIA   -    MD0080PA00X+143100Y+094978X0160Y    R180 S0      
317GND              VIA   -    MD0080PA00X+143100Y+094340X0160Y    R180 S0      
317GND              VIA   -    MD0080PA00X+143655Y+095935X0160Y    R180 S0      
317GND              VIA   -    MD0080PA00X+143100Y+096891X0160Y    R180 S0      
317GND              VIA   -    MD0080PA00X+143285Y+096572X0160Y    R180 S0      
317GND              VIA   -    MD0080PA00X+143100Y+096254X0160Y    R180 S0      
317GND              VIA   -    MD0080PA00X+142730Y+096254X0160Y    R180 S0      
317GND              VIA   -    MD0080PA00X+143285Y+095935X0160Y    R180 S0      
317GND              VIA   -    MD0080PA00X+143774Y+105357X0160Y         S0      
317GND              VIA   -    MD0080PA00X+143774Y+104719X0160Y         S0      
317GND              VIA   -    MD0080PA00X+143218Y+105038X0160Y         S0      
317GND              VIA   -    MD0080PA00X+142478Y+105038X0160Y         S0      
317GND              VIA   -    MD0080PA00X+143033Y+105357X0160Y         S0      
317GND              VIA   -    MD0080PA00X+143218Y+105676X0160Y         S0      
317GND              VIA   -    MD0080PA00X+143404Y+105994X0160Y         S0      
317GND              VIA   -    MD0080PA00X+142478Y+105676X0160Y         S0      
317GND              VIA   -    MD0080PA00X+143033Y+104719X0160Y         S0      
317GND              VIA   -    MD0080PA00X+143775Y+104082X0160Y         S0      
317GND              VIA   -    MD0080PA00X+143035Y+104082X0160Y         S0      
317GND              VIA   -    MD0080PA00X+142916Y+099761X0160Y    R180 S0      
317GND              VIA   -    MD0080PA00X+143657Y+099761X0160Y    R180 S0      
317GND              VIA   -    MD0080PA00X+143840Y+098805X0160Y    R180 S0      
317GND              VIA   -    MD0080PA00X+143655Y+099124X0160Y    R180 S0      
317GND              VIA   -    MD0080PA00X+142915Y+099124X0160Y    R180 S0      
317GND              VIA   -    MD0080PA00X+143100Y+098805X0160Y    R180 S0      
317GND              VIA   -    MD0080PA00X+143655Y+098486X0160Y    R180 S0      
317GND              VIA   -    MD0080PA00X+143655Y+097210X0160Y    R180 S0      
317GND              VIA   -    MD0080PA00X+143840Y+098167X0160Y    R180 S0      
317GND              VIA   -    MD0080PA00X+142915Y+098486X0160Y    R180 S0      
317GND              VIA   -    MD0080PA00X+142730Y+097529X0160Y    R180 S0      
317GND              VIA   -    MD0080PA00X+143100Y+097529X0160Y    R180 S0      
317GND              VIA   -    MD0080PA00X+143285Y+097210X0160Y    R180 S0      
317GND              VIA   -    MD0080PA00X+143100Y+098167X0160Y    R180 S0      
317GND              VIA   -    MD0080PA00X+143285Y+097848X0160Y    R180 S0      
317GND              VIA   -    MD0080PA00X+143774Y+106632X0160Y         S0      
317GND              VIA   -    MD0080PA00X+143404Y+106632X0160Y         S0      
317GND              VIA   -    MD0080PA00X+143404Y+107270X0160Y         S0      
317GND              VIA   -    MD0080PA00X+143218Y+106951X0160Y         S0      
317GND              VIA   -    MD0080PA00X+142478Y+106313X0160Y         S0      
317GND              VIA   -    MD0080PA00X+142848Y+106313X0160Y         S0      
317GND              VIA   -    MD0080PA00X+143218Y+106313X0160Y         S0      
317GND              VIA   -    MD0080PA00X+143404Y+108546X0160Y         S0      
317GND              VIA   -    MD0080PA00X+143218Y+108865X0160Y         S0      
317GND              VIA   -    MD0080PA00X+142848Y+108865X0160Y         S0      
317GND              VIA   -    MD0080PA00X+143218Y+108227X0160Y         S0      
317GND              VIA   -    MD0080PA00X+142478Y+108865X0160Y         S0      
317GND              VIA   -    MD0080PA00X+143404Y+107908X0160Y         S0      
317GND              VIA   -    MD0080PA00X+142478Y+107589X0160Y         S0      
317GND              VIA   -    MD0080PA00X+143218Y+107589X0160Y         S0      
317GND              VIA   -    MD0080PA00X+142848Y+107589X0160Y         S0      
317GND              VIA   -    MD0080PA00X+143774Y+110459X0160Y         S0      
317GND              VIA   -    MD0080PA00X+143774Y+109184X0160Y         S0      
317GND              VIA   -    MD0080PA00X+142478Y+110140X0160Y         S0      
317GND              VIA   -    MD0080PA00X+143404Y+109821X0160Y         S0      
317GND              VIA   -    MD0080PA00X+143218Y+110140X0160Y         S0      
317GND              VIA   -    MD0080PA00X+142848Y+110140X0160Y         S0      
317GND              VIA   -    MD0080PA00X+143404Y+110459X0160Y         S0      
317GND              VIA   -    MD0080PA00X+143404Y+109184X0160Y         S0      
317GND              VIA   -    MD0080PA00X+143218Y+109502X0160Y         S0      
317GND              VIA   -    MD0080PA00X+143774Y+107908X0160Y         S0      
317GND              VIA   -    MD0080PA00X+143774Y+111097X0160Y         S0      
317GND              VIA   -    MD0080PA00X+143218Y+111416X0160Y         S0      
317GND              VIA   -    MD0080PA00X+143404Y+111735X0160Y         S0      
317GND              VIA   -    MD0080PA00X+143404Y+111097X0160Y         S0      
317GND              VIA   -    MD0080PA00X+142478Y+110778X0160Y         S0      
317GND              VIA   -    MD0080PA00X+143218Y+110778X0160Y         S0      
317GND              VIA   -    MD0080PA00X+142848Y+110778X0160Y         S0      
317GND              VIA   -    MD0080PA00X+143774Y+112372X0160Y         S0      
317GND              VIA   -    MD0080PA00X+143218Y+113329X0160Y         S0      
317GND              VIA   -    MD0080PA00X+142848Y+113329X0160Y         S0      
317GND              VIA   -    MD0080PA00X+142478Y+113329X0160Y         S0      
317GND              VIA   -    MD0080PA00X+143404Y+112372X0160Y         S0      
317GND              VIA   -    MD0080PA00X+142478Y+112054X0160Y         S0      
317GND              VIA   -    MD0080PA00X+142848Y+112054X0160Y         S0      
317GND              VIA   -    MD0080PA00X+143218Y+112054X0160Y         S0      
317GND              VIA   -    MD0080PA00X+143218Y+112691X0160Y         S0      
317GND              VIA   -    MD0080PA00X+143588Y+115242X0160Y         S0      
317GND              VIA   -    MD0080PA00X+143588Y+115880X0160Y         S0      
317GND              VIA   -    MD0080PA00X+143033Y+115561X0160Y         S0      
317GND              VIA   -    MD0080PA00X+143774Y+114924X0160Y         S0      
317GND              VIA   -    MD0080PA00X+143774Y+113648X0160Y         S0      
317GND              VIA   -    MD0080PA00X+142663Y+114924X0160Y         S0      
317GND              VIA   -    MD0080PA00X+143218Y+114605X0160Y         S0      
317GND              VIA   -    MD0080PA00X+143033Y+114924X0160Y         S0      
317GND              VIA   -    MD0080PA00X+143404Y+114286X0160Y         S0      
317GND              VIA   -    MD0080PA00X+143404Y+113648X0160Y         S0      
317GND              VIA   -    MD0080PA00X+143218Y+113967X0160Y         S0      
317GND              VIA   -    MD0080PA00X+144581Y+087962X0160Y    R180 S0      
317GND              VIA   -    MD0080PA00X+144766Y+087643X0160Y    R180 S0      
317GND              VIA   -    MD0080PA00X+145321Y+091151X0160Y    R180 S0      
317GND              VIA   -    MD0080PA00X+145321Y+090513X0160Y    R180 S0      
317GND              VIA   -    MD0080PA00X+145321Y+089876X0160Y    R180 S0      
317GND              VIA   -    MD0080PA00X+145136Y+090195X0160Y    R180 S0      
317GND              VIA   -    MD0080PA00X+144211Y+091151X0160Y    R180 S0      
317GND              VIA   -    MD0080PA00X+144396Y+090832X0160Y    R180 S0      
317GND              VIA   -    MD0080PA00X+144211Y+090513X0160Y    R180 S0      
317GND              VIA   -    MD0080PA00X+144396Y+090195X0160Y    R180 S0      
317GND              VIA   -    MD0080PA00X+144766Y+090195X0160Y    R180 S0      
317GND              VIA   -    MD0080PA00X+144026Y+090195X0160Y    R180 S0      
317GND              VIA   -    MD0080PA00X+144211Y+089876X0160Y    R180 S0      
317GND              VIA   -    MD0080PA00X+145321Y+089238X0160Y    R180 S0      
317GND              VIA   -    MD0080PA00X+145136Y+088919X0160Y    R180 S0      
317GND              VIA   -    MD0080PA00X+145136Y+088281X0160Y    R180 S0      
317GND              VIA   -    MD0080PA00X+144396Y+089557X0160Y    R180 S0      
317GND              VIA   -    MD0080PA00X+144211Y+089238X0160Y    R180 S0      
317GND              VIA   -    MD0080PA00X+144766Y+088919X0160Y    R180 S0      
317GND              VIA   -    MD0080PA00X+144026Y+088919X0160Y    R180 S0      
317GND              VIA   -    MD0080PA00X+144766Y+088281X0160Y    R180 S0      
317GND              VIA   -    MD0080PA00X+144396Y+088281X0160Y    R180 S0      
317GND              VIA   -    MD0080PA00X+145321Y+095616X0160Y    R180 S0      
317GND              VIA   -    MD0080PA00X+145321Y+094978X0160Y    R180 S0      
317GND              VIA   -    MD0080PA00X+145321Y+094340X0160Y    R180 S0      
317GND              VIA   -    MD0080PA00X+145136Y+094659X0160Y    R180 S0      
317GND              VIA   -    MD0080PA00X+144211Y+095616X0160Y    R180 S0      
317GND              VIA   -    MD0080PA00X+144396Y+095297X0160Y    R180 S0      
317GND              VIA   -    MD0080PA00X+144396Y+094659X0160Y    R180 S0      
317GND              VIA   -    MD0080PA00X+144211Y+094978X0160Y    R180 S0      
317GND              VIA   -    MD0080PA00X+144026Y+094659X0160Y    R180 S0      
317GND              VIA   -    MD0080PA00X+144211Y+094340X0160Y    R180 S0      
317GND              VIA   -    MD0080PA00X+144766Y+094659X0160Y    R180 S0      
317GND              VIA   -    MD0080PA00X+145136Y+092746X0160Y    R180 S0      
317GND              VIA   -    MD0080PA00X+145321Y+093065X0160Y    R180 S0      
317GND              VIA   -    MD0080PA00X+144396Y+094021X0160Y    R180 S0      
317GND              VIA   -    MD0080PA00X+144211Y+093702X0160Y    R180 S0      
317GND              VIA   -    MD0080PA00X+144396Y+093384X0160Y    R180 S0      
317GND              VIA   -    MD0080PA00X+144026Y+093384X0160Y    R180 S0      
317GND              VIA   -    MD0080PA00X+144766Y+092746X0160Y    R180 S0      
317GND              VIA   -    MD0080PA00X+144396Y+092746X0160Y    R180 S0      
317GND              VIA   -    MD0080PA00X+144026Y+092746X0160Y    R180 S0      
317GND              VIA   -    MD0080PA00X+145321Y+092427X0160Y    R180 S0      
317GND              VIA   -    MD0080PA00X+145321Y+091789X0160Y    R180 S0      
317GND              VIA   -    MD0080PA00X+145136Y+091470X0160Y    R180 S0      
317GND              VIA   -    MD0080PA00X+144211Y+092427X0160Y    R180 S0      
317GND              VIA   -    MD0080PA00X+144396Y+092108X0160Y    R180 S0      
317GND              VIA   -    MD0080PA00X+144211Y+091789X0160Y    R180 S0      
317GND              VIA   -    MD0080PA00X+144766Y+091470X0160Y    R180 S0      
317GND              VIA   -    MD0080PA00X+144396Y+091470X0160Y    R180 S0      
317GND              VIA   -    MD0080PA00X+144026Y+091470X0160Y    R180 S0      
317GND              VIA   -    MD0080PA00X+144397Y+099761X0160Y    R180 S0      
317GND              VIA   -    MD0080PA00X+145321Y+100080X0160Y    R180 S0      
317GND              VIA   -    MD0080PA00X+145136Y+099124X0160Y    R180 S0      
317GND              VIA   -    MD0080PA00X+145321Y+099443X0160Y    R180 S0      
317GND              VIA   -    MD0080PA00X+145321Y+098805X0160Y    R180 S0      
317GND              VIA   -    MD0080PA00X+144396Y+099124X0160Y    R180 S0      
317GND              VIA   -    MD0080PA00X+144581Y+098805X0160Y    R180 S0      
317GND              VIA   -    MD0080PA00X+145136Y+098486X0160Y    R180 S0      
317GND              VIA   -    MD0080PA00X+145321Y+097529X0160Y    R180 S0      
317GND              VIA   -    MD0080PA00X+145136Y+097210X0160Y    R180 S0      
317GND              VIA   -    MD0080PA00X+145321Y+098167X0160Y    R180 S0      
317GND              VIA   -    MD0080PA00X+144396Y+098486X0160Y    R180 S0      
317GND              VIA   -    MD0080PA00X+144026Y+097210X0160Y    R180 S0      
317GND              VIA   -    MD0080PA00X+144211Y+097529X0160Y    R180 S0      
317GND              VIA   -    MD0080PA00X+144766Y+097210X0160Y    R180 S0      
317GND              VIA   -    MD0080PA00X+144396Y+097210X0160Y    R180 S0      
317GND              VIA   -    MD0080PA00X+144396Y+097848X0160Y    R180 S0      
317GND              VIA   -    MD0080PA00X+144581Y+098167X0160Y    R180 S0      
317GND              VIA   -    MD0080PA00X+145321Y+096891X0160Y    R180 S0      
317GND              VIA   -    MD0080PA00X+145321Y+096254X0160Y    R180 S0      
317GND              VIA   -    MD0080PA00X+145136Y+095935X0160Y    R180 S0      
317GND              VIA   -    MD0080PA00X+144211Y+096891X0160Y    R180 S0      
317GND              VIA   -    MD0080PA00X+144211Y+096254X0160Y    R180 S0      
317GND              VIA   -    MD0080PA00X+144396Y+096572X0160Y    R180 S0      
317GND              VIA   -    MD0080PA00X+144766Y+095935X0160Y    R180 S0      
317GND              VIA   -    MD0080PA00X+144396Y+095935X0160Y    R180 S0      
317GND              VIA   -    MD0080PA00X+144026Y+095935X0160Y    R180 S0      
317GND              VIA   -    MD0080PA00X+145254Y+106632X0160Y         S0      
317GND              VIA   -    MD0080PA00X+144144Y+106632X0160Y         S0      
317GND              VIA   -    MD0080PA00X+144514Y+106632X0160Y         S0      
317GND              VIA   -    MD0080PA00X+144884Y+106632X0160Y         S0      
317GND              VIA   -    MD0080PA00X+144329Y+106951X0160Y         S0      
317GND              VIA   -    MD0080PA00X+144514Y+107270X0160Y         S0      
317GND              VIA   -    MD0080PA00X+144329Y+106313X0160Y         S0      
317GND              VIA   -    MD0080PA00X+145254Y+105357X0160Y         S0      
317GND              VIA   -    MD0080PA00X+145254Y+104719X0160Y         S0      
317GND              VIA   -    MD0080PA00X+144699Y+105038X0160Y         S0      
317GND              VIA   -    MD0080PA00X+143959Y+105038X0160Y         S0      
317GND              VIA   -    MD0080PA00X+144514Y+105357X0160Y         S0      
317GND              VIA   -    MD0080PA00X+143959Y+105676X0160Y         S0      
317GND              VIA   -    MD0080PA00X+144514Y+105994X0160Y         S0      
317GND              VIA   -    MD0080PA00X+144699Y+105676X0160Y         S0      
317GND              VIA   -    MD0080PA00X+144514Y+104719X0160Y         S0      
317GND              VIA   -    MD0080PA00X+144515Y+104082X0160Y         S0      
317GND              VIA   -    MD0080PA00X+145254Y+104082X0160Y         S0      
317GND              VIA   -    MD0080PA00X+145321Y+100718X0160Y    R180 S0      
317GND              VIA   -    MD0080PA00X+145254Y+107908X0160Y         S0      
317GND              VIA   -    MD0080PA00X+144329Y+108227X0160Y         S0      
317GND              VIA   -    MD0080PA00X+144514Y+108546X0160Y         S0      
317GND              VIA   -    MD0080PA00X+144329Y+108865X0160Y         S0      
317GND              VIA   -    MD0080PA00X+144329Y+107589X0160Y         S0      
317GND              VIA   -    MD0080PA00X+144144Y+107908X0160Y         S0      
317GND              VIA   -    MD0080PA00X+144884Y+107908X0160Y         S0      
317GND              VIA   -    MD0080PA00X+144514Y+107908X0160Y         S0      
317GND              VIA   -    MD0080PA00X+145254Y+111097X0160Y         S0      
317GND              VIA   -    MD0080PA00X+144329Y+111416X0160Y         S0      
317GND              VIA   -    MD0080PA00X+144514Y+111735X0160Y         S0      
317GND              VIA   -    MD0080PA00X+144329Y+110778X0160Y         S0      
317GND              VIA   -    MD0080PA00X+144514Y+111097X0160Y         S0      
317GND              VIA   -    MD0080PA00X+144884Y+111097X0160Y         S0      
317GND              VIA   -    MD0080PA00X+144144Y+111097X0160Y         S0      
317GND              VIA   -    MD0080PA00X+145254Y+109184X0160Y         S0      
317GND              VIA   -    MD0080PA00X+144144Y+110459X0160Y         S0      
317GND              VIA   -    MD0080PA00X+144514Y+109821X0160Y         S0      
317GND              VIA   -    MD0080PA00X+144329Y+110140X0160Y         S0      
317GND              VIA   -    MD0080PA00X+144514Y+110459X0160Y         S0      
317GND              VIA   -    MD0080PA00X+144329Y+109502X0160Y         S0      
317GND              VIA   -    MD0080PA00X+144514Y+109184X0160Y         S0      
317GND              VIA   -    MD0080PA00X+144884Y+109184X0160Y         S0      
317GND              VIA   -    MD0080PA00X+144144Y+109184X0160Y         S0      
317GND              VIA   -    MD0080PA00X+144144Y+113648X0160Y         S0      
317GND              VIA   -    MD0080PA00X+144884Y+113648X0160Y         S0      
317GND              VIA   -    MD0080PA00X+144514Y+113648X0160Y         S0      
317GND              VIA   -    MD0080PA00X+144329Y+113967X0160Y         S0      
317GND              VIA   -    MD0080PA00X+144514Y+114286X0160Y         S0      
317GND              VIA   -    MD0080PA00X+145254Y+112372X0160Y         S0      
317GND              VIA   -    MD0080PA00X+144514Y+113010X0160Y         S0      
317GND              VIA   -    MD0080PA00X+144329Y+113329X0160Y         S0      
317GND              VIA   -    MD0080PA00X+144329Y+112691X0160Y         S0      
317GND              VIA   -    MD0080PA00X+144144Y+112372X0160Y         S0      
317GND              VIA   -    MD0080PA00X+144329Y+112054X0160Y         S0      
317GND              VIA   -    MD0080PA00X+144884Y+112372X0160Y         S0      
317GND              VIA   -    MD0080PA00X+144514Y+112372X0160Y         S0      
317GND              VIA   -    MD0080PA00X+144144Y+115561X0160Y         S0      
317GND              VIA   -    MD0080PA00X+145069Y+115242X0160Y         S0      
317GND              VIA   -    MD0080PA00X+144699Y+115880X0160Y         S0      
317GND              VIA   -    MD0080PA00X+145254Y+114924X0160Y         S0      
317GND              VIA   -    MD0080PA00X+145254Y+113648X0160Y         S0      
317GND              VIA   -    MD0080PA00X+144144Y+114924X0160Y         S0      
317GND              VIA   -    MD0080PA00X+144329Y+114605X0160Y         S0      
317GND              VIA   -    MD0080PA00X+144884Y+114924X0160Y         S0      
317GND              VIA   -    MD0080PA00X+146246Y+088919X0160Y    R180 S0      
317GND              VIA   -    MD0080PA00X+146616Y+089557X0160Y    R180 S0      
317GND              VIA   -    MD0080PA00X+146431Y+089238X0160Y    R180 S0      
317GND              VIA   -    MD0080PA00X+145506Y+089557X0160Y    R180 S0      
317GND              VIA   -    MD0080PA00X+145876Y+088919X0160Y    R180 S0      
317GND              VIA   -    MD0080PA00X+145876Y+088281X0160Y    R180 S0      
317GND              VIA   -    MD0080PA00X+146616Y+088281X0160Y    R180 S0      
317GND              VIA   -    MD0080PA00X+146246Y+088281X0160Y    R180 S0      
317GND              VIA   -    MD0080PA00X+145506Y+088281X0160Y    R180 S0      
317GND              VIA   -    MD0080PA00X+146801Y+087962X0160Y    R180 S0      
317GND              VIA   -    MD0080PA00X+145876Y+087643X0160Y    R180 S0      
317GND              VIA   -    MD0080PA00X+145691Y+087962X0160Y    R180 S0      
317GND              VIA   -    MD0080PA00X+145691Y+087324X0160Y    R180 S0      
317GND              VIA   -    MD0080PA00X+146616Y+091470X0160Y    R180 S0      
317GND              VIA   -    MD0080PA00X+146246Y+091470X0160Y    R180 S0      
317GND              VIA   -    MD0080PA00X+145506Y+091470X0160Y    R180 S0      
317GND              VIA   -    MD0080PA00X+146431Y+091151X0160Y    R180 S0      
317GND              VIA   -    MD0080PA00X+145506Y+090832X0160Y    R180 S0      
317GND              VIA   -    MD0080PA00X+146431Y+090513X0160Y    R180 S0      
317GND              VIA   -    MD0080PA00X+146246Y+090195X0160Y    R180 S0      
317GND              VIA   -    MD0080PA00X+146616Y+090195X0160Y    R180 S0      
317GND              VIA   -    MD0080PA00X+145876Y+090195X0160Y    R180 S0      
317GND              VIA   -    MD0080PA00X+145506Y+090195X0160Y    R180 S0      
317GND              VIA   -    MD0080PA00X+146431Y+089876X0160Y    R180 S0      
317GND              VIA   -    MD0080PA00X+146431Y+094978X0160Y    R180 S0      
317GND              VIA   -    MD0080PA00X+145506Y+094659X0160Y    R180 S0      
317GND              VIA   -    MD0080PA00X+146431Y+094340X0160Y    R180 S0      
317GND              VIA   -    MD0080PA00X+146616Y+094021X0160Y    R180 S0      
317GND              VIA   -    MD0080PA00X+145506Y+094021X0160Y    R180 S0      
317GND              VIA   -    MD0080PA00X+145876Y+093384X0160Y    R180 S0      
317GND              VIA   -    MD0080PA00X+146616Y+093384X0160Y    R180 S0      
317GND              VIA   -    MD0080PA00X+146246Y+093384X0160Y    R180 S0      
317GND              VIA   -    MD0080PA00X+146431Y+093065X0160Y    R180 S0      
317GND              VIA   -    MD0080PA00X+145506Y+093384X0160Y    R180 S0      
317GND              VIA   -    MD0080PA00X+146246Y+092746X0160Y    R180 S0      
317GND              VIA   -    MD0080PA00X+146616Y+092746X0160Y    R180 S0      
317GND              VIA   -    MD0080PA00X+145876Y+092746X0160Y    R180 S0      
317GND              VIA   -    MD0080PA00X+145506Y+092746X0160Y    R180 S0      
317GND              VIA   -    MD0080PA00X+146616Y+092108X0160Y    R180 S0      
317GND              VIA   -    MD0080PA00X+145506Y+092108X0160Y    R180 S0      
317GND              VIA   -    MD0080PA00X+146431Y+092427X0160Y    R180 S0      
317GND              VIA   -    MD0080PA00X+146431Y+091789X0160Y    R180 S0      
317GND              VIA   -    MD0080PA00X+145876Y+091470X0160Y    R180 S0      
317GND              VIA   -    MD0080PA00X+146431Y+096891X0160Y    R180 S0      
317GND              VIA   -    MD0080PA00X+146431Y+096254X0160Y    R180 S0      
317GND              VIA   -    MD0080PA00X+145876Y+095935X0160Y    R180 S0      
317GND              VIA   -    MD0080PA00X+146616Y+095935X0160Y    R180 S0      
317GND              VIA   -    MD0080PA00X+146246Y+095935X0160Y    R180 S0      
317GND              VIA   -    MD0080PA00X+145506Y+095935X0160Y    R180 S0      
317GND              VIA   -    MD0080PA00X+146616Y+096572X0160Y    R180 S0      
317GND              VIA   -    MD0080PA00X+145506Y+096572X0160Y    R180 S0      
317GND              VIA   -    MD0080PA00X+145506Y+095297X0160Y    R180 S0      
317GND              VIA   -    MD0080PA00X+146431Y+095616X0160Y    R180 S0      
317GND              VIA   -    MD0080PA00X+146616Y+095297X0160Y    R180 S0      
317GND              VIA   -    MD0080PA00X+145876Y+094659X0160Y    R180 S0      
317GND              VIA   -    MD0080PA00X+146616Y+094659X0160Y    R180 S0      
317GND              VIA   -    MD0080PA00X+146246Y+094659X0160Y    R180 S0      
317GND              VIA   -    MD0080PA00X+146179Y+104400X0160Y         S0      
317GND              VIA   -    MD0080PA00X+146179Y+103762X0160Y         S0      
317GND              VIA   -    MD0080PA00X+145439Y+104400X0160Y         S0      
317GND              VIA   -    MD0080PA00X+145624Y+102806X0160Y         S0      
317GND              VIA   -    MD0080PA00X+146364Y+102806X0160Y         S0      
317GND              VIA   -    MD0080PA00X+146801Y+100718X0160Y    R180 S0      
317GND              VIA   -    MD0080PA00X+146061Y+100718X0160Y    R180 S0      
317GND              VIA   -    MD0080PA00X+145876Y+101037X0160Y    R180 S0      
317GND              VIA   -    MD0080PA00X+146616Y+101037X0160Y    R180 S0      
317GND              VIA   -    MD0080PA00X+146616Y+100399X0160Y    R180 S0      
317GND              VIA   -    MD0080PA00X+145876Y+100399X0160Y    R180 S0      
317GND              VIA   -    MD0080PA00X+146801Y+100080X0160Y    R180 S0      
317GND              VIA   -    MD0080PA00X+146801Y+099443X0160Y    R180 S0      
317GND              VIA   -    MD0080PA00X+146801Y+098805X0160Y    R180 S0      
317GND              VIA   -    MD0080PA00X+146061Y+100080X0160Y    R180 S0      
317GND              VIA   -    MD0080PA00X+146616Y+099124X0160Y    R180 S0      
317GND              VIA   -    MD0080PA00X+145876Y+099124X0160Y    R180 S0      
317GND              VIA   -    MD0080PA00X+146061Y+099443X0160Y    R180 S0      
317GND              VIA   -    MD0080PA00X+146061Y+098805X0160Y    R180 S0      
317GND              VIA   -    MD0080PA00X+146616Y+099762X0160Y    R180 S0      
317GND              VIA   -    MD0080PA00X+145876Y+099762X0160Y    R180 S0      
317GND              VIA   -    MD0080PA00X+146801Y+098167X0160Y    R180 S0      
317GND              VIA   -    MD0080PA00X+146616Y+098486X0160Y    R180 S0      
317GND              VIA   -    MD0080PA00X+145876Y+098486X0160Y    R180 S0      
317GND              VIA   -    MD0080PA00X+146431Y+097529X0160Y    R180 S0      
317GND              VIA   -    MD0080PA00X+145876Y+097210X0160Y    R180 S0      
317GND              VIA   -    MD0080PA00X+146616Y+097210X0160Y    R180 S0      
317GND              VIA   -    MD0080PA00X+146246Y+097210X0160Y    R180 S0      
317GND              VIA   -    MD0080PA00X+145506Y+097210X0160Y    R180 S0      
317GND              VIA   -    MD0080PA00X+146616Y+097848X0160Y    R180 S0      
317GND              VIA   -    MD0080PA00X+145506Y+097848X0160Y    R180 S0      
317GND              VIA   -    MD0080PA00X+146061Y+098167X0160Y    R180 S0      
317GND              VIA   -    MD0080PA00X+146734Y+106632X0160Y         S0      
317GND              VIA   -    MD0080PA00X+146734Y+107270X0160Y         S0      
317GND              VIA   -    MD0080PA00X+145624Y+106632X0160Y         S0      
317GND              VIA   -    MD0080PA00X+145439Y+106951X0160Y         S0      
317GND              VIA   -    MD0080PA00X+146549Y+106951X0160Y         S0      
317GND              VIA   -    MD0080PA00X+146364Y+106632X0160Y         S0      
317GND              VIA   -    MD0080PA00X+145994Y+106632X0160Y         S0      
317GND              VIA   -    MD0080PA00X+145624Y+107270X0160Y         S0      
317GND              VIA   -    MD0080PA00X+145439Y+106313X0160Y         S0      
317GND              VIA   -    MD0080PA00X+146549Y+106313X0160Y         S0      
317GND              VIA   -    MD0080PA00X+146734Y+105357X0160Y         S0      
317GND              VIA   -    MD0080PA00X+146734Y+105994X0160Y         S0      
317GND              VIA   -    MD0080PA00X+146734Y+104719X0160Y         S0      
317GND              VIA   -    MD0080PA00X+146179Y+105038X0160Y         S0      
317GND              VIA   -    MD0080PA00X+145439Y+105038X0160Y         S0      
317GND              VIA   -    MD0080PA00X+146179Y+105676X0160Y         S0      
317GND              VIA   -    MD0080PA00X+145439Y+105676X0160Y         S0      
317GND              VIA   -    MD0080PA00X+145994Y+105357X0160Y         S0      
317GND              VIA   -    MD0080PA00X+145624Y+105994X0160Y         S0      
317GND              VIA   -    MD0080PA00X+145994Y+104719X0160Y         S0      
317GND              VIA   -    MD0080PA00X+146734Y+104081X0160Y         S0      
317GND              VIA   -    MD0080PA00X+145439Y+103762X0160Y         S0      
317GND              VIA   -    MD0080PA00X+146549Y+103124X0160Y         S0      
317GND              VIA   -    MD0080PA00X+145624Y+103443X0160Y         S0      
317GND              VIA   -    MD0080PA00X+146364Y+103443X0160Y         S0      
317GND              VIA   -    MD0080PA00X+145809Y+103124X0160Y         S0      
317GND              VIA   -    MD0080PA00X+145994Y+104081X0160Y         S0      
317GND              VIA   -    MD0080PA00X+145624Y+110459X0160Y         S0      
317GND              VIA   -    MD0080PA00X+146364Y+110459X0160Y         S0      
317GND              VIA   -    MD0080PA00X+145994Y+110459X0160Y         S0      
317GND              VIA   -    MD0080PA00X+145439Y+109502X0160Y         S0      
317GND              VIA   -    MD0080PA00X+146549Y+109502X0160Y         S0      
317GND              VIA   -    MD0080PA00X+145624Y+109184X0160Y         S0      
317GND              VIA   -    MD0080PA00X+145994Y+109184X0160Y         S0      
317GND              VIA   -    MD0080PA00X+146364Y+109184X0160Y         S0      
317GND              VIA   -    MD0080PA00X+146734Y+108546X0160Y         S0      
317GND              VIA   -    MD0080PA00X+146734Y+107908X0160Y         S0      
317GND              VIA   -    MD0080PA00X+145439Y+108227X0160Y         S0      
317GND              VIA   -    MD0080PA00X+146549Y+108227X0160Y         S0      
317GND              VIA   -    MD0080PA00X+145624Y+108546X0160Y         S0      
317GND              VIA   -    MD0080PA00X+145439Y+108865X0160Y         S0      
317GND              VIA   -    MD0080PA00X+146549Y+108865X0160Y         S0      
317GND              VIA   -    MD0080PA00X+145439Y+107589X0160Y         S0      
317GND              VIA   -    MD0080PA00X+146549Y+107589X0160Y         S0      
317GND              VIA   -    MD0080PA00X+145624Y+107908X0160Y         S0      
317GND              VIA   -    MD0080PA00X+146364Y+107908X0160Y         S0      
317GND              VIA   -    MD0080PA00X+145994Y+107908X0160Y         S0      
317GND              VIA   -    MD0080PA00X+146734Y+111735X0160Y         S0      
317GND              VIA   -    MD0080PA00X+146734Y+111097X0160Y         S0      
317GND              VIA   -    MD0080PA00X+146549Y+111416X0160Y         S0      
317GND              VIA   -    MD0080PA00X+145439Y+111416X0160Y         S0      
317GND              VIA   -    MD0080PA00X+145624Y+111735X0160Y         S0      
317GND              VIA   -    MD0080PA00X+145624Y+111097X0160Y         S0      
317GND              VIA   -    MD0080PA00X+145994Y+111097X0160Y         S0      
317GND              VIA   -    MD0080PA00X+146364Y+111097X0160Y         S0      
317GND              VIA   -    MD0080PA00X+145439Y+110778X0160Y         S0      
317GND              VIA   -    MD0080PA00X+146549Y+110778X0160Y         S0      
317GND              VIA   -    MD0080PA00X+146734Y+109821X0160Y         S0      
317GND              VIA   -    MD0080PA00X+146734Y+110459X0160Y         S0      
317GND              VIA   -    MD0080PA00X+146734Y+109184X0160Y         S0      
317GND              VIA   -    MD0080PA00X+145624Y+109821X0160Y         S0      
317GND              VIA   -    MD0080PA00X+145809Y+115880X0160Y         S0      
317GND              VIA   -    MD0080PA00X+146179Y+115242X0160Y         S0      
317GND              VIA   -    MD0080PA00X+146364Y+115561X0160Y         S0      
317GND              VIA   -    MD0080PA00X+146734Y+114286X0160Y         S0      
317GND              VIA   -    MD0080PA00X+146734Y+113648X0160Y         S0      
317GND              VIA   -    MD0080PA00X+145439Y+114605X0160Y         S0      
317GND              VIA   -    MD0080PA00X+146364Y+114924X0160Y         S0      
317GND              VIA   -    MD0080PA00X+145994Y+114924X0160Y         S0      
317GND              VIA   -    MD0080PA00X+146549Y+114605X0160Y         S0      
317GND              VIA   -    MD0080PA00X+145624Y+113648X0160Y         S0      
317GND              VIA   -    MD0080PA00X+145439Y+113967X0160Y         S0      
317GND              VIA   -    MD0080PA00X+146364Y+113648X0160Y         S0      
317GND              VIA   -    MD0080PA00X+145994Y+113648X0160Y         S0      
317GND              VIA   -    MD0080PA00X+146549Y+113967X0160Y         S0      
317GND              VIA   -    MD0080PA00X+145624Y+114286X0160Y         S0      
317GND              VIA   -    MD0080PA00X+146734Y+113010X0160Y         S0      
317GND              VIA   -    MD0080PA00X+146734Y+112372X0160Y         S0      
317GND              VIA   -    MD0080PA00X+146549Y+113329X0160Y         S0      
317GND              VIA   -    MD0080PA00X+145624Y+113010X0160Y         S0      
317GND              VIA   -    MD0080PA00X+145439Y+113329X0160Y         S0      
317GND              VIA   -    MD0080PA00X+145624Y+112372X0160Y         S0      
317GND              VIA   -    MD0080PA00X+146549Y+112054X0160Y         S0      
317GND              VIA   -    MD0080PA00X+146364Y+112372X0160Y         S0      
317GND              VIA   -    MD0080PA00X+145994Y+112372X0160Y         S0      
317GND              VIA   -    MD0080PA00X+145439Y+112691X0160Y         S0      
317GND              VIA   -    MD0080PA00X+146549Y+112691X0160Y         S0      
317GND              VIA   -    MD0080PA00X+145439Y+112054X0160Y         S0      
317GND              VIA   -    MD0080PA00X+147911Y+087962X0160Y    R180 S0      
317GND              VIA   -    MD0080PA00X+146986Y+087643X0160Y    R180 S0      
317GND              VIA   -    MD0080PA00X+147911Y+087324X0160Y    R180 S0      
317GND              VIA   -    MD0080PA00X+147541Y+090513X0160Y    R180 S0      
317GND              VIA   -    MD0080PA00X+147541Y+091151X0160Y    R180 S0      
317GND              VIA   -    MD0080PA00X+147726Y+090832X0160Y    R180 S0      
317GND              VIA   -    MD0080PA00X+148281Y+091151X0160Y    R180 S0      
317GND              VIA   -    MD0080PA00X+148281Y+090513X0160Y    R180 S0      
317GND              VIA   -    MD0080PA00X+147356Y+090195X0160Y    R180 S0      
317GND              VIA   -    MD0080PA00X+147541Y+089876X0160Y    R180 S0      
317GND              VIA   -    MD0080PA00X+146986Y+090195X0160Y    R180 S0      
317GND              VIA   -    MD0080PA00X+148281Y+089876X0160Y    R180 S0      
317GND              VIA   -    MD0080PA00X+147726Y+089557X0160Y    R180 S0      
317GND              VIA   -    MD0080PA00X+147541Y+089238X0160Y    R180 S0      
317GND              VIA   -    MD0080PA00X+147356Y+088919X0160Y    R180 S0      
317GND              VIA   -    MD0080PA00X+146986Y+088919X0160Y    R180 S0      
317GND              VIA   -    MD0080PA00X+148281Y+089238X0160Y    R180 S0      
317GND              VIA   -    MD0080PA00X+147911Y+088600X0160Y    R180 S0      
317GND              VIA   -    MD0080PA00X+146986Y+088281X0160Y    R180 S0      
317GND              VIA   -    MD0080PA00X+148096Y+088281X0160Y    R180 S0      
317GND              VIA   -    MD0080PA00X+148281Y+088600X0160Y    R180 S0      
317GND              VIA   -    MD0080PA00X+147726Y+094021X0160Y    R180 S0      
317GND              VIA   -    MD0080PA00X+148281Y+093702X0160Y    R180 S0      
317GND              VIA   -    MD0080PA00X+146986Y+092746X0160Y    R180 S0      
317GND              VIA   -    MD0080PA00X+147356Y+092746X0160Y    R180 S0      
317GND              VIA   -    MD0080PA00X+147726Y+093384X0160Y    R180 S0      
317GND              VIA   -    MD0080PA00X+147541Y+093065X0160Y    R180 S0      
317GND              VIA   -    MD0080PA00X+148281Y+093065X0160Y    R180 S0      
317GND              VIA   -    MD0080PA00X+147356Y+093384X0160Y    R180 S0      
317GND              VIA   -    MD0080PA00X+146986Y+093384X0160Y    R180 S0      
317GND              VIA   -    MD0080PA00X+147726Y+092108X0160Y    R180 S0      
317GND              VIA   -    MD0080PA00X+148281Y+092427X0160Y    R180 S0      
317GND              VIA   -    MD0080PA00X+147541Y+092427X0160Y    R180 S0      
317GND              VIA   -    MD0080PA00X+147541Y+091789X0160Y    R180 S0      
317GND              VIA   -    MD0080PA00X+147356Y+091470X0160Y    R180 S0      
317GND              VIA   -    MD0080PA00X+146986Y+091470X0160Y    R180 S0      
317GND              VIA   -    MD0080PA00X+148281Y+091789X0160Y    R180 S0      
317GND              VIA   -    MD0080PA00X+147541Y+095616X0160Y    R180 S0      
317GND              VIA   -    MD0080PA00X+147726Y+095297X0160Y    R180 S0      
317GND              VIA   -    MD0080PA00X+148281Y+095616X0160Y    R180 S0      
317GND              VIA   -    MD0080PA00X+147541Y+094978X0160Y    R180 S0      
317GND              VIA   -    MD0080PA00X+147356Y+094659X0160Y    R180 S0      
317GND              VIA   -    MD0080PA00X+146986Y+094659X0160Y    R180 S0      
317GND              VIA   -    MD0080PA00X+147541Y+094340X0160Y    R180 S0      
317GND              VIA   -    MD0080PA00X+148281Y+094978X0160Y    R180 S0      
317GND              VIA   -    MD0080PA00X+148281Y+094340X0160Y    R180 S0      
317GND              VIA   -    MD0080PA00X+148281Y+100080X0160Y    R180 S0      
317GND              VIA   -    MD0080PA00X+147541Y+099443X0160Y    R180 S0      
317GND              VIA   -    MD0080PA00X+147541Y+098805X0160Y    R180 S0      
317GND              VIA   -    MD0080PA00X+147356Y+099762X0160Y    R180 S0      
317GND              VIA   -    MD0080PA00X+147356Y+099124X0160Y    R180 S0      
317GND              VIA   -    MD0080PA00X+148281Y+099443X0160Y    R180 S0      
317GND              VIA   -    MD0080PA00X+148281Y+098805X0160Y    R180 S0      
317GND              VIA   -    MD0080PA00X+147356Y+098486X0160Y    R180 S0      
317GND              VIA   -    MD0080PA00X+147541Y+098167X0160Y    R180 S0      
317GND              VIA   -    MD0080PA00X+147726Y+097848X0160Y    R180 S0      
317GND              VIA   -    MD0080PA00X+147541Y+097529X0160Y    R180 S0      
317GND              VIA   -    MD0080PA00X+147356Y+097210X0160Y    R180 S0      
317GND              VIA   -    MD0080PA00X+146986Y+097210X0160Y    R180 S0      
317GND              VIA   -    MD0080PA00X+148281Y+098167X0160Y    R180 S0      
317GND              VIA   -    MD0080PA00X+148281Y+097529X0160Y    R180 S0      
317GND              VIA   -    MD0080PA00X+147541Y+096891X0160Y    R180 S0      
317GND              VIA   -    MD0080PA00X+148281Y+096891X0160Y    R180 S0      
317GND              VIA   -    MD0080PA00X+147726Y+096572X0160Y    R180 S0      
317GND              VIA   -    MD0080PA00X+147541Y+096254X0160Y    R180 S0      
317GND              VIA   -    MD0080PA00X+147356Y+095935X0160Y    R180 S0      
317GND              VIA   -    MD0080PA00X+146986Y+095935X0160Y    R180 S0      
317GND              VIA   -    MD0080PA00X+148281Y+096254X0160Y    R180 S0      
317GND              VIA   -    MD0080PA00X+147104Y+103443X0160Y         S0      
317GND              VIA   -    MD0080PA00X+147659Y+104400X0160Y         S0      
317GND              VIA   -    MD0080PA00X+147474Y+104081X0160Y         S0      
317GND              VIA   -    MD0080PA00X+147659Y+103762X0160Y         S0      
317GND              VIA   -    MD0080PA00X+147844Y+103443X0160Y         S0      
317GND              VIA   -    MD0080PA00X+146919Y+104400X0160Y         S0      
317GND              VIA   -    MD0080PA00X+146919Y+103762X0160Y         S0      
317GND              VIA   -    MD0080PA00X+147289Y+103124X0160Y         S0      
317GND              VIA   -    MD0080PA00X+147104Y+102806X0160Y         S0      
317GND              VIA   -    MD0080PA00X+147844Y+102806X0160Y         S0      
317GND              VIA   -    MD0080PA00X+147541Y+100718X0160Y    R180 S0      
317GND              VIA   -    MD0080PA00X+147356Y+101037X0160Y    R180 S0      
317GND              VIA   -    MD0080PA00X+147356Y+100399X0160Y    R180 S0      
317GND              VIA   -    MD0080PA00X+148281Y+100718X0160Y    R180 S0      
317GND              VIA   -    MD0080PA00X+147541Y+100080X0160Y    R180 S0      
317GND              VIA   -    MD0080PA00X+147104Y+106632X0160Y         S0      
317GND              VIA   -    MD0080PA00X+147474Y+106632X0160Y         S0      
317GND              VIA   -    MD0080PA00X+147659Y+106951X0160Y         S0      
317GND              VIA   -    MD0080PA00X+147844Y+107270X0160Y         S0      
317GND              VIA   -    MD0080PA00X+147659Y+106313X0160Y         S0      
317GND              VIA   -    MD0080PA00X+146919Y+105676X0160Y         S0      
317GND              VIA   -    MD0080PA00X+147844Y+105994X0160Y         S0      
317GND              VIA   -    MD0080PA00X+147474Y+105357X0160Y         S0      
317GND              VIA   -    MD0080PA00X+147659Y+105676X0160Y         S0      
317GND              VIA   -    MD0080PA00X+147659Y+105038X0160Y         S0      
317GND              VIA   -    MD0080PA00X+146919Y+105038X0160Y         S0      
317GND              VIA   -    MD0080PA00X+148214Y+105994X0160Y         S0      
317GND              VIA   -    MD0080PA00X+148030Y+105676X0160Y         S0      
317GND              VIA   -    MD0080PA00X+147474Y+104719X0160Y         S0      
317GND              VIA   -    MD0080PA00X+147289Y+110140X0160Y         S0      
317GND              VIA   -    MD0080PA00X+147104Y+110459X0160Y         S0      
317GND              VIA   -    MD0080PA00X+147474Y+110459X0160Y         S0      
317GND              VIA   -    MD0080PA00X+147844Y+110459X0160Y         S0      
317GND              VIA   -    MD0080PA00X+147844Y+109821X0160Y         S0      
317GND              VIA   -    MD0080PA00X+147659Y+109502X0160Y         S0      
317GND              VIA   -    MD0080PA00X+147104Y+109184X0160Y         S0      
317GND              VIA   -    MD0080PA00X+147474Y+109184X0160Y         S0      
317GND              VIA   -    MD0080PA00X+147659Y+108227X0160Y         S0      
317GND              VIA   -    MD0080PA00X+147659Y+108865X0160Y         S0      
317GND              VIA   -    MD0080PA00X+147844Y+108546X0160Y         S0      
317GND              VIA   -    MD0080PA00X+147104Y+107908X0160Y         S0      
317GND              VIA   -    MD0080PA00X+147474Y+107908X0160Y         S0      
317GND              VIA   -    MD0080PA00X+147659Y+107589X0160Y         S0      
317GND              VIA   -    MD0080PA00X+147844Y+111735X0160Y         S0      
317GND              VIA   -    MD0080PA00X+147659Y+111416X0160Y         S0      
317GND              VIA   -    MD0080PA00X+147104Y+111097X0160Y         S0      
317GND              VIA   -    MD0080PA00X+147474Y+111097X0160Y         S0      
317GND              VIA   -    MD0080PA00X+147659Y+110778X0160Y         S0      
317GND              VIA   -    MD0080PA00X+147659Y+113329X0160Y         S0      
317GND              VIA   -    MD0080PA00X+147844Y+113010X0160Y         S0      
317GND              VIA   -    MD0080PA00X+147104Y+112372X0160Y         S0      
317GND              VIA   -    MD0080PA00X+147474Y+112372X0160Y         S0      
317GND              VIA   -    MD0080PA00X+147659Y+112054X0160Y         S0      
317GND              VIA   -    MD0080PA00X+147659Y+112691X0160Y         S0      
317GND              VIA   -    MD0080PA00X+146919Y+115880X0160Y         S0      
317GND              VIA   -    MD0080PA00X+148030Y+115880X0160Y         S0      
317GND              VIA   -    MD0080PA00X+147289Y+115242X0160Y         S0      
317GND              VIA   -    MD0080PA00X+147844Y+115561X0160Y         S0      
317GND              VIA   -    MD0080PA00X+147474Y+115561X0160Y         S0      
317GND              VIA   -    MD0080PA00X+147104Y+114924X0160Y         S0      
317GND              VIA   -    MD0080PA00X+147474Y+114924X0160Y         S0      
317GND              VIA   -    MD0080PA00X+147659Y+114605X0160Y         S0      
317GND              VIA   -    MD0080PA00X+147844Y+114286X0160Y         S0      
317GND              VIA   -    MD0080PA00X+147104Y+113648X0160Y         S0      
317GND              VIA   -    MD0080PA00X+147474Y+113648X0160Y         S0      
317GND              VIA   -    MD0080PA00X+147659Y+113967X0160Y         S0      
317GND              VIA   -    MD0080PA00X+149207Y+087643X0160Y    R180 S0      
317GND              VIA   -    MD0080PA00X+149577Y+089557X0160Y    R180 S0      
317GND              VIA   -    MD0080PA00X+149022Y+089238X0160Y    R180 S0      
317GND              VIA   -    MD0080PA00X+149577Y+088919X0160Y    R180 S0      
317GND              VIA   -    MD0080PA00X+148836Y+088919X0160Y    R180 S0      
317GND              VIA   -    MD0080PA00X+149392Y+088600X0160Y    R180 S0      
317GND              VIA   -    MD0080PA00X+149577Y+088281X0160Y    R180 S0      
317GND              VIA   -    MD0080PA00X+148836Y+088281X0160Y    R180 S0      
317GND              VIA   -    MD0080PA00X+148466Y+088281X0160Y    R180 S0      
317GND              VIA   -    MD0080PA00X+149022Y+088600X0160Y    R180 S0      
317GND              VIA   -    MD0080PA00X+149577Y+090832X0160Y    R180 S0      
317GND              VIA   -    MD0080PA00X+149022Y+091151X0160Y    R180 S0      
317GND              VIA   -    MD0080PA00X+148836Y+090832X0160Y    R180 S0      
317GND              VIA   -    MD0080PA00X+149577Y+090195X0160Y    R180 S0      
317GND              VIA   -    MD0080PA00X+148836Y+090195X0160Y    R180 S0      
317GND              VIA   -    MD0080PA00X+149022Y+089876X0160Y    R180 S0      
317GND              VIA   -    MD0080PA00X+149022Y+093702X0160Y    R180 S0      
317GND              VIA   -    MD0080PA00X+149577Y+094021X0160Y    R180 S0      
317GND              VIA   -    MD0080PA00X+148836Y+094021X0160Y    R180 S0      
317GND              VIA   -    MD0080PA00X+149577Y+092746X0160Y    R180 S0      
317GND              VIA   -    MD0080PA00X+148836Y+092746X0160Y    R180 S0      
317GND              VIA   -    MD0080PA00X+149577Y+093384X0160Y    R180 S0      
317GND              VIA   -    MD0080PA00X+149022Y+093065X0160Y    R180 S0      
317GND              VIA   -    MD0080PA00X+149577Y+092108X0160Y    R180 S0      
317GND              VIA   -    MD0080PA00X+148836Y+092108X0160Y    R180 S0      
317GND              VIA   -    MD0080PA00X+149022Y+091789X0160Y    R180 S0      
317GND              VIA   -    MD0080PA00X+149577Y+091470X0160Y    R180 S0      
317GND              VIA   -    MD0080PA00X+149022Y+095616X0160Y    R180 S0      
317GND              VIA   -    MD0080PA00X+149577Y+095297X0160Y    R180 S0      
317GND              VIA   -    MD0080PA00X+149577Y+094659X0160Y    R180 S0      
317GND              VIA   -    MD0080PA00X+149022Y+094978X0160Y    R180 S0      
317GND              VIA   -    MD0080PA00X+148836Y+094659X0160Y    R180 S0      
317GND              VIA   -    MD0080PA00X+149022Y+096891X0160Y    R180 S0      
317GND              VIA   -    MD0080PA00X+148836Y+095935X0160Y    R180 S0      
317GND              VIA   -    MD0080PA00X+149577Y+096572X0160Y    R180 S0      
317GND              VIA   -    MD0080PA00X+149577Y+095935X0160Y    R180 S0      
317GND              VIA   -    MD0080PA00X+148836Y+096572X0160Y    R180 S0      
317GND              VIA   -    MD0080PA00X+149577Y+098486X0160Y    R180 S0      
317GND              VIA   -    MD0080PA00X+148836Y+098486X0160Y    R180 S0      
317GND              VIA   -    MD0080PA00X+148466Y+098486X0160Y    R180 S0      
317GND              VIA   -    MD0080PA00X+149762Y+098167X0160Y    R180 S0      
317GND              VIA   -    MD0080PA00X+149577Y+097848X0160Y    R180 S0      
317GND              VIA   -    MD0080PA00X+148836Y+097848X0160Y    R180 S0      
317GND              VIA   -    MD0080PA00X+148652Y+098167X0160Y    R180 S0      
317GND              VIA   -    MD0080PA00X+149022Y+097529X0160Y    R180 S0      
317GND              VIA   -    MD0080PA00X+149577Y+097210X0160Y    R180 S0      
317GND              VIA   -    MD0080PA00X+149695Y+102806X0160Y         S0      
317GND              VIA   -    MD0080PA00X+148955Y+102806X0160Y         S0      
317GND              VIA   -    MD0080PA00X+149577Y+101037X0160Y    R180 S0      
317GND              VIA   -    MD0080PA00X+149577Y+100399X0160Y    R180 S0      
317GND              VIA   -    MD0080PA00X+149022Y+100718X0160Y    R180 S0      
317GND              VIA   -    MD0080PA00X+148836Y+100399X0160Y    R180 S0      
317GND              VIA   -    MD0080PA00X+149577Y+099762X0160Y    R180 S0      
317GND              VIA   -    MD0080PA00X+149577Y+099124X0160Y    R180 S0      
317GND              VIA   -    MD0080PA00X+149022Y+099443X0160Y    R180 S0      
317GND              VIA   -    MD0080PA00X+148836Y+099762X0160Y    R180 S0      
317GND              VIA   -    MD0080PA00X+149022Y+098805X0160Y    R180 S0      
317GND              VIA   -    MD0080PA00X+149695Y+105994X0160Y         S0      
317GND              VIA   -    MD0080PA00X+149695Y+105357X0160Y         S0      
317GND              VIA   -    MD0080PA00X+149325Y+105994X0160Y         S0      
317GND              VIA   -    MD0080PA00X+148955Y+105994X0160Y         S0      
317GND              VIA   -    MD0080PA00X+149140Y+105038X0160Y         S0      
317GND              VIA   -    MD0080PA00X+149510Y+105676X0160Y         S0      
317GND              VIA   -    MD0080PA00X+148955Y+105357X0160Y         S0      
317GND              VIA   -    MD0080PA00X+148400Y+105676X0160Y         S0      
317GND              VIA   -    MD0080PA00X+148400Y+105038X0160Y         S0      
317GND              VIA   -    MD0080PA00X+149695Y+104719X0160Y         S0      
317GND              VIA   -    MD0080PA00X+149695Y+104081X0160Y         S0      
317GND              VIA   -    MD0080PA00X+149695Y+103443X0160Y         S0      
317GND              VIA   -    MD0080PA00X+149140Y+104400X0160Y         S0      
317GND              VIA   -    MD0080PA00X+148955Y+103443X0160Y         S0      
317GND              VIA   -    MD0080PA00X+148955Y+104081X0160Y         S0      
317GND              VIA   -    MD0080PA00X+149140Y+103124X0160Y         S0      
317GND              VIA   -    MD0080PA00X+148400Y+104400X0160Y         S0      
317GND              VIA   -    MD0080PA00X+148400Y+103762X0160Y         S0      
317GND              VIA   -    MD0080PA00X+148400Y+103124X0160Y         S0      
317GND              VIA   -    MD0080PA00X+149695Y+106632X0160Y         S0      
317GND              VIA   -    MD0080PA00X+149695Y+107270X0160Y         S0      
317GND              VIA   -    MD0080PA00X+149140Y+106951X0160Y         S0      
317GND              VIA   -    MD0080PA00X+148955Y+107270X0160Y         S0      
317GND              VIA   -    MD0080PA00X+148400Y+106951X0160Y         S0      
317GND              VIA   -    MD0080PA00X+149140Y+106313X0160Y         S0      
317GND              VIA   -    MD0080PA00X+148400Y+106313X0160Y         S0      
317GND              VIA   -    MD0080PA00X+149140Y+108227X0160Y         S0      
317GND              VIA   -    MD0080PA00X+148400Y+108227X0160Y         S0      
317GND              VIA   -    MD0080PA00X+149695Y+108546X0160Y         S0      
317GND              VIA   -    MD0080PA00X+149140Y+108865X0160Y         S0      
317GND              VIA   -    MD0080PA00X+148400Y+108865X0160Y         S0      
317GND              VIA   -    MD0080PA00X+149695Y+107908X0160Y         S0      
317GND              VIA   -    MD0080PA00X+148955Y+107908X0160Y         S0      
317GND              VIA   -    MD0080PA00X+148400Y+107589X0160Y         S0      
317GND              VIA   -    MD0080PA00X+149695Y+110459X0160Y         S0      
317GND              VIA   -    MD0080PA00X+149695Y+109821X0160Y         S0      
317GND              VIA   -    MD0080PA00X+149140Y+110140X0160Y         S0      
317GND              VIA   -    MD0080PA00X+148955Y+109821X0160Y         S0      
317GND              VIA   -    MD0080PA00X+148400Y+110140X0160Y         S0      
317GND              VIA   -    MD0080PA00X+148400Y+109502X0160Y         S0      
317GND              VIA   -    MD0080PA00X+149695Y+109184X0160Y         S0      
317GND              VIA   -    MD0080PA00X+148955Y+109184X0160Y         S0      
317GND              VIA   -    MD0080PA00X+149695Y+111735X0160Y         S0      
317GND              VIA   -    MD0080PA00X+148955Y+111735X0160Y         S0      
317GND              VIA   -    MD0080PA00X+148400Y+111416X0160Y         S0      
317GND              VIA   -    MD0080PA00X+149140Y+110778X0160Y         S0      
317GND              VIA   -    MD0080PA00X+148400Y+110778X0160Y         S0      
317GND              VIA   -    MD0080PA00X+149695Y+111097X0160Y         S0      
317GND              VIA   -    MD0080PA00X+148955Y+111097X0160Y         S0      
317GND              VIA   -    MD0080PA00X+149695Y+113010X0160Y         S0      
317GND              VIA   -    MD0080PA00X+148400Y+113329X0160Y         S0      
317GND              VIA   -    MD0080PA00X+149140Y+112691X0160Y         S0      
317GND              VIA   -    MD0080PA00X+148400Y+112691X0160Y         S0      
317GND              VIA   -    MD0080PA00X+149695Y+112372X0160Y         S0      
317GND              VIA   -    MD0080PA00X+149140Y+112054X0160Y         S0      
317GND              VIA   -    MD0080PA00X+148400Y+112054X0160Y         S0      
317GND              VIA   -    MD0080PA00X+149881Y+116529X0160Y         S0      
317GND              VIA   -    MD0080PA00X+149141Y+116529X0160Y         S0      
317GND              VIA   -    MD0080PA00X+149511Y+116529X0160Y         S0      
317GND              VIA   -    MD0080PA00X+149325Y+116199X0160Y         S0      
317GND              VIA   -    MD0080PA00X+149140Y+115880X0160Y         S0      
317GND              VIA   -    MD0080PA00X+148400Y+115880X0160Y         S0      
317GND              VIA   -    MD0080PA00X+149695Y+115561X0160Y         S0      
317GND              VIA   -    MD0080PA00X+149325Y+115561X0160Y         S0      
317GND              VIA   -    MD0080PA00X+148955Y+115561X0160Y         S0      
317GND              VIA   -    MD0080PA00X+148585Y+115561X0160Y         S0      
317GND              VIA   -    MD0080PA00X+148400Y+115242X0160Y         S0      
317GND              VIA   -    MD0080PA00X+149880Y+115880X0160Y         S0      
317GND              VIA   -    MD0080PA00X+148770Y+116518X0160Y         S0      
317GND              VIA   -    MD0080PA00X+149695Y+114924X0160Y         S0      
317GND              VIA   -    MD0080PA00X+149140Y+114605X0160Y         S0      
317GND              VIA   -    MD0080PA00X+148955Y+114924X0160Y         S0      
317GND              VIA   -    MD0080PA00X+148400Y+114605X0160Y         S0      
317GND              VIA   -    MD0080PA00X+149695Y+114286X0160Y         S0      
317GND              VIA   -    MD0080PA00X+149695Y+113648X0160Y         S0      
317GND              VIA   -    MD0080PA00X+149140Y+113967X0160Y         S0      
317GND              VIA   -    MD0080PA00X+148955Y+113648X0160Y         S0      
317GND              VIA   -    MD0080PA00X+148400Y+113967X0160Y         S0      
317GND              VIA   -    MD0080PA00X+150502Y+088600X0160Y    R180 S0      
317GND              VIA   -    MD0080PA00X+149947Y+088281X0160Y    R180 S0      
317GND              VIA   -    MD0080PA00X+150872Y+087962X0160Y    R180 S0      
317GND              VIA   -    MD0080PA00X+151057Y+087643X0160Y    R180 S0      
317GND              VIA   -    MD0080PA00X+150132Y+087962X0160Y    R180 S0      
317GND              VIA   -    MD0080PA00X+150132Y+087324X0160Y    R180 S0      
317GND              VIA   -    MD0080PA00X+150872Y+092427X0160Y    R180 S0      
317GND              VIA   -    MD0080PA00X+150132Y+092427X0160Y    R180 S0      
317GND              VIA   -    MD0080PA00X+150317Y+092108X0160Y    R180 S0      
317GND              VIA   -    MD0080PA00X+150872Y+091789X0160Y    R180 S0      
317GND              VIA   -    MD0080PA00X+150132Y+091789X0160Y    R180 S0      
317GND              VIA   -    MD0080PA00X+150317Y+091470X0160Y    R180 S0      
317GND              VIA   -    MD0080PA00X+150872Y+091151X0160Y    R180 S0      
317GND              VIA   -    MD0080PA00X+150132Y+091151X0160Y    R180 S0      
317GND              VIA   -    MD0080PA00X+150872Y+090513X0160Y    R180 S0      
317GND              VIA   -    MD0080PA00X+150132Y+090513X0160Y    R180 S0      
317GND              VIA   -    MD0080PA00X+150317Y+090195X0160Y    R180 S0      
317GND              VIA   -    MD0080PA00X+150872Y+089876X0160Y    R180 S0      
317GND              VIA   -    MD0080PA00X+150132Y+089876X0160Y    R180 S0      
317GND              VIA   -    MD0080PA00X+150872Y+089238X0160Y    R180 S0      
317GND              VIA   -    MD0080PA00X+150132Y+089238X0160Y    R180 S0      
317GND              VIA   -    MD0080PA00X+150317Y+089557X0160Y    R180 S0      
317GND              VIA   -    MD0080PA00X+150317Y+088919X0160Y    R180 S0      
317GND              VIA   -    MD0080PA00X+150872Y+088600X0160Y    R180 S0      
317GND              VIA   -    MD0080PA00X+151057Y+088281X0160Y    R180 S0      
317GND              VIA   -    MD0080PA00X+150132Y+088600X0160Y    R180 S0      
317GND              VIA   -    MD0080PA00X+150132Y+093702X0160Y    R180 S0      
317GND              VIA   -    MD0080PA00X+150317Y+094021X0160Y    R180 S0      
317GND              VIA   -    MD0080PA00X+150872Y+093702X0160Y    R180 S0      
317GND              VIA   -    MD0080PA00X+150872Y+093065X0160Y    R180 S0      
317GND              VIA   -    MD0080PA00X+150317Y+093384X0160Y    R180 S0      
317GND              VIA   -    MD0080PA00X+150132Y+093065X0160Y    R180 S0      
317GND              VIA   -    MD0080PA00X+150317Y+092746X0160Y    R180 S0      
317GND              VIA   -    MD0080PA00X+150317Y+098486X0160Y    R180 S0      
317GND              VIA   -    MD0080PA00X+149947Y+098486X0160Y    R180 S0      
317GND              VIA   -    MD0080PA00X+150872Y+098167X0160Y    R180 S0      
317GND              VIA   -    MD0080PA00X+150872Y+097529X0160Y    R180 S0      
317GND              VIA   -    MD0080PA00X+150132Y+098167X0160Y    R180 S0      
317GND              VIA   -    MD0080PA00X+150317Y+097848X0160Y    R180 S0      
317GND              VIA   -    MD0080PA00X+150132Y+097529X0160Y    R180 S0      
317GND              VIA   -    MD0080PA00X+150317Y+097210X0160Y    R180 S0      
317GND              VIA   -    MD0080PA00X+151242Y+098167X0160Y    R180 S0      
317GND              VIA   -    MD0080PA00X+150872Y+096891X0160Y    R180 S0      
317GND              VIA   -    MD0080PA00X+150132Y+096891X0160Y    R180 S0      
317GND              VIA   -    MD0080PA00X+150872Y+096254X0160Y    R180 S0      
317GND              VIA   -    MD0080PA00X+150132Y+096254X0160Y    R180 S0      
317GND              VIA   -    MD0080PA00X+150317Y+096572X0160Y    R180 S0      
317GND              VIA   -    MD0080PA00X+150317Y+095935X0160Y    R180 S0      
317GND              VIA   -    MD0080PA00X+150872Y+095616X0160Y    R180 S0      
317GND              VIA   -    MD0080PA00X+150132Y+095616X0160Y    R180 S0      
317GND              VIA   -    MD0080PA00X+150317Y+095297X0160Y    R180 S0      
317GND              VIA   -    MD0080PA00X+150872Y+094978X0160Y    R180 S0      
317GND              VIA   -    MD0080PA00X+150132Y+094978X0160Y    R180 S0      
317GND              VIA   -    MD0080PA00X+150317Y+094659X0160Y    R180 S0      
317GND              VIA   -    MD0080PA00X+150872Y+094340X0160Y    R180 S0      
317GND              VIA   -    MD0080PA00X+150132Y+094340X0160Y    R180 S0      
317GND              VIA   -    MD0080PA00X+150435Y+102806X0160Y         S0      
317GND              VIA   -    MD0080PA00X+150317Y+100399X0160Y    R180 S0      
317GND              VIA   -    MD0080PA00X+150872Y+100718X0160Y    R180 S0      
317GND              VIA   -    MD0080PA00X+150317Y+101037X0160Y    R180 S0      
317GND              VIA   -    MD0080PA00X+150132Y+100718X0160Y    R180 S0      
317GND              VIA   -    MD0080PA00X+150872Y+100080X0160Y    R180 S0      
317GND              VIA   -    MD0080PA00X+150132Y+100080X0160Y    R180 S0      
317GND              VIA   -    MD0080PA00X+150872Y+099443X0160Y    R180 S0      
317GND              VIA   -    MD0080PA00X+150872Y+098805X0160Y    R180 S0      
317GND              VIA   -    MD0080PA00X+150132Y+099443X0160Y    R180 S0      
317GND              VIA   -    MD0080PA00X+150317Y+099762X0160Y    R180 S0      
317GND              VIA   -    MD0080PA00X+150132Y+098805X0160Y    R180 S0      
317GND              VIA   -    MD0080PA00X+150317Y+099124X0160Y    R180 S0      
317GND              VIA   -    MD0080PA00X+151057Y+098486X0160Y    R180 S0      
317GND              VIA   -    MD0080PA00X+150250Y+105676X0160Y         S0      
317GND              VIA   -    MD0080PA00X+150620Y+105676X0160Y         S0      
317GND              VIA   -    MD0080PA00X+150805Y+105994X0160Y         S0      
317GND              VIA   -    MD0080PA00X+150435Y+105994X0160Y         S0      
317GND              VIA   -    MD0080PA00X+150990Y+105038X0160Y         S0      
317GND              VIA   -    MD0080PA00X+150990Y+105676X0160Y         S0      
317GND              VIA   -    MD0080PA00X+150250Y+105038X0160Y         S0      
317GND              VIA   -    MD0080PA00X+150435Y+105357X0160Y         S0      
317GND              VIA   -    MD0080PA00X+150435Y+104719X0160Y         S0      
317GND              VIA   -    MD0080PA00X+150990Y+104400X0160Y         S0      
317GND              VIA   -    MD0080PA00X+150990Y+103762X0160Y         S0      
317GND              VIA   -    MD0080PA00X+150250Y+104400X0160Y         S0      
317GND              VIA   -    MD0080PA00X+150435Y+103443X0160Y         S0      
317GND              VIA   -    MD0080PA00X+150250Y+103762X0160Y         S0      
317GND              VIA   -    MD0080PA00X+150435Y+104081X0160Y         S0      
317GND              VIA   -    MD0080PA00X+150990Y+103124X0160Y         S0      
317GND              VIA   -    MD0080PA00X+150250Y+103124X0160Y         S0      
317GND              VIA   -    MD0080PA00X+150990Y+108227X0160Y         S0      
317GND              VIA   -    MD0080PA00X+150250Y+108227X0160Y         S0      
317GND              VIA   -    MD0080PA00X+150990Y+108865X0160Y         S0      
317GND              VIA   -    MD0080PA00X+150250Y+108865X0160Y         S0      
317GND              VIA   -    MD0080PA00X+150435Y+108546X0160Y         S0      
317GND              VIA   -    MD0080PA00X+150435Y+107908X0160Y         S0      
317GND              VIA   -    MD0080PA00X+150990Y+107589X0160Y         S0      
317GND              VIA   -    MD0080PA00X+150250Y+107589X0160Y         S0      
317GND              VIA   -    MD0080PA00X+150990Y+106951X0160Y         S0      
317GND              VIA   -    MD0080PA00X+150435Y+106632X0160Y         S0      
317GND              VIA   -    MD0080PA00X+150435Y+107270X0160Y         S0      
317GND              VIA   -    MD0080PA00X+150250Y+106951X0160Y         S0      
317GND              VIA   -    MD0080PA00X+150990Y+106313X0160Y         S0      
317GND              VIA   -    MD0080PA00X+150250Y+106313X0160Y         S0      
317GND              VIA   -    MD0080PA00X+150250Y+111416X0160Y         S0      
317GND              VIA   -    MD0080PA00X+150435Y+111735X0160Y         S0      
317GND              VIA   -    MD0080PA00X+150990Y+111416X0160Y         S0      
317GND              VIA   -    MD0080PA00X+150435Y+111097X0160Y         S0      
317GND              VIA   -    MD0080PA00X+150990Y+110778X0160Y         S0      
317GND              VIA   -    MD0080PA00X+150250Y+110778X0160Y         S0      
317GND              VIA   -    MD0080PA00X+150435Y+110459X0160Y         S0      
317GND              VIA   -    MD0080PA00X+150990Y+110140X0160Y         S0      
317GND              VIA   -    MD0080PA00X+150250Y+110140X0160Y         S0      
317GND              VIA   -    MD0080PA00X+150435Y+109821X0160Y         S0      
317GND              VIA   -    MD0080PA00X+150990Y+109502X0160Y         S0      
317GND              VIA   -    MD0080PA00X+150250Y+109502X0160Y         S0      
317GND              VIA   -    MD0080PA00X+150435Y+109184X0160Y         S0      
317GND              VIA   -    MD0080PA00X+150990Y+114605X0160Y         S0      
317GND              VIA   -    MD0080PA00X+150250Y+114605X0160Y         S0      
317GND              VIA   -    MD0080PA00X+150435Y+114924X0160Y         S0      
317GND              VIA   -    MD0080PA00X+150435Y+114286X0160Y         S0      
317GND              VIA   -    MD0080PA00X+150990Y+113967X0160Y         S0      
317GND              VIA   -    MD0080PA00X+150435Y+113648X0160Y         S0      
317GND              VIA   -    MD0080PA00X+150250Y+113967X0160Y         S0      
317GND              VIA   -    MD0080PA00X+150990Y+113329X0160Y         S0      
317GND              VIA   -    MD0080PA00X+150990Y+112691X0160Y         S0      
317GND              VIA   -    MD0080PA00X+150250Y+112691X0160Y         S0      
317GND              VIA   -    MD0080PA00X+150990Y+112054X0160Y         S0      
317GND              VIA   -    MD0080PA00X+150435Y+112372X0160Y         S0      
317GND              VIA   -    MD0080PA00X+150250Y+112054X0160Y         S0      
317GND              VIA   -    MD0080PA00X+150251Y+116529X0160Y    R180 S0      
317GND              VIA   -    MD0080PA00X+150621Y+116529X0160Y         S0      
317GND              VIA   -    MD0080PA00X+150991Y+116529X0160Y         S0      
317GND              VIA   -    MD0080PA00X+150990Y+115880X0160Y         S0      
317GND              VIA   -    MD0080PA00X+150620Y+115880X0160Y         S0      
317GND              VIA   -    MD0080PA00X+150250Y+115880X0160Y         S0      
317GND              VIA   -    MD0080PA00X+151175Y+115561X0160Y         S0      
317GND              VIA   -    MD0080PA00X+150990Y+115242X0160Y         S0      
317GND              VIA   -    MD0080PA00X+150250Y+115242X0160Y         S0      
317GND              VIA   -    MD0080PA00X+150435Y+115561X0160Y         S0      
317GND              VIA   -    MD0080PA00X+152352Y+087324X0160Y    R180 S0      
317GND              VIA   -    MD0080PA00X+151612Y+087962X0160Y    R180 S0      
317GND              VIA   -    MD0080PA00X+152722Y+087962X0160Y    R180 S0      
317GND              VIA   -    MD0080PA00X+151982Y+087962X0160Y    R180 S0      
317GND              VIA   -    MD0080PA00X+151797Y+087643X0160Y    R180 S0      
317GND              VIA   -    MD0080PA00X+152167Y+087643X0160Y    R180 S0      
317GND              VIA   -    MD0080PA00X+151612Y+091151X0160Y    R180 S0      
317GND              VIA   -    MD0080PA00X+152722Y+090513X0160Y    R180 S0      
317GND              VIA   -    MD0080PA00X+152722Y+091151X0160Y    R180 S0      
317GND              VIA   -    MD0080PA00X+151612Y+089876X0160Y    R180 S0      
317GND              VIA   -    MD0080PA00X+152722Y+089876X0160Y    R180 S0      
317GND              VIA   -    MD0080PA00X+152167Y+090195X0160Y    R180 S0      
317GND              VIA   -    MD0080PA00X+151427Y+090832X0160Y    R180 S0      
317GND              VIA   -    MD0080PA00X+151427Y+090195X0160Y    R180 S0      
317GND              VIA   -    MD0080PA00X+151612Y+089238X0160Y    R180 S0      
317GND              VIA   -    MD0080PA00X+152722Y+089238X0160Y    R180 S0      
317GND              VIA   -    MD0080PA00X+152167Y+089557X0160Y    R180 S0      
317GND              VIA   -    MD0080PA00X+152167Y+088919X0160Y    R180 S0      
317GND              VIA   -    MD0080PA00X+152722Y+088600X0160Y    R180 S0      
317GND              VIA   -    MD0080PA00X+152537Y+088281X0160Y    R180 S0      
317GND              VIA   -    MD0080PA00X+151982Y+088600X0160Y    R180 S0      
317GND              VIA   -    MD0080PA00X+152167Y+088281X0160Y    R180 S0      
317GND              VIA   -    MD0080PA00X+151427Y+088919X0160Y    R180 S0      
317GND              VIA   -    MD0080PA00X+151427Y+088281X0160Y    R180 S0      
317GND              VIA   -    MD0080PA00X+152167Y+094021X0160Y    R180 S0      
317GND              VIA   -    MD0080PA00X+152722Y+093702X0160Y    R180 S0      
317GND              VIA   -    MD0080PA00X+151612Y+093702X0160Y    R180 S0      
317GND              VIA   -    MD0080PA00X+152722Y+093065X0160Y    R180 S0      
317GND              VIA   -    MD0080PA00X+152167Y+093384X0160Y    R180 S0      
317GND              VIA   -    MD0080PA00X+152167Y+092746X0160Y    R180 S0      
317GND              VIA   -    MD0080PA00X+151612Y+093065X0160Y    R180 S0      
317GND              VIA   -    MD0080PA00X+151427Y+094021X0160Y    R180 S0      
317GND              VIA   -    MD0080PA00X+151427Y+092746X0160Y    R180 S0      
317GND              VIA   -    MD0080PA00X+152722Y+092427X0160Y    R180 S0      
317GND              VIA   -    MD0080PA00X+152167Y+092108X0160Y    R180 S0      
317GND              VIA   -    MD0080PA00X+151612Y+091789X0160Y    R180 S0      
317GND              VIA   -    MD0080PA00X+152722Y+091789X0160Y    R180 S0      
317GND              VIA   -    MD0080PA00X+152167Y+091470X0160Y    R180 S0      
317GND              VIA   -    MD0080PA00X+151427Y+092108X0160Y    R180 S0      
317GND              VIA   -    MD0080PA00X+151612Y+096891X0160Y    R180 S0      
317GND              VIA   -    MD0080PA00X+152722Y+096891X0160Y    R180 S0      
317GND              VIA   -    MD0080PA00X+152722Y+096254X0160Y    R180 S0      
317GND              VIA   -    MD0080PA00X+152167Y+096572X0160Y    R180 S0      
317GND              VIA   -    MD0080PA00X+152167Y+095935X0160Y    R180 S0      
317GND              VIA   -    MD0080PA00X+151427Y+096572X0160Y    R180 S0      
317GND              VIA   -    MD0080PA00X+151427Y+095935X0160Y    R180 S0      
317GND              VIA   -    MD0080PA00X+151612Y+095616X0160Y    R180 S0      
317GND              VIA   -    MD0080PA00X+152722Y+095616X0160Y    R180 S0      
317GND              VIA   -    MD0080PA00X+152167Y+095297X0160Y    R180 S0      
317GND              VIA   -    MD0080PA00X+152722Y+094978X0160Y    R180 S0      
317GND              VIA   -    MD0080PA00X+152722Y+094340X0160Y    R180 S0      
317GND              VIA   -    MD0080PA00X+152167Y+094659X0160Y    R180 S0      
317GND              VIA   -    MD0080PA00X+151612Y+094978X0160Y    R180 S0      
317GND              VIA   -    MD0080PA00X+151427Y+094659X0160Y    R180 S0      
317GND              VIA   -    MD0080PA00X+152722Y+100080X0160Y    R180 S0      
317GND              VIA   -    MD0080PA00X+151612Y+099443X0160Y    R180 S0      
317GND              VIA   -    MD0080PA00X+151612Y+098805X0160Y    R180 S0      
317GND              VIA   -    MD0080PA00X+152722Y+099443X0160Y    R180 S0      
317GND              VIA   -    MD0080PA00X+152722Y+098805X0160Y    R180 S0      
317GND              VIA   -    MD0080PA00X+152167Y+099762X0160Y    R180 S0      
317GND              VIA   -    MD0080PA00X+152167Y+099124X0160Y    R180 S0      
317GND              VIA   -    MD0080PA00X+151427Y+099762X0160Y    R180 S0      
317GND              VIA   -    MD0080PA00X+152537Y+098486X0160Y    R180 S0      
317GND              VIA   -    MD0080PA00X+152167Y+098486X0160Y    R180 S0      
317GND              VIA   -    MD0080PA00X+151612Y+097529X0160Y    R180 S0      
317GND              VIA   -    MD0080PA00X+152722Y+098167X0160Y    R180 S0      
317GND              VIA   -    MD0080PA00X+152722Y+097529X0160Y    R180 S0      
317GND              VIA   -    MD0080PA00X+152167Y+097848X0160Y    R180 S0      
317GND              VIA   -    MD0080PA00X+152352Y+098167X0160Y    R180 S0      
317GND              VIA   -    MD0080PA00X+152167Y+097210X0160Y    R180 S0      
317GND              VIA   -    MD0080PA00X+151427Y+098486X0160Y    R180 S0      
317GND              VIA   -    MD0080PA00X+151427Y+097848X0160Y    R180 S0      
317GND              VIA   -    MD0080PA00X+152840Y+105676X0160Y         S0      
317GND              VIA   -    MD0080PA00X+152840Y+105038X0160Y         S0      
317GND              VIA   -    MD0080PA00X+151915Y+105994X0160Y         S0      
317GND              VIA   -    MD0080PA00X+152285Y+105994X0160Y         S0      
317GND              VIA   -    MD0080PA00X+151730Y+105038X0160Y         S0      
317GND              VIA   -    MD0080PA00X+152100Y+105676X0160Y         S0      
317GND              VIA   -    MD0080PA00X+152285Y+105357X0160Y         S0      
317GND              VIA   -    MD0080PA00X+152285Y+104719X0160Y         S0      
317GND              VIA   -    MD0080PA00X+152840Y+103124X0160Y         S0      
317GND              VIA   -    MD0080PA00X+151730Y+103124X0160Y         S0      
317GND              VIA   -    MD0080PA00X+151545Y+103443X0160Y         S0      
317GND              VIA   -    MD0080PA00X+151545Y+104081X0160Y         S0      
317GND              VIA   -    MD0080PA00X+152840Y+104400X0160Y         S0      
317GND              VIA   -    MD0080PA00X+152840Y+103762X0160Y         S0      
317GND              VIA   -    MD0080PA00X+151730Y+104400X0160Y         S0      
317GND              VIA   -    MD0080PA00X+152285Y+104081X0160Y         S0      
317GND              VIA   -    MD0080PA00X+152285Y+103443X0160Y         S0      
317GND              VIA   -    MD0080PA00X+151545Y+102806X0160Y         S0      
317GND              VIA   -    MD0080PA00X+152285Y+102806X0160Y         S0      
317GND              VIA   -    MD0080PA00X+152722Y+100718X0160Y    R180 S0      
317GND              VIA   -    MD0080PA00X+152167Y+101037X0160Y    R180 S0      
317GND              VIA   -    MD0080PA00X+152167Y+100399X0160Y    R180 S0      
317GND              VIA   -    MD0080PA00X+151612Y+100718X0160Y    R180 S0      
317GND              VIA   -    MD0080PA00X+151427Y+100399X0160Y    R180 S0      
317GND              VIA   -    MD0080PA00X+152840Y+108865X0160Y         S0      
317GND              VIA   -    MD0080PA00X+151730Y+108865X0160Y         S0      
317GND              VIA   -    MD0080PA00X+152285Y+108546X0160Y         S0      
317GND              VIA   -    MD0080PA00X+152840Y+108227X0160Y         S0      
317GND              VIA   -    MD0080PA00X+151730Y+108227X0160Y         S0      
317GND              VIA   -    MD0080PA00X+152285Y+107908X0160Y         S0      
317GND              VIA   -    MD0080PA00X+151545Y+107908X0160Y         S0      
317GND              VIA   -    MD0080PA00X+152840Y+107589X0160Y         S0      
317GND              VIA   -    MD0080PA00X+152840Y+106951X0160Y         S0      
317GND              VIA   -    MD0080PA00X+151730Y+106951X0160Y         S0      
317GND              VIA   -    MD0080PA00X+152285Y+107270X0160Y         S0      
317GND              VIA   -    MD0080PA00X+152285Y+106632X0160Y         S0      
317GND              VIA   -    MD0080PA00X+151545Y+107270X0160Y         S0      
317GND              VIA   -    MD0080PA00X+152840Y+106313X0160Y         S0      
317GND              VIA   -    MD0080PA00X+151730Y+106313X0160Y         S0      
317GND              VIA   -    MD0080PA00X+151545Y+105994X0160Y         S0      
317GND              VIA   -    MD0080PA00X+151545Y+105357X0160Y         S0      
317GND              VIA   -    MD0080PA00X+151545Y+111735X0160Y         S0      
317GND              VIA   -    MD0080PA00X+152840Y+111416X0160Y         S0      
317GND              VIA   -    MD0080PA00X+152285Y+111735X0160Y         S0      
317GND              VIA   -    MD0080PA00X+151545Y+111097X0160Y         S0      
317GND              VIA   -    MD0080PA00X+152285Y+111097X0160Y         S0      
317GND              VIA   -    MD0080PA00X+152840Y+110778X0160Y         S0      
317GND              VIA   -    MD0080PA00X+151730Y+110778X0160Y         S0      
317GND              VIA   -    MD0080PA00X+151730Y+110140X0160Y         S0      
317GND              VIA   -    MD0080PA00X+152285Y+109821X0160Y         S0      
317GND              VIA   -    MD0080PA00X+151545Y+109821X0160Y         S0      
317GND              VIA   -    MD0080PA00X+152840Y+110140X0160Y         S0      
317GND              VIA   -    MD0080PA00X+152285Y+110459X0160Y         S0      
317GND              VIA   -    MD0080PA00X+152840Y+109502X0160Y         S0      
317GND              VIA   -    MD0080PA00X+152285Y+109184X0160Y         S0      
317GND              VIA   -    MD0080PA00X+151545Y+109184X0160Y         S0      
317GND              VIA   -    MD0080PA00X+151545Y+113010X0160Y         S0      
317GND              VIA   -    MD0080PA00X+152840Y+113329X0160Y         S0      
317GND              VIA   -    MD0080PA00X+152840Y+112691X0160Y         S0      
317GND              VIA   -    MD0080PA00X+151730Y+112691X0160Y         S0      
317GND              VIA   -    MD0080PA00X+152840Y+112054X0160Y         S0      
317GND              VIA   -    MD0080PA00X+151730Y+112054X0160Y         S0      
317GND              VIA   -    MD0080PA00X+152285Y+112372X0160Y         S0      
317GND              VIA   -    MD0080PA00X+151915Y+116199X0160Y         S0      
317GND              VIA   -    MD0080PA00X+152285Y+115561X0160Y         S0      
317GND              VIA   -    MD0080PA00X+151915Y+115561X0160Y         S0      
317GND              VIA   -    MD0080PA00X+151545Y+115561X0160Y         S0      
317GND              VIA   -    MD0080PA00X+152840Y+115880X0160Y         S0      
317GND              VIA   -    MD0080PA00X+152470Y+115880X0160Y         S0      
317GND              VIA   -    MD0080PA00X+152840Y+115242X0160Y         S0      
317GND              VIA   -    MD0080PA00X+151730Y+114605X0160Y         S0      
317GND              VIA   -    MD0080PA00X+152285Y+114924X0160Y         S0      
317GND              VIA   -    MD0080PA00X+151545Y+114924X0160Y         S0      
317GND              VIA   -    MD0080PA00X+152840Y+114605X0160Y         S0      
317GND              VIA   -    MD0080PA00X+151545Y+113648X0160Y         S0      
317GND              VIA   -    MD0080PA00X+152840Y+113967X0160Y         S0      
317GND              VIA   -    MD0080PA00X+151730Y+113967X0160Y         S0      
317GND              VIA   -    MD0080PA00X+152285Y+113648X0160Y         S0      
317GND              VIA   -    MD0080PA00X+152285Y+114286X0160Y         S0      
317GND              VIA   -    MD0080PA00X+153833Y+087962X0160Y    R180 S0      
317GND              VIA   -    MD0080PA00X+152907Y+087643X0160Y    R180 S0      
317GND              VIA   -    MD0080PA00X+153462Y+091151X0160Y    R180 S0      
317GND              VIA   -    MD0080PA00X+153462Y+090513X0160Y    R180 S0      
317GND              VIA   -    MD0080PA00X+154203Y+091151X0160Y    R180 S0      
317GND              VIA   -    MD0080PA00X+154018Y+090832X0160Y    R180 S0      
317GND              VIA   -    MD0080PA00X+153462Y+089876X0160Y    R180 S0      
317GND              VIA   -    MD0080PA00X+154018Y+090195X0160Y    R180 S0      
317GND              VIA   -    MD0080PA00X+154203Y+089876X0160Y    R180 S0      
317GND              VIA   -    MD0080PA00X+152907Y+090832X0160Y    R180 S0      
317GND              VIA   -    MD0080PA00X+152907Y+090195X0160Y    R180 S0      
317GND              VIA   -    MD0080PA00X+153462Y+089238X0160Y    R180 S0      
317GND              VIA   -    MD0080PA00X+154203Y+089238X0160Y    R180 S0      
317GND              VIA   -    MD0080PA00X+154018Y+088919X0160Y    R180 S0      
317GND              VIA   -    MD0080PA00X+153462Y+088600X0160Y    R180 S0      
317GND              VIA   -    MD0080PA00X+153648Y+088281X0160Y    R180 S0      
317GND              VIA   -    MD0080PA00X+154018Y+088281X0160Y    R180 S0      
317GND              VIA   -    MD0080PA00X+152907Y+089557X0160Y    R180 S0      
317GND              VIA   -    MD0080PA00X+152907Y+088919X0160Y    R180 S0      
317GND              VIA   -    MD0080PA00X+153092Y+088600X0160Y    R180 S0      
317GND              VIA   -    MD0080PA00X+153462Y+092427X0160Y    R180 S0      
317GND              VIA   -    MD0080PA00X+154018Y+092108X0160Y    R180 S0      
317GND              VIA   -    MD0080PA00X+153462Y+091789X0160Y    R180 S0      
317GND              VIA   -    MD0080PA00X+154203Y+091789X0160Y    R180 S0      
317GND              VIA   -    MD0080PA00X+152907Y+092108X0160Y    R180 S0      
317GND              VIA   -    MD0080PA00X+152907Y+091470X0160Y    R180 S0      
317GND              VIA   -    MD0080PA00X+154203Y+095616X0160Y    R180 S0      
317GND              VIA   -    MD0080PA00X+153462Y+095616X0160Y    R180 S0      
317GND              VIA   -    MD0080PA00X+153462Y+094978X0160Y    R180 S0      
317GND              VIA   -    MD0080PA00X+153462Y+094340X0160Y    R180 S0      
317GND              VIA   -    MD0080PA00X+154203Y+094978X0160Y    R180 S0      
317GND              VIA   -    MD0080PA00X+154018Y+094659X0160Y    R180 S0      
317GND              VIA   -    MD0080PA00X+152907Y+095297X0160Y    R180 S0      
317GND              VIA   -    MD0080PA00X+152907Y+094659X0160Y    R180 S0      
317GND              VIA   -    MD0080PA00X+153462Y+093702X0160Y    R180 S0      
317GND              VIA   -    MD0080PA00X+154018Y+094021X0160Y    R180 S0      
317GND              VIA   -    MD0080PA00X+154203Y+093702X0160Y    R180 S0      
317GND              VIA   -    MD0080PA00X+153462Y+093065X0160Y    R180 S0      
317GND              VIA   -    MD0080PA00X+154203Y+093065X0160Y    R180 S0      
317GND              VIA   -    MD0080PA00X+154018Y+092746X0160Y    R180 S0      
317GND              VIA   -    MD0080PA00X+152907Y+094021X0160Y    R180 S0      
317GND              VIA   -    MD0080PA00X+152907Y+093384X0160Y    R180 S0      
317GND              VIA   -    MD0080PA00X+152907Y+092746X0160Y    R180 S0      
317GND              VIA   -    MD0080PA00X+152907Y+098486X0160Y    R180 S0      
317GND              VIA   -    MD0080PA00X+152907Y+097848X0160Y    R180 S0      
317GND              VIA   -    MD0080PA00X+152907Y+097210X0160Y    R180 S0      
317GND              VIA   -    MD0080PA00X+153462Y+096891X0160Y    R180 S0      
317GND              VIA   -    MD0080PA00X+154203Y+096891X0160Y    R180 S0      
317GND              VIA   -    MD0080PA00X+153462Y+096254X0160Y    R180 S0      
317GND              VIA   -    MD0080PA00X+154018Y+096572X0160Y    R180 S0      
317GND              VIA   -    MD0080PA00X+154018Y+095935X0160Y    R180 S0      
317GND              VIA   -    MD0080PA00X+152907Y+096572X0160Y    R180 S0      
317GND              VIA   -    MD0080PA00X+152907Y+095935X0160Y    R180 S0      
317GND              VIA   -    MD0080PA00X+154018Y+100399X0160Y    R180 S0      
317GND              VIA   -    MD0080PA00X+152907Y+101037X0160Y    R180 S0      
317GND              VIA   -    MD0080PA00X+152907Y+100399X0160Y    R180 S0      
317GND              VIA   -    MD0080PA00X+153462Y+100080X0160Y    R180 S0      
317GND              VIA   -    MD0080PA00X+153462Y+099443X0160Y    R180 S0      
317GND              VIA   -    MD0080PA00X+153462Y+098805X0160Y    R180 S0      
317GND              VIA   -    MD0080PA00X+154203Y+099443X0160Y    R180 S0      
317GND              VIA   -    MD0080PA00X+154018Y+099762X0160Y    R180 S0      
317GND              VIA   -    MD0080PA00X+154203Y+098805X0160Y    R180 S0      
317GND              VIA   -    MD0080PA00X+152907Y+099762X0160Y    R180 S0      
317GND              VIA   -    MD0080PA00X+152907Y+099124X0160Y    R180 S0      
317GND              VIA   -    MD0080PA00X+154018Y+098486X0160Y    R180 S0      
317GND              VIA   -    MD0080PA00X+153648Y+098486X0160Y    R180 S0      
317GND              VIA   -    MD0080PA00X+153462Y+098167X0160Y    R180 S0      
317GND              VIA   -    MD0080PA00X+153462Y+097529X0160Y    R180 S0      
317GND              VIA   -    MD0080PA00X+154018Y+097848X0160Y    R180 S0      
317GND              VIA   -    MD0080PA00X+154203Y+097529X0160Y    R180 S0      
317GND              VIA   -    MD0080PA00X+153833Y+098167X0160Y    R180 S0      
317GND              VIA   -    MD0080PA00X+153581Y+104400X0160Y         S0      
317GND              VIA   -    MD0080PA00X+153581Y+103762X0160Y         S0      
317GND              VIA   -    MD0080PA00X+153581Y+103124X0160Y         S0      
317GND              VIA   -    MD0080PA00X+154321Y+104400X0160Y         S0      
317GND              VIA   -    MD0080PA00X+154321Y+103124X0160Y         S0      
317GND              VIA   -    MD0080PA00X+154136Y+103443X0160Y         S0      
317GND              VIA   -    MD0080PA00X+154136Y+104081X0160Y         S0      
317GND              VIA   -    MD0080PA00X+153026Y+104081X0160Y         S0      
317GND              VIA   -    MD0080PA00X+153026Y+103443X0160Y         S0      
317GND              VIA   -    MD0080PA00X+154136Y+102806X0160Y         S0      
317GND              VIA   -    MD0080PA00X+153026Y+102806X0160Y         S0      
317GND              VIA   -    MD0080PA00X+153462Y+100718X0160Y    R180 S0      
317GND              VIA   -    MD0080PA00X+154203Y+100718X0160Y    R180 S0      
317GND              VIA   -    MD0080PA00X+153581Y+106951X0160Y         S0      
317GND              VIA   -    MD0080PA00X+154136Y+107270X0160Y         S0      
317GND              VIA   -    MD0080PA00X+154321Y+106951X0160Y         S0      
317GND              VIA   -    MD0080PA00X+153581Y+106313X0160Y         S0      
317GND              VIA   -    MD0080PA00X+154321Y+106313X0160Y         S0      
317GND              VIA   -    MD0080PA00X+153026Y+107270X0160Y         S0      
317GND              VIA   -    MD0080PA00X+153026Y+106632X0160Y         S0      
317GND              VIA   -    MD0080PA00X+153396Y+105994X0160Y         S0      
317GND              VIA   -    MD0080PA00X+153581Y+105038X0160Y         S0      
317GND              VIA   -    MD0080PA00X+153581Y+105676X0160Y         S0      
317GND              VIA   -    MD0080PA00X+153211Y+105676X0160Y         S0      
317GND              VIA   -    MD0080PA00X+154321Y+105038X0160Y         S0      
317GND              VIA   -    MD0080PA00X+154136Y+105994X0160Y         S0      
317GND              VIA   -    MD0080PA00X+154136Y+105357X0160Y         S0      
317GND              VIA   -    MD0080PA00X+153026Y+105994X0160Y         S0      
317GND              VIA   -    MD0080PA00X+153026Y+105357X0160Y         S0      
317GND              VIA   -    MD0080PA00X+153026Y+104719X0160Y         S0      
317GND              VIA   -    MD0080PA00X+153026Y+109184X0160Y         S0      
317GND              VIA   -    MD0080PA00X+153581Y+108227X0160Y         S0      
317GND              VIA   -    MD0080PA00X+153581Y+108865X0160Y         S0      
317GND              VIA   -    MD0080PA00X+154321Y+108865X0160Y         S0      
317GND              VIA   -    MD0080PA00X+154321Y+108227X0160Y         S0      
317GND              VIA   -    MD0080PA00X+154136Y+107908X0160Y         S0      
317GND              VIA   -    MD0080PA00X+153581Y+107589X0160Y         S0      
317GND              VIA   -    MD0080PA00X+153026Y+108546X0160Y         S0      
317GND              VIA   -    MD0080PA00X+153026Y+107908X0160Y         S0      
317GND              VIA   -    MD0080PA00X+153581Y+111416X0160Y         S0      
317GND              VIA   -    MD0080PA00X+154136Y+111735X0160Y         S0      
317GND              VIA   -    MD0080PA00X+154136Y+111097X0160Y         S0      
317GND              VIA   -    MD0080PA00X+153581Y+110778X0160Y         S0      
317GND              VIA   -    MD0080PA00X+154321Y+110778X0160Y         S0      
317GND              VIA   -    MD0080PA00X+153026Y+111735X0160Y         S0      
317GND              VIA   -    MD0080PA00X+153026Y+111097X0160Y         S0      
317GND              VIA   -    MD0080PA00X+153581Y+110140X0160Y         S0      
317GND              VIA   -    MD0080PA00X+154136Y+109821X0160Y         S0      
317GND              VIA   -    MD0080PA00X+154321Y+110140X0160Y         S0      
317GND              VIA   -    MD0080PA00X+153581Y+109502X0160Y         S0      
317GND              VIA   -    MD0080PA00X+154136Y+109184X0160Y         S0      
317GND              VIA   -    MD0080PA00X+153026Y+110459X0160Y         S0      
317GND              VIA   -    MD0080PA00X+153026Y+109821X0160Y         S0      
317GND              VIA   -    MD0080PA00X+153581Y+113329X0160Y         S0      
317GND              VIA   -    MD0080PA00X+154136Y+113010X0160Y         S0      
317GND              VIA   -    MD0080PA00X+153581Y+112691X0160Y         S0      
317GND              VIA   -    MD0080PA00X+154321Y+112691X0160Y         S0      
317GND              VIA   -    MD0080PA00X+153581Y+112054X0160Y         S0      
317GND              VIA   -    MD0080PA00X+154321Y+112054X0160Y         S0      
317GND              VIA   -    MD0080PA00X+153026Y+113010X0160Y         S0      
317GND              VIA   -    MD0080PA00X+153026Y+112372X0160Y         S0      
317GND              VIA   -    MD0080PA00X+153211Y+116518X0160Y         S0      
317GND              VIA   -    MD0080PA00X+154136Y+116199X0160Y         S0      
317GND              VIA   -    MD0080PA00X+153581Y+115880X0160Y         S0      
317GND              VIA   -    MD0080PA00X+153211Y+115880X0160Y         S0      
317GND              VIA   -    MD0080PA00X+153581Y+115242X0160Y         S0      
317GND              VIA   -    MD0080PA00X+154136Y+115561X0160Y         S0      
317GND              VIA   -    MD0080PA00X+153766Y+115561X0160Y         S0      
317GND              VIA   -    MD0080PA00X+153026Y+115561X0160Y         S0      
317GND              VIA   -    MD0080PA00X+153581Y+114605X0160Y         S0      
317GND              VIA   -    MD0080PA00X+154136Y+114924X0160Y         S0      
317GND              VIA   -    MD0080PA00X+154321Y+114605X0160Y         S0      
317GND              VIA   -    MD0080PA00X+153581Y+113967X0160Y         S0      
317GND              VIA   -    MD0080PA00X+154321Y+113967X0160Y         S0      
317GND              VIA   -    MD0080PA00X+154136Y+113648X0160Y         S0      
317GND              VIA   -    MD0080PA00X+153026Y+114924X0160Y         S0      
317GND              VIA   -    MD0080PA00X+153026Y+113648X0160Y         S0      
317GND              VIA   -    MD0080PA00X+153026Y+114286X0160Y         S0      
317GND              VIA   -    MD0080PA00X+155387Y+096996X0160Y         S0      
317GND              VIA   -    MD0080PA00X+155387Y+096358X0160Y         S0      
317GND              VIA   -    MD0080PA00X+155387Y+095720X0160Y         S0      
317GND              VIA   -    MD0080PA00X+154758Y+096572X0160Y    R180 S0      
317GND              VIA   -    MD0080PA00X+154758Y+095935X0160Y    R180 S0      
317GND              VIA   -    MD0080PA00X+154758Y+095297X0160Y    R180 S0      
317GND              VIA   -    MD0080PA00X+155387Y+095083X0160Y         S0      
317GND              VIA   -    MD0080PA00X+155387Y+094445X0160Y         S0      
317GND              VIA   -    MD0080PA00X+154758Y+094659X0160Y    R180 S0      
317GND              VIA   -    MD0080PA00X+155387Y+093807X0160Y         S0      
317GND              VIA   -    MD0080PA00X+154758Y+094021X0160Y    R180 S0      
317GND              VIA   -    MD0080PA00X+155387Y+093169X0160Y         S0      
317GND              VIA   -    MD0080PA00X+154758Y+093384X0160Y    R180 S0      
317GND              VIA   -    MD0080PA00X+154758Y+092746X0160Y    R180 S0      
317GND              VIA   -    MD0080PA00X+155387Y+092532X0160Y         S0      
317GND              VIA   -    MD0080PA00X+154758Y+092108X0160Y    R180 S0      
317GND              VIA   -    MD0080PA00X+155387Y+091894X0160Y         S0      
317GND              VIA   -    MD0080PA00X+154758Y+091470X0160Y    R180 S0      
317GND              VIA   -    MD0080PA00X+155387Y+091256X0160Y         S0      
317GND              VIA   -    MD0080PA00X+155387Y+090618X0160Y         S0      
317GND              VIA   -    MD0080PA00X+154758Y+090832X0160Y    R180 S0      
317GND              VIA   -    MD0080PA00X+155313Y+089876X0160Y    R180 S0      
317GND              VIA   -    MD0080PA00X+154758Y+090195X0160Y    R180 S0      
317GND              VIA   -    MD0080PA00X+155313Y+089238X0160Y    R180 S0      
317GND              VIA   -    MD0080PA00X+154758Y+089557X0160Y    R180 S0      
317GND              VIA   -    MD0080PA00X+154758Y+088919X0160Y    R180 S0      
317GND              VIA   -    MD0080PA00X+155128Y+088281X0160Y    R180 S0      
317GND              VIA   -    MD0080PA00X+155313Y+088600X0160Y    R180 S0      
317GND              VIA   -    MD0080PA00X+154758Y+088281X0160Y    R180 S0      
317GND              VIA   -    MD0080PA00X+154573Y+088600X0160Y    R180 S0      
317GND              VIA   -    MD0080PA00X+155313Y+087962X0160Y    R180 S0      
317GND              VIA   -    MD0080PA00X+154573Y+087324X0160Y    R180 S0      
317GND              VIA   -    MD0080PA00X+154876Y+113010X0160Y         S0      
317GND              VIA   -    MD0080PA00X+155505Y+112587X0160Y         S0      
317GND              VIA   -    MD0080PA00X+154876Y+112372X0160Y         S0      
317GND              VIA   -    MD0080PA00X+155505Y+111949X0160Y         S0      
317GND              VIA   -    MD0080PA00X+154876Y+111735X0160Y         S0      
317GND              VIA   -    MD0080PA00X+155505Y+111311X0160Y         S0      
317GND              VIA   -    MD0080PA00X+154876Y+111097X0160Y         S0      
317GND              VIA   -    MD0080PA00X+155505Y+110673X0160Y         S0      
317GND              VIA   -    MD0080PA00X+155505Y+110036X0160Y         S0      
317GND              VIA   -    MD0080PA00X+154876Y+110459X0160Y         S0      
317GND              VIA   -    MD0080PA00X+154876Y+109821X0160Y         S0      
317GND              VIA   -    MD0080PA00X+155505Y+109398X0160Y         S0      
317GND              VIA   -    MD0080PA00X+154876Y+109184X0160Y         S0      
317GND              VIA   -    MD0080PA00X+155505Y+108760X0160Y         S0      
317GND              VIA   -    MD0080PA00X+154876Y+108546X0160Y         S0      
317GND              VIA   -    MD0080PA00X+155505Y+108122X0160Y         S0      
317GND              VIA   -    MD0080PA00X+154876Y+107908X0160Y         S0      
317GND              VIA   -    MD0080PA00X+155505Y+107484X0160Y         S0      
317GND              VIA   -    MD0080PA00X+155505Y+106846X0160Y         S0      
317GND              VIA   -    MD0080PA00X+154876Y+106632X0160Y         S0      
317GND              VIA   -    MD0080PA00X+154876Y+107270X0160Y         S0      
317GND              VIA   -    MD0080PA00X+155505Y+106209X0160Y         S0      
317GND              VIA   -    MD0080PA00X+155505Y+105571X0160Y         S0      
317GND              VIA   -    MD0080PA00X+154876Y+105994X0160Y         S0      
317GND              VIA   -    MD0080PA00X+154876Y+105357X0160Y         S0      
317GND              VIA   -    MD0080PA00X+155505Y+104933X0160Y         S0      
317GND              VIA   -    MD0080PA00X+154876Y+104719X0160Y         S0      
317GND              VIA   -    MD0080PA00X+154506Y+105994X0160Y         S0      
317GND              VIA   -    MD0080PA00X+154691Y+105676X0160Y         S0      
317GND              VIA   -    MD0080PA00X+155505Y+103658X0160Y         S0      
317GND              VIA   -    MD0080PA00X+155505Y+104295X0160Y         S0      
317GND              VIA   -    MD0080PA00X+154876Y+103443X0160Y         S0      
317GND              VIA   -    MD0080PA00X+154876Y+104081X0160Y         S0      
317GND              VIA   -    MD0080PA00X+155505Y+103020X0160Y         S0      
317GND              VIA   -    MD0080PA00X+154876Y+102806X0160Y         S0      
317GND              VIA   -    MD0080PA00X+155387Y+100185X0160Y         S0      
317GND              VIA   -    MD0080PA00X+155387Y+100823X0160Y         S0      
317GND              VIA   -    MD0080PA00X+154758Y+101037X0160Y    R180 S0      
317GND              VIA   -    MD0080PA00X+154758Y+100399X0160Y    R180 S0      
317GND              VIA   -    MD0080PA00X+155387Y+099547X0160Y         S0      
317GND              VIA   -    MD0080PA00X+155387Y+098910X0160Y         S0      
317GND              VIA   -    MD0080PA00X+154758Y+099762X0160Y    R180 S0      
317GND              VIA   -    MD0080PA00X+154758Y+099124X0160Y    R180 S0      
317GND              VIA   -    MD0080PA00X+154573Y+098805X0160Y    R180 S0      
317GND              VIA   -    MD0080PA00X+154758Y+098486X0160Y    R180 S0      
317GND              VIA   -    MD0080PA00X+155387Y+098272X0160Y         S0      
317GND              VIA   -    MD0080PA00X+155387Y+097634X0160Y         S0      
317GND              VIA   -    MD0080PA00X+154758Y+097848X0160Y    R180 S0      
317GND              VIA   -    MD0080PA00X+154758Y+097210X0160Y    R180 S0      
317GND              VIA   -    MD0080PA00X+154388Y+098486X0160Y    R180 S0      
317GND              VIA   -    MD0080PA00X+155431Y+115880X0160Y         S0      
317GND              VIA   -    MD0080PA00X+155061Y+115880X0160Y         S0      
317GND              VIA   -    MD0080PA00X+155505Y+115138X0160Y         S0      
317GND              VIA   -    MD0080PA00X+154876Y+115561X0160Y         S0      
317GND              VIA   -    MD0080PA00X+154506Y+115561X0160Y         S0      
317GND              VIA   -    MD0080PA00X+154876Y+114924X0160Y         S0      
317GND              VIA   -    MD0080PA00X+155505Y+114500X0160Y         S0      
317GND              VIA   -    MD0080PA00X+154876Y+114286X0160Y         S0      
317GND              VIA   -    MD0080PA00X+155505Y+113862X0160Y         S0      
317GND              VIA   -    MD0080PA00X+154876Y+113648X0160Y         S0      
317GND              VIA   -    MD0080PA00X+155505Y+113224X0160Y         S0      
317GND              VIA   -    MD0080PA00X+136744Y+113010X0160Y         S0      
317GND              VIA   -    MD0080PA00X+039130Y+113010X0160Y         S0      
317GND              VIA   -    MD0080PA00X+045671Y+090832X0160Y    R180 S0      
317GND              VIA   -    MD0080PA00X+052821Y+113010X0160Y         S0      
327GND              R1395 -2          A01X+141218Y+153610X0120Y0150     S1      
317GND              VIA   -    MD0100PA00X+140946Y+153787X0200Y         S0      
317GND              J41   -G1  MD0440PA00X+076048Y+003327X0640Y    R180 S3      
317GND              J41   -G2  MD0440PA00X+071174Y+003327X0640Y    R180 S3      
317GND              J41   -G3  MD0440PA00X+063150Y+003327X0640Y    R180 S3      
317GND              J41   -G4  MD0440PA00X+058215Y+003327X0640Y    R180 S3      
317GND              J41   -G5  MD0440PA00X+050253Y+003327X0640Y    R180 S3      
327GND              J41   -OB4        A01X+074513Y+006516X0150Y0570R180 S1      
327GND              J41   -OB7        A01X+073804Y+006516X0150Y0570R180 S1      
327GND              J41   -OB10       A01X+073095Y+006516X0150Y0570R180 S1      
327GND              J41   -B10        A01X+068294Y+006516X0150Y0570R180 S1      
327GND              J41   -B17        A01X+066641Y+006516X0150Y0570R180 S1      
327GND              J41   -B26        A01X+064515Y+006516X0150Y0570R180 S1      
327GND              J41   -B33        A01X+061518Y+006516X0150Y0570R180 S1      
327GND              J41   -B38        A01X+060337Y+006516X0150Y0570R180 S1      
327GND              J41   -B49        A01X+056042Y+006516X0150Y0570R180 S1      
327GND              J41   -B52        A01X+055334Y+006516X0150Y0570R180 S1      
327GND              J41   -B55        A01X+054625Y+006516X0150Y0570R180 S1      
327GND              J41   -B58        A01X+053916Y+006516X0150Y0570R180 S1      
327GND              J41   -B61        A01X+053208Y+006516X0150Y0570R180 S1      
327GND              J41   -B64        A01X+052499Y+006516X0150Y0570R180 S1      
327GND              J41   -B67        A01X+051790Y+006516X0150Y0570R180 S1      
327GND              J41   -B70        A01X+051082Y+006516X0150Y0570R180 S1      
327GND              J41   -OA3        A01X+074749Y+005354X0150Y0570R180 S1      
327GND              J41   -OA4        A01X+074513Y+005354X0150Y0570R180 S1      
327GND              J41   -OA13       A01X+072387Y+005354X0150Y0570R180 S1      
327GND              J41   -A13        A01X+067585Y+005354X0150Y0570R180 S1      
327GND              J41   -A16        A01X+066877Y+005354X0150Y0570R180 S1      
327GND              J41   -A19        A01X+066168Y+005354X0150Y0570R180 S1      
327GND              J41   -A22        A01X+065460Y+005354X0150Y0570R180 S1      
327GND              J41   -A33        A01X+061518Y+005354X0150Y0570R180 S1      
327GND              J41   -A42        A01X+059392Y+005354X0150Y0570R180 S1      
327GND              J41   -A58        A01X+053916Y+005354X0150Y0570R180 S1      
327GND              J41   -A61        A01X+053208Y+005354X0150Y0570R180 S1      
327GND              J41   -A64        A01X+052499Y+005354X0150Y0570R180 S1      
327GND              J41   -A67        A01X+051790Y+005354X0150Y0570R180 S1      
327GND              J41   -A70        A01X+051082Y+005354X0150Y0570R180 S1      
327GND              R342  -2          A01X+056521Y+012278X0180Y0200     S1      
327GND              R341  -2          A01X+057651Y+012278X0180Y0200R180 S1      
327GND              PC6620-2          A01X+010767Y+159780X0198Y0197     S1      
327GND              PC473 -2          A01X+013357Y+158031X0630Y1190R090 S1      
327GND              PC6619-2          A01X+006283Y+157519X0630Y1190R270 S1      
327GND              PC6639-2          A01X+012535Y+155764X0400Y0500R180 S1      
327GND              PC6637-2          A01X+012530Y+156455X0400Y0500R180 S1      
327GND              PC6638-2          A01X+006767Y+155936X0400Y0500     S1      
327GND              PU6512-2   M      A01X+009150Y+153811X0090Y0240R090 S1      
327GND              PC6645-2          A01X+008637Y+154075X0198Y0197R090 S1      
327GND              PU6511-2   M      A01X+005576Y+153811X0090Y0240R090 S1      
327GND              PC6610-2          A01X+005063Y+154025X0198Y0197R090 S1      
327GND              PC6634-2          A01X+011507Y+152965X0198Y0197R270 S1      
327GND              PU6512-5          A01X+009150Y+153279X0090Y0240R090 S1      
327GND              PR6630-2          A01X+008440Y+152641X0198Y0197R090 S1      
327GND              PC6644-2   M      A01X+008637Y+153060X0198Y0197R270 S1      
327GND              PC6612-2          A01X+007932Y+152995X0198Y0197R270 S1      
327GND              PU6511-5          A01X+005576Y+153279X0090Y0240R090 S1      
327GND              PR6624-2          A01X+004866Y+152641X0198Y0197R090 S1      
327GND              PC6609-2          A01X+005063Y+153010X0198Y0197R270 S1      
327GND              PC6623-2          A01X+005204Y+150237X0198Y0197R090 S1      
327GND              PC6631-2          A01X+009827Y+146161X0630Y1190     S1      
327GND              PC6630-2          A01X+007427Y+146161X0630Y1190     S1      
327GND              PC6629-2          A01X+005027Y+146161X0630Y1190     S1      
327GND              PC6632-2          A01X+002627Y+146161X0630Y1190     S1      
327GND              C1040 -2          A18X+153482Y+156906X0198Y0197R090 S2      
327GND              C1032 -2          A18X+150115Y+156906X0198Y0197R090 S2      
327GND              C992  -2          A01X+155155Y+155600X0198Y0197R090 S1      
327GND              C993  -2          A01X+154564Y+155600X0198Y0197R090 S1      
327GND              C805  -2          A18X+162921Y+156906X0198Y0197R090 S2      
327GND              C668  -2          A01X+167371Y+156358X0198Y0197R090 S1      
327GND              C969  -2          A18X+164811Y+156906X0198Y0197R090 S2      
327GND              C667  -2          A01X+169553Y+154519X0198Y0197R270 S1      
327GND              C656  -2          A18X+138393Y+156906X0198Y0197R090 S2      
327GND              C636  -2          A18X+136504Y+156906X0198Y0197R090 S2      
327GND              C589  -2          A01X+141543Y+155600X0198Y0197R090 S1      
327GND              C590  -2          A01X+140953Y+155600X0198Y0197R090 S1      
327GND              C575  -2          A18X+127065Y+156906X0198Y0197R090 S2      
327GND              C563  -2          A18X+123697Y+156906X0198Y0197R090 S2      
327GND              C504  -2          A01X+128737Y+155600X0198Y0197R090 S1      
327GND              C505  -2          A01X+128147Y+155600X0198Y0197R090 S1      
327GND              C486  -2          A18X+052695Y+153606X0198Y0197R090 S2      
327GND              C478  -2          A18X+049327Y+153606X0198Y0197R090 S2      
327GND              C434  -2          A01X+054367Y+152300X0198Y0197R090 S1      
327GND              C435  -2          A01X+053777Y+152300X0198Y0197R090 S1      
327GND              C408  -2          A18X+062134Y+153606X0198Y0197R090 S2      
327GND              C424  -2          A18X+064023Y+153606X0198Y0197R090 S2      
327GND              C368  -2          A01X+068812Y+151960X0198Y0197R090 S1      
327GND              C369  -2          A01X+066583Y+153058X0198Y0197R090 S1      
327GND              C335  -2          A18X+037606Y+153606X0198Y0197R090 S2      
327GND              C327  -2          A18X+035716Y+153606X0198Y0197R090 S2      
327GND              C110  -2          A01X+040756Y+152300X0198Y0197R090 S1      
327GND              C111  -2          A01X+040166Y+152300X0198Y0197R090 S1      
327GND              C117  -2          A01X+027360Y+152300X0198Y0197R090 S1      
327GND              C115  -2          A01X+027950Y+152300X0198Y0197R090 S1      
327GND              C244  -2          A18X+022910Y+153606X0198Y0197R090 S2      
327GND              C262  -2          A18X+026278Y+153606X0198Y0197R090 S2      
327GND              C245  -2          A18X+138910Y+096649X0198Y0197     S2      
327GND              C246  -2          A18X+143123Y+098176X0198Y0197     S2      
327GND              C251  -2          A18X+141630Y+096719X0198Y0197R090 S2      
327GND              C252  -2          A18X+139925Y+096649X0198Y0197R180 S2      
327GND              C263  -2          A18X+139938Y+097826X0198Y0197R180 S2      
327GND              C267  -2          A18X+143310Y+096649X0198Y0197     S2      
327GND              C268  -2          A18X+140475Y+098176X0198Y0197R180 S2      
327GND              C270  -2          A18X+140032Y+098526X0198Y0197     S2      
327GND              C271  -2          A18X+144623Y+098776X0198Y0197     S2      
327GND              C272  -2          A18X+146823Y+098176X0198Y0197     S2      
327GND              C273  -2          A18X+139775Y+098176X0198Y0197R180 S2      
327GND              C274  -2          A18X+146123Y+098176X0198Y0197     S2      
327GND              C275  -2          A18X+136555Y+097826X0198Y0197R180 S2      
327GND              C276  -2          A18X+138275Y+098776X0198Y0197R180 S2      
327GND              C277  -2          A18X+144375Y+096649X0198Y0197R180 S2      
327GND              C278  -2          A18X+139025Y+098176X0198Y0197R180 S2      
327GND              C279  -2          A18X+140723Y+098526X0198Y0197     S2      
327GND              C1922 -2          A18X+138275Y+098176X0198Y0197R180 S2      
327GND              C2102 -2          A18X+040464Y+102256X0198Y0197R180 S2      
327GND              C2103 -2          A18X+039716Y+102256X0198Y0197R180 S2      
327GND              C2104 -2          A18X+038973Y+101077X0198Y0197R180 S2      
327GND              C2105 -2          A18X+039320Y+103749X0198Y0197     S2      
327GND              C2106 -2          A18X+039320Y+103129X0198Y0197     S2      
327GND              C2107 -2          A18X+038968Y+102256X0198Y0197R180 S2      
327GND              C2108 -2          A18X+038620Y+104349X0198Y0197     S2      
327GND              C2109 -2          A18X+038968Y+101902X0198Y0197R180 S2      
327GND              C2110 -2          A18X+040464Y+101547X0198Y0197R180 S2      
327GND              C2111 -2          A18X+041874Y+101360X0198Y0197R180 S2      
327GND              C2112 -2          A18X+039716Y+101547X0198Y0197R180 S2      
327GND              C2113 -2          A01X+043889Y+102893X0198Y0197R270 S1      
327GND              C2114 -2          A18X+047658Y+104077X0198Y0197     S2      
327GND              C2115 -2          A18X+040308Y+104727X0198Y0197     S2      
327GND              C2116 -2          A18X+038620Y+103129X0198Y0197     S2      
327GND              C2117 -2          A18X+039320Y+104349X0198Y0197     S2      
327GND              C2118 -2          A18X+045458Y+104727X0198Y0197     S2      
327GND              C2119 -2          A18X+046958Y+104077X0198Y0197     S2      
327GND              C2120 -2          A18X+049108Y+104077X0198Y0197     S2      
327GND              C2121 -2          A01X+043141Y+102893X0198Y0197R270 S1      
327GND              C2122 -2          A18X+042817Y+101888X0198Y0197R180 S2      
327GND              C2123 -2          A18X+038968Y+101547X0198Y0197R180 S2      
327GND              C2124 -2          A18X+043515Y+102893X0198Y0197R090 S2      
327GND              C2125 -2          A18X+043141Y+102893X0198Y0197R090 S2      
327GND              C2126 -2          A18X+049158Y+104727X0198Y0197     S2      
327GND              C2127 -2          A01X+042817Y+102301X0198Y0197     S1      
327GND              C2128 -2          A18X+046208Y+104077X0198Y0197     S2      
327GND              C2129 -2          A18X+146123Y+101902X0198Y0197     S2      
327GND              C2130 -2          A18X+145373Y+100726X0198Y0197     S2      
327GND              C2131 -2          A18X+140432Y+102301X0198Y0197R180 S2      
327GND              C2132 -2          A01X+141416Y+102301X0198Y0197     S1      
327GND              C2133 -2          A01X+143872Y+103230X0198Y0197R180 S1      
327GND              C2134 -2          A18X+145373Y+099426X0198Y0197     S2      
327GND              C2135 -2          A18X+141876Y+100950X0198Y0197R270 S2      
327GND              C2136 -2          A01X+139488Y+102108X0198Y0197     S1      
327GND              C2137 -2          A18X+142999Y+102893X0198Y0197R090 S2      
327GND              C2138 -2          A18X+143073Y+104076X0198Y0197     S2      
327GND              C2139 -2          A01X+143872Y+102482X0198Y0197R180 S1      
327GND              C2140 -2          A18X+141780Y+100176X0198Y0197R180 S2      
327GND              C2141 -2          A01X+139488Y+102482X0198Y0197     S1      
327GND              C2142 -2          A18X+144573Y+104726X0198Y0197     S2      
327GND              C2143 -2          A18X+144423Y+099776X0198Y0197     S2      
327GND              C2144 -2          A18X+141780Y+099776X0198Y0197R180 S2      
327GND              C2145 -2          A18X+139488Y+102856X0198Y0197R180 S2      
327GND              C2146 -2          A01X+141877Y+102893X0198Y0197R270 S1      
327GND              C2147 -2          A18X+143872Y+100986X0198Y0197     S2      
327GND              C2148 -2          A01X+142250Y+100950X0198Y0197R090 S1      
327GND              C2149 -2          A01X+139488Y+102856X0198Y0197     S1      
327GND              C2150 -2          A01X+140007Y+102893X0198Y0197R270 S1      
327GND              C2151 -2          A18X+146123Y+099426X0198Y0197     S2      
327GND              C2152 -2          A18X+143872Y+100612X0198Y0197     S2      
327GND              C2153 -2          A18X+140755Y+102893X0198Y0197R090 S2      
327GND              C2154 -2          A18X+146123Y+100726X0198Y0197     S2      
327GND              C2155 -2          A18X+143372Y+100950X0198Y0197R270 S2      
327GND              C2156 -2          A01X+141129Y+102893X0198Y0197R270 S1      
327GND              C2157 -2          A01X+143872Y+102108X0198Y0197R180 S1      
327GND              C2158 -2          A01X+141503Y+102893X0198Y0197R270 S1      
327GND              C2159 -2          A01X+142624Y+100950X0198Y0197R090 S1      
327GND              C2160 -2          A18X+142302Y+102301X0198Y0197R180 S2      
327GND              C2161 -2          A01X+142998Y+100950X0198Y0197R090 S1      
327GND              C2162 -2          A18X+137873Y+104076X0198Y0197     S2      
327GND              C2163 -2          A18X+139488Y+100986X0198Y0197R180 S2      
327GND              C2164 -2          A01X+139488Y+100612X0198Y0197     S1      
327GND              C2165 -2          A18X+138975Y+098776X0198Y0197R180 S2      
327GND              C2166 -2          A18X+146123Y+098776X0198Y0197     S2      
327GND              C2167 -2          A18X+137525Y+098176X0198Y0197R180 S2      
327GND              C2169 -2          A18X+144338Y+097826X0198Y0197R180 S2      
327GND              C2170 -2          A18X+139695Y+098776X0198Y0197R180 S2      
327GND              C2171 -2          A18X+142201Y+097163X0198Y0197R300 S2      
327GND              C2173 -2          A18X+144623Y+098176X0198Y0197     S2      
327GND              C2174 -2          A18X+143323Y+097826X0198Y0197     S2      
327GND              C2175 -2          A18X+142382Y+098176X0198Y0197     S2      
327GND              C2177 -2          A18X+145343Y+098176X0198Y0197     S2      
327GND              C2178 -2          A18X+138873Y+097826X0198Y0197     S2      
327GND              C2181 -2          A18X+146660Y+097826X0198Y0197     S2      
327GND              C2182 -2          A18X+141046Y+097862X0198Y0197R120 S2      
327GND              C2183 -2          A18X+136968Y+096956X0198Y0197R270 S2      
327GND              C2185 -2          A18X+143075Y+096999X0198Y0197R180 S2      
327GND              C2186 -2          A18X+141630Y+098219X0198Y0197R090 S2      
327GND              C2189 -2          A18X+137725Y+096649X0198Y0197R180 S2      
327GND              C2190 -2          A18X+141059Y+097163X0198Y0197R240 S2      
327GND              C2192 -2          A18X+145560Y+096649X0198Y0197     S2      
327GND              C2193 -2          A18X+141630Y+097469X0198Y0197R090 S2      
327GND              C2195 -2          A18X+145530Y+097826X0198Y0197     S2      
327GND              C2196 -2          A18X+142223Y+098526X0198Y0197     S2      
327GND              C2198 -2          A18X+146318Y+096956X0198Y0197R270 S2      
327GND              C2199 -2          A18X+140160Y+096999X0198Y0197     S2      
327GND              C2201 -2          A18X+140038Y+106026X0198Y0197R180 S2      
327GND              C2202 -2          A18X+142352Y+105326X0198Y0197     S2      
327GND              C2203 -2          A18X+140673Y+105676X0198Y0197     S2      
327GND              C2204 -2          A18X+143100Y+105326X0198Y0197     S2      
327GND              C2205 -2          A18X+137873Y+105326X0198Y0197     S2      
327GND              C2207 -2          A18X+146023Y+105314X0198Y0197     S2      
327GND              C2208 -2          A18X+144488Y+106026X0198Y0197R180 S2      
327GND              C2209 -2          A18X+140280Y+106849X0198Y0197     S2      
327GND              C2210 -2          A18X+137923Y+106026X0198Y0197     S2      
327GND              C2211 -2          A18X+144573Y+105314X0198Y0197     S2      
327GND              C2213 -2          A18X+144475Y+107199X0198Y0197R180 S2      
327GND              C2214 -2          A18X+145473Y+105676X0198Y0197     S2      
327GND              C2215 -2          A18X+145660Y+107199X0198Y0197     S2      
327GND              C2216 -2          A18X+139023Y+106026X0198Y0197     S2      
327GND              C2217 -2          A18X+136925Y+105676X0198Y0197R180 S2      
327GND              C2219 -2          A18X+143273Y+105676X0198Y0197     S2      
327GND              C2220 -2          A18X+138473Y+105676X0198Y0197     S2      
327GND              C2221 -2          A18X+143460Y+107199X0198Y0197     S2      
327GND              C2222 -2          A18X+144023Y+105676X0198Y0197     S2      
327GND              C2223 -2          A18X+146773Y+105314X0198Y0197     S2      
327GND              C2225 -2          A18X+143205Y+106849X0198Y0197R180 S2      
327GND              C2226 -2          A18X+139923Y+105676X0198Y0197     S2      
327GND              C2227 -2          A18X+140123Y+105326X0198Y0197     S2      
327GND              C2228 -2          A18X+145680Y+106026X0198Y0197     S2      
327GND              C2229 -2          A18X+139223Y+105676X0198Y0197     S2      
327GND              C2231 -2          A18X+137173Y+105326X0198Y0197     S2      
327GND              C2232 -2          A18X+144723Y+105676X0198Y0197     S2      
327GND              C2233 -2          A18X+137048Y+106881X0198Y0197R090 S2      
327GND              C2234 -2          A18X+137825Y+107199X0198Y0197R180 S2      
327GND              C2237 -2          A18X+138623Y+105326X0198Y0197     S2      
327GND              C2238 -2          A18X+137723Y+105676X0198Y0197     S2      
327GND              C2239 -2          A18X+140025Y+107199X0198Y0197R180 S2      
327GND              C2240 -2          A18X+140873Y+105326X0198Y0197     S2      
327GND              C2243 -2          A18X+145273Y+105314X0198Y0197     S2      
327GND              C2244 -2          A18X+141730Y+105484X0198Y0197R270 S2      
327GND              C2245 -2          A18X+146223Y+105676X0198Y0197     S2      
327GND              C2246 -2          A18X+146939Y+105712X0198Y0197R060 S2      
327GND              C2248 -2          A18X+142523Y+105676X0198Y0197     S2      
327GND              C2249 -2          A18X+146418Y+106871X0198Y0197R090 S2      
327GND              C2250 -2          A18X+139010Y+107199X0198Y0197     S2      
327GND              C2251 -2          A18X+146668Y+106026X0198Y0197R180 S2      
327GND              C2253 -2          A18X+139373Y+105326X0198Y0197     S2      
327GND              C2254 -2          A18X+143473Y+106026X0198Y0197     S2      
327GND              C2255 -2          A18X+143848Y+105326X0198Y0197     S2      
327GND              C2256 -2          A18X+136675Y+106026X0198Y0197R180 S2      
327GND              C2258 -2          A18X+042408Y+099777X0198Y0197     S2      
327GND              C2259 -2          A18X+046808Y+099127X0198Y0197     S2      
327GND              C2260 -2          A01X+041874Y+101734X0198Y0197     S1      
327GND              C2261 -2          A18X+041008Y+104727X0198Y0197     S2      
327GND              C2262 -2          A01X+042393Y+102893X0198Y0197R270 S1      
327GND              C2263 -2          A18X+043140Y+100950X0198Y0197R270 S2      
327GND              C2264 -2          A18X+044687Y+101474X0198Y0197R180 S2      
327GND              C2265 -2          A18X+041874Y+102482X0198Y0197R180 S2      
327GND              C2266 -2          A01X+043802Y+102301X0198Y0197     S1      
327GND              C2267 -2          A01X+045711Y+102301X0198Y0197     S1      
327GND              C2268 -2          A18X+044166Y+099377X0198Y0197R180 S2      
327GND              C2269 -2          A01X+046258Y+102108X0198Y0197R180 S1      
327GND              C2270 -2          A01X+041874Y+101360X0198Y0197     S1      
327GND              C2271 -2          A18X+045759Y+102893X0198Y0197R090 S2      
327GND              C2272 -2          A18X+044166Y+099777X0198Y0197R180 S2      
327GND              C2273 -2          A01X+046258Y+102856X0198Y0197R180 S1      
327GND              C2274 -2          A01X+041874Y+102482X0198Y0197     S1      
327GND              C2275 -2          A18X+044708Y+104727X0198Y0197     S2      
327GND              C2276 -2          A18X+044687Y+101888X0198Y0197R180 S2      
327GND              C2277 -2          A18X+044173Y+098977X0198Y0197R180 S2      
327GND              C2278 -2          A01X+041874Y+102108X0198Y0197     S1      
327GND              C2279 -2          A01X+044687Y+102301X0198Y0197     S1      
327GND              C2280 -2          A18X+046808Y+099777X0198Y0197     S2      
327GND              C2281 -2          A18X+044608Y+099127X0198Y0197     S2      
327GND              C2282 -2          A01X+044637Y+102893X0198Y0197R270 S1      
327GND              C2283 -2          A01X+046258Y+100612X0198Y0197R180 S1      
327GND              C2284 -2          A18X+044608Y+099777X0198Y0197     S2      
327GND              C2285 -2          A18X+043208Y+104727X0198Y0197     S2      
327GND              C2286 -2          A01X+046258Y+102482X0198Y0197R180 S1      
327GND              C2287 -2          A18X+041758Y+104727X0198Y0197     S2      
327GND              C2288 -2          A01X+046258Y+101734X0198Y0197R180 S1      
327GND              C2289 -2          A18X+042508Y+104727X0198Y0197     S2      
327GND              C2290 -2          A01X+046258Y+100986X0198Y0197R180 S1      
327GND              C2291 -2          A18X+043889Y+102893X0198Y0197R090 S2      
327GND              C2292 -2          A18X+039875Y+100027X0198Y0197R180 S2      
327GND              C2293 -2          A18X+039173Y+100727X0198Y0197R180 S2      
327GND              C2294 -2          A18X+042135Y+098177X0198Y0197R180 S2      
327GND              C2295 -2          A18X+039337Y+096956X0198Y0197R270 S2      
327GND              C2296 -2          A18X+047008Y+098777X0198Y0197     S2      
327GND              C2297 -2          A18X+046258Y+098177X0198Y0197     S2      
327GND              C2298 -2          A18X+042885Y+098177X0198Y0197R180 S2      
327GND              C2300 -2          A18X+041385Y+098177X0198Y0197R180 S2      
327GND              C2301 -2          A18X+042420Y+098527X0198Y0197     S2      
327GND              C2302 -2          A18X+045508Y+098777X0198Y0197     S2      
327GND              C2303 -2          A18X+039885Y+098177X0198Y0197R180 S2      
327GND              C2304 -2          A18X+042560Y+097009X0198Y0197     S2      
327GND              C2306 -2          A18X+045720Y+096649X0198Y0197     S2      
327GND              C2307 -2          A18X+045508Y+098177X0198Y0197     S2      
327GND              C2308 -2          A18X+042335Y+096649X0198Y0197R180 S2      
327GND              C2309 -2          A18X+041270Y+096649X0198Y0197     S2      
327GND              C2310 -2          A18X+038941Y+097827X0198Y0197R180 S2      
327GND              C2312 -2          A18X+048508Y+098777X0198Y0197     S2      
327GND              C2313 -2          A18X+049208Y+098177X0198Y0197     S2      
327GND              C2314 -2          A18X+042323Y+097827X0198Y0197R180 S2      
327GND              C2315 -2          A18X+047916Y+097827X0198Y0197     S2      
327GND              C2316 -2          A18X+044608Y+098527X0198Y0197     S2      
327GND              C2318 -2          A18X+047946Y+096649X0198Y0197     S2      
327GND              C2319 -2          A18X+041258Y+097827X0198Y0197     S2      
327GND              C2320 -2          A18X+048508Y+098177X0198Y0197     S2      
327GND              C2321 -2          A18X+044016Y+096719X0198Y0197R090 S2      
327GND              C2322 -2          A18X+043108Y+098527X0198Y0197     S2      
327GND              C2324 -2          A18X+045485Y+096999X0198Y0197R180 S2      
327GND              C2325 -2          A18X+047758Y+098177X0198Y0197     S2      
327GND              C2326 -2          A18X+040071Y+097827X0198Y0197R180 S2      
327GND              C2327 -2          A18X+042082Y+098776X0198Y0197R180 S2      
327GND              C2330 -2          A18X+046785Y+096649X0198Y0197R180 S2      
327GND              C2331 -2          A18X+045708Y+097827X0198Y0197     S2      
327GND              C2332 -2          A18X+044016Y+098219X0198Y0197R090 S2      
327GND              C2333 -2          A18X+049046Y+097827X0198Y0197     S2      
327GND              C2335 -2          A18X+041385Y+098777X0198Y0197R180 S2      
327GND              C2336 -2          A18X+048727Y+096956X0198Y0197R270 S2      
327GND              C2337 -2          A18X+046723Y+097827X0198Y0197R180 S2      
327GND              C2338 -2          A18X+044758Y+098177X0198Y0197     S2      
327GND              C2340 -2          A18X+043445Y+097163X0198Y0197R240 S2      
327GND              C2341 -2          A18X+044016Y+097469X0198Y0197R090 S2      
327GND              C2342 -2          A18X+044587Y+097163X0198Y0197R300 S2      
327GND              C2343 -2          A18X+040635Y+098177X0198Y0197R180 S2      
327GND              C2345 -2          A18X+047008Y+098177X0198Y0197     S2      
327GND              C2346 -2          A18X+040085Y+096649X0198Y0197R180 S2      
327GND              C2347 -2          A18X+043456Y+097862X0198Y0197R120 S2      
327GND              C2348 -2          A18X+040685Y+098777X0198Y0197R180 S2      
327GND              C2350 -2          A18X+040858Y+105677X0198Y0197     S2      
327GND              C2351 -2          A18X+041408Y+106027X0198Y0197     S2      
327GND              C2352 -2          A18X+045486Y+105327X0198Y0197     S2      
327GND              C2353 -2          A18X+048023Y+106027X0198Y0197R180 S2      
327GND              C2354 -2          A18X+042435Y+107199X0198Y0197R180 S2      
327GND              C2356 -2          A18X+046885Y+107199X0198Y0197R180 S2      
327GND              C2357 -2          A18X+042720Y+106849X0198Y0197     S2      
327GND              C2358 -2          A18X+039158Y+106027X0198Y0197     S2      
327GND              C2359 -2          A18X+043258Y+105327X0198Y0197     S2      
327GND              C2360 -2          A18X+039558Y+105327X0198Y0197     S2      
327GND              C2362 -2          A18X+046873Y+106027X0198Y0197R180 S2      
327GND              C2363 -2          A18X+049045Y+106029X0198Y0197R180 S2      
327GND              C2364 -2          A18X+048608Y+105677X0198Y0197     S2      
327GND              C2365 -2          A18X+045858Y+106027X0198Y0197     S2      
327GND              C2366 -2          A18X+040108Y+105677X0198Y0197     S2      
327GND              C2368 -2          A18X+046958Y+105314X0198Y0197     S2      
327GND              C2369 -2          A18X+045820Y+107199X0198Y0197     S2      
327GND              C2370 -2          A18X+047858Y+105677X0198Y0197     S2      
327GND              C2371 -2          A18X+045585Y+106849X0198Y0197R180 S2      
327GND              C2372 -2          A18X+048070Y+107199X0198Y0197     S2      
327GND              C2374 -2          A18X+042308Y+105677X0198Y0197     S2      
327GND              C2375 -2          A18X+046408Y+105677X0198Y0197     S2      
327GND              C2376 -2          A18X+049318Y+105712X0198Y0197R060 S2      
327GND              C2377 -2          A18X+044116Y+105484X0198Y0197R270 S2      
327GND              C2378 -2          A18X+039358Y+105677X0198Y0197     S2      
327GND              C2380 -2          A18X+042508Y+105327X0198Y0197     S2      
327GND              C2381 -2          A18X+047658Y+105314X0198Y0197     S2      
327GND              C2382 -2          A18X+039427Y+106891X0198Y0197R090 S2      
327GND              C2383 -2          A18X+041608Y+105677X0198Y0197     S2      
327GND              C2386 -2          A18X+048807Y+106871X0198Y0197R090 S2      
327GND              C2387 -2          A18X+044908Y+105677X0198Y0197     S2      
327GND              C2388 -2          A18X+044737Y+105327X0198Y0197     S2      
327GND              C2389 -2          A18X+040185Y+107199X0198Y0197R180 S2      
327GND              C2392 -2          A18X+046234Y+105327X0198Y0197     S2      
327GND              C2393 -2          A18X+040308Y+106027X0198Y0197     S2      
327GND              C2394 -2          A18X+041008Y+105327X0198Y0197     S2      
327GND              C2395 -2          A18X+041420Y+107199X0198Y0197     S2      
327GND              C2397 -2          A18X+040258Y+105327X0198Y0197     S2      
327GND              C2398 -2          A18X+047108Y+105677X0198Y0197     S2      
327GND              C2399 -2          A18X+049158Y+105314X0198Y0197     S2      
327GND              C2400 -2          A18X+045658Y+105677X0198Y0197     S2      
327GND              C2402 -2          A18X+042423Y+106027X0198Y0197R180 S2      
327GND              C2403 -2          A18X+041758Y+105327X0198Y0197     S2      
327GND              C2404 -2          A18X+043058Y+105677X0198Y0197     S2      
327GND              C2405 -2          A18X+048408Y+105314X0198Y0197     S2      
327GND              C2407 -2          A18X+045711Y+101474X0198Y0197R180 S2      
327GND              C2408 -2          A18X+042392Y+100950X0198Y0197R270 S2      
327GND              C2409 -2          A18X+040163Y+099168X0198Y0197R060 S2      
327GND              C2410 -2          A01X+043140Y+100950X0198Y0197R090 S1      
327GND              C2411 -2          A18X+040908Y+099127X0198Y0197     S2      
327GND              C2412 -2          A01X+042392Y+100950X0198Y0197R090 S1      
327GND              C2413 -2          A18X+045358Y+099127X0198Y0197     S2      
327GND              C2414 -2          A18X+046258Y+098777X0198Y0197     S2      
327GND              C2415 -2          A18X+046058Y+099777X0198Y0197     S2      
327GND              C2416 -2          A18X+040973Y+103427X0198Y0197R180 S2      
327GND              C2417 -2          A18X+042766Y+100950X0198Y0197R270 S2      
327GND              C2418 -2          A18X+045384Y+100950X0198Y0197R270 S2      
327GND              C2419 -2          A18X+044166Y+100177X0198Y0197R180 S2      
327GND              C2420 -2          A18X+046258Y+102108X0198Y0197     S2      
327GND              C2421 -2          A18X+040178Y+100335X0198Y0197R300 S2      
327GND              C2422 -2          A01X+046258Y+101360X0198Y0197R180 S1      
327GND              C2423 -2          A01X+045711Y+101474X0198Y0197     S1      
327GND              C2424 -2          A18X+046258Y+100612X0198Y0197     S2      
327GND              C2425 -2          A18X+049208Y+101902X0198Y0197     S2      
327GND              C2426 -2          A18X+045358Y+099777X0198Y0197     S2      
327GND              C2427 -2          A01X+043802Y+101474X0198Y0197     S1      
327GND              C2428 -2          A01X+045711Y+101888X0198Y0197     S1      
327GND              C2429 -2          A18X+048508Y+099427X0198Y0197     S2      
327GND              C2430 -2          A18X+046258Y+100986X0198Y0197     S2      
327GND              C2431 -2          A18X+043514Y+100950X0198Y0197R270 S2      
327GND              C2432 -2          A18X+048508Y+102256X0198Y0197     S2      
327GND              C2433 -2          A18X+043802Y+101474X0198Y0197R180 S2      
327GND              C2434 -2          A01X+045384Y+100950X0198Y0197R090 S1      
327GND              C2435 -2          A18X+048953Y+103124X0198Y0197     S2      
327GND              C2436 -2          A18X+041658Y+099777X0198Y0197     S2      
327GND              C2437 -2          A18X+046258Y+102856X0198Y0197     S2      
327GND              C2438 -2          A18X+042408Y+099127X0198Y0197     S2      
327GND              C2439 -2          A01X+044636Y+100950X0198Y0197R090 S1      
327GND              C2440 -2          A18X+039958Y+102827X0198Y0197     S2      
327GND              C2441 -2          A18X+045711Y+101888X0198Y0197R180 S2      
327GND              C2442 -2          A01X+044687Y+101888X0198Y0197     S1      
327GND              C2443 -2          A18X+049208Y+098777X0198Y0197     S2      
327GND              C2444 -2          A18X+048808Y+103474X0198Y0197     S2      
327GND              C2445 -2          A01X+042766Y+100950X0198Y0197R090 S1      
327GND              C2446 -2          A01X+044262Y+100950X0198Y0197R090 S1      
327GND              C2447 -2          A18X+049208Y+100727X0198Y0197     S2      
327GND              C2448 -2          A18X+041658Y+099127X0198Y0197     S2      
327GND              C2449 -2          A18X+047758Y+098777X0198Y0197     S2      
327GND              C2450 -2          A01X+044687Y+101474X0198Y0197     S1      
327GND              C2451 -2          A18X+046058Y+099127X0198Y0197     S2      
327GND              C2452 -2          A18X+049208Y+100077X0198Y0197     S2      
327GND              C2453 -2          A18X+041023Y+100727X0198Y0197R180 S2      
327GND              C2454 -2          A18X+048508Y+100077X0198Y0197     S2      
327GND              C2455 -2          A18X+040908Y+099777X0198Y0197     S2      
327GND              C2456 -2          A18X+048213Y+103124X0198Y0197     S2      
327GND              C2457 -2          A18X+047758Y+100727X0198Y0197     S2      
327GND              C2458 -2          A18X+045758Y+100950X0198Y0197R270 S2      
327GND              C2459 -2          A18X+043108Y+099127X0198Y0197     S2      
327GND              C2460 -2          A01X+043888Y+100950X0198Y0197R090 S1      
327GND              C2461 -2          A18X+048508Y+101902X0198Y0197     S2      
327GND              C2462 -2          A18X+049208Y+102256X0198Y0197     S2      
327GND              C2463 -2          A18X+046258Y+102482X0198Y0197     S2      
327GND              C2464 -2          A18X+046258Y+101360X0198Y0197     S2      
327GND              C2465 -2          A18X+039958Y+103427X0198Y0197     S2      
327GND              C2466 -2          A18X+043108Y+099777X0198Y0197     S2      
327GND              C2467 -2          A18X+040973Y+102827X0198Y0197R180 S2      
327GND              C2468 -2          A18X+047758Y+099427X0198Y0197     S2      
327GND              C2469 -2          A18X+049208Y+101547X0198Y0197     S2      
327GND              C2470 -2          A18X+039958Y+100727X0198Y0197     S2      
327GND              C2471 -2          A18X+049208Y+099427X0198Y0197     S2      
327GND              C2472 -2          A18X+047758Y+100077X0198Y0197     S2      
327GND              C2473 -2          A18X+043888Y+100950X0198Y0197R270 S2      
327GND              C2474 -2          A18X+040473Y+101077X0198Y0197R180 S2      
327GND              C2475 -2          A01X+043514Y+100950X0198Y0197R090 S1      
327GND              C2476 -2          A18X+046258Y+101734X0198Y0197     S2      
327GND              C2477 -2          A18X+042817Y+102301X0198Y0197R180 S2      
327GND              C2478 -2          A01X+042817Y+101888X0198Y0197     S1      
327GND              C2479 -2          A18X+041874Y+101734X0198Y0197R180 S2      
327GND              C2480 -2          A18X+047708Y+104727X0198Y0197     S2      
327GND              C2481 -2          A18X+046958Y+104727X0198Y0197     S2      
327GND              C2482 -2          A18X+047852Y+103727X0198Y0197     S2      
327GND              C2483 -2          A18X+048408Y+104077X0198Y0197     S2      
327GND              C2484 -2          A18X+040464Y+101902X0198Y0197R180 S2      
327GND              C2485 -2          A01X+045385Y+102893X0198Y0197R270 S1      
327GND              C2486 -2          A18X+043802Y+101888X0198Y0197R180 S2      
327GND              C2487 -2          A01X+046258Y+103230X0198Y0197R180 S1      
327GND              C2488 -2          A18X+045711Y+102301X0198Y0197R180 S2      
327GND              C2489 -2          A18X+041559Y+103230X0198Y0197     S2      
327GND              C2490 -2          A18X+041008Y+104077X0198Y0197     S2      
327GND              C2491 -2          A18X+044637Y+102893X0198Y0197R090 S2      
327GND              C2492 -2          A18X+046258Y+103230X0198Y0197     S2      
327GND              C2493 -2          A18X+038620Y+103749X0198Y0197     S2      
327GND              C2494 -2          A18X+042767Y+102893X0198Y0197R090 S2      
327GND              C2495 -2          A18X+040258Y+104077X0198Y0197     S2      
327GND              C2496 -2          A18X+045458Y+104077X0198Y0197     S2      
327GND              C2497 -2          A18X+045385Y+102893X0198Y0197R090 S2      
327GND              C2498 -2          A18X+039723Y+101077X0198Y0197R180 S2      
327GND              C2499 -2          A01X+044263Y+102893X0198Y0197R270 S1      
327GND              C2500 -2          A01X+042767Y+102893X0198Y0197R270 S1      
327GND              C2501 -2          A01X+045011Y+102893X0198Y0197R270 S1      
327GND              C2502 -2          A18X+043802Y+102301X0198Y0197R180 S2      
327GND              C2503 -2          A01X+043802Y+101888X0198Y0197     S1      
327GND              C2504 -2          A01X+043515Y+102893X0198Y0197R270 S1      
327GND              C2505 -2          A18X+044687Y+102301X0198Y0197R180 S2      
327GND              C2506 -2          A18X+045011Y+102893X0198Y0197R090 S2      
327GND              C2507 -2          A18X+039716Y+101902X0198Y0197R180 S2      
327GND              C2508 -2          A01X+045759Y+102893X0198Y0197R270 S1      
327GND              C2509 -2          A18X+041874Y+102856X0198Y0197R180 S2      
327GND              C2510 -2          A18X+044263Y+102893X0198Y0197R090 S2      
327GND              C2511 -2          A18X+046208Y+104727X0198Y0197     S2      
327GND              C2513 -2          A18X+136775Y+098176X0198Y0197R180 S2      
327GND              C2514 -2          A18X+137525Y+098776X0198Y0197R180 S2      
327GND              C2516 -2          A18X+136775Y+099426X0198Y0197R180 S2      
327GND              C2517 -2          A18X+140432Y+101474X0198Y0197R180 S2      
327GND              C2518 -2          A18X+137475Y+099426X0198Y0197R180 S2      
327GND              C2520 -2          A18X+136278Y+100376X0198Y0197     S2      
327GND              C2521 -2          A18X+136775Y+098776X0198Y0197R180 S2      
327GND              C2522 -2          A18X+137515Y+100026X0198Y0197R180 S2      
327GND              C2523 -2          A18X+136775Y+100026X0198Y0197R180 S2      
327GND              C2524 -2          A18X+136788Y+100726X0198Y0197R180 S2      
327GND              C2525 -2          A01X+140432Y+101474X0198Y0197     S1      
327GND              C2526 -2          A18X+139488Y+100612X0198Y0197R180 S2      
327GND              C2527 -2          A01X+142302Y+101888X0198Y0197     S1      
327GND              C2528 -2          A01X+143372Y+100950X0198Y0197R090 S1      
327GND              C2529 -2          A18X+145673Y+102774X0198Y0197     S2      
327GND              C2530 -2          A18X+146123Y+101547X0198Y0197     S2      
327GND              C2531 -2          A18X+143872Y+102482X0198Y0197     S2      
327GND              C2532 -2          A18X+142973Y+099776X0198Y0197     S2      
327GND              C2533 -2          A18X+138588Y+103426X0198Y0197R180 S2      
327GND              C2534 -2          A18X+146823Y+100076X0198Y0197     S2      
327GND              C2535 -2          A01X+143872Y+100612X0198Y0197R180 S1      
327GND              C2536 -2          A18X+142223Y+099126X0198Y0197     S2      
327GND              C2537 -2          A18X+145364Y+101902X0198Y0197     S2      
327GND              C2538 -2          A18X+146423Y+103474X0198Y0197     S2      
327GND              C2539 -2          A18X+142998Y+100950X0198Y0197R270 S2      
327GND              C2540 -2          A18X+140723Y+099776X0198Y0197     S2      
327GND              C2541 -2          A18X+143673Y+099126X0198Y0197     S2      
327GND              C2542 -2          A18X+146123Y+102256X0198Y0197     S2      
327GND              C2543 -2          A18X+142624Y+100950X0198Y0197R270 S2      
327GND              C2544 -2          A18X+145364Y+101547X0198Y0197     S2      
327GND              C2545 -2          A18X+146823Y+099426X0198Y0197     S2      
327GND              C2546 -2          A18X+140754Y+100950X0198Y0197R270 S2      
327GND              C2547 -2          A18X+140380Y+100950X0198Y0197R270 S2      
327GND              C2548 -2          A18X+146423Y+102774X0198Y0197     S2      
327GND              C2549 -2          A18X+140023Y+099776X0198Y0197     S2      
327GND              C2550 -2          A18X+142973Y+099126X0198Y0197     S2      
327GND              C2551 -2          A01X+143872Y+100986X0198Y0197R180 S1      
327GND              C2552 -2          A18X+143872Y+102108X0198Y0197     S2      
327GND              C2553 -2          A18X+141128Y+100950X0198Y0197R270 S2      
327GND              C2554 -2          A18X+138088Y+101076X0198Y0197R180 S2      
327GND              C2555 -2          A01X+143872Y+102856X0198Y0197R180 S1      
327GND              C2556 -2          A18X+142223Y+099776X0198Y0197     S2      
327GND              C2557 -2          A18X+145373Y+098776X0198Y0197     S2      
327GND              C2558 -2          A18X+143325Y+101888X0198Y0197R180 S2      
327GND              C2559 -2          A18X+143872Y+101734X0198Y0197     S2      
327GND              C2560 -2          A18X+137573Y+100726X0198Y0197     S2      
327GND              C2561 -2          A18X+137797Y+100336X0198Y0197R300 S2      
327GND              C2562 -2          A01X+140006Y+100950X0198Y0197R090 S1      
327GND              C2563 -2          A01X+143325Y+101888X0198Y0197     S1      
327GND              C2564 -2          A01X+143325Y+101474X0198Y0197     S1      
327GND              C2565 -2          A18X+143325Y+101474X0198Y0197R180 S2      
327GND              C2566 -2          A18X+143873Y+098776X0198Y0197     S2      
327GND              C2567 -2          A18X+137795Y+099164X0198Y0197R060 S2      
327GND              C2568 -2          A18X+140006Y+100950X0198Y0197R270 S2      
327GND              C2569 -2          A18X+139273Y+099776X0198Y0197     S2      
327GND              C2570 -2          A18X+146568Y+103124X0198Y0197     S2      
327GND              C2571 -2          A01X+143872Y+101734X0198Y0197R180 S1      
327GND              C2572 -2          A01X+141416Y+101474X0198Y0197     S1      
327GND              C2573 -2          A01X+142302Y+101474X0198Y0197     S1      
327GND              C2574 -2          A18X+137573Y+103426X0198Y0197     S2      
327GND              C2575 -2          A18X+138638Y+100726X0198Y0197R180 S2      
327GND              C2576 -2          A18X+139273Y+099126X0198Y0197     S2      
327GND              C2577 -2          A18X+145364Y+102256X0198Y0197     S2      
327GND              C2578 -2          A18X+146823Y+100726X0198Y0197     S2      
327GND              C2579 -2          A18X+146123Y+100076X0198Y0197     S2      
327GND              C2580 -2          A18X+142250Y+100950X0198Y0197R270 S2      
327GND              C2581 -2          A18X+137573Y+102826X0198Y0197     S2      
327GND              C2582 -2          A18X+138523Y+099776X0198Y0197     S2      
327GND              C2583 -2          A18X+146823Y+101547X0198Y0197     S2      
327GND              C2584 -2          A18X+146823Y+102256X0198Y0197     S2      
327GND              C2585 -2          A18X+146823Y+101902X0198Y0197     S2      
327GND              C2586 -2          A18X+145373Y+100076X0198Y0197     S2      
327GND              C2587 -2          A18X+143872Y+101360X0198Y0197     S2      
327GND              C2588 -2          A18X+138523Y+099126X0198Y0197     S2      
327GND              C2589 -2          A18X+140023Y+099126X0198Y0197     S2      
327GND              C2590 -2          A18X+145827Y+103124X0198Y0197     S2      
327GND              C2591 -2          A01X+143872Y+101360X0198Y0197R180 S1      
327GND              C2592 -2          A18X+146823Y+098776X0198Y0197     S2      
327GND              C2593 -2          A18X+140723Y+099126X0198Y0197     S2      
327GND              C2594 -2          A18X+143872Y+102856X0198Y0197     S2      
327GND              C2595 -2          A18X+141788Y+098976X0198Y0197R180 S2      
327GND              C2596 -2          A18X+138588Y+102826X0198Y0197R180 S2      
327GND              C2597 -2          A18X+136910Y+103749X0198Y0197     S2      
327GND              C2598 -2          A18X+140432Y+101888X0198Y0197R180 S2      
327GND              C2599 -2          A01X+139488Y+101734X0198Y0197     S1      
327GND              C2600 -2          A18X+145323Y+104726X0198Y0197     S2      
327GND              C2601 -2          A01X+140755Y+102893X0198Y0197R270 S1      
327GND              C2602 -2          A18X+139373Y+104076X0198Y0197     S2      
327GND              C2603 -2          A18X+137173Y+104726X0198Y0197     S2      
327GND              C2604 -2          A18X+136210Y+103749X0198Y0197     S2      
327GND              C2605 -2          A18X+136210Y+103099X0198Y0197     S2      
327GND              C2606 -2          A01X+139488Y+101360X0198Y0197     S1      
327GND              C2607 -2          A18X+140123Y+104076X0198Y0197     S2      
327GND              C2608 -2          A18X+138623Y+104076X0198Y0197     S2      
327GND              C2609 -2          A18X+140381Y+102893X0198Y0197R090 S2      
327GND              C2610 -2          A18X+141503Y+102893X0198Y0197R090 S2      
327GND              C2611 -2          A18X+138078Y+102256X0198Y0197R180 S2      
327GND              C2612 -2          A18X+136210Y+104349X0198Y0197     S2      
327GND              C2613 -2          A18X+139488Y+102482X0198Y0197R180 S2      
327GND              C2614 -2          A01X+141416Y+101888X0198Y0197     S1      
327GND              C2615 -2          A18X+140007Y+102893X0198Y0197R090 S2      
327GND              C2616 -2          A18X+141416Y+101888X0198Y0197R180 S2      
327GND              C2617 -2          A18X+141129Y+102893X0198Y0197R090 S2      
327GND              C2618 -2          A18X+136582Y+101547X0198Y0197R180 S2      
327GND              C2619 -2          A18X+137338Y+101076X0198Y0197R180 S2      
327GND              C2620 -2          A18X+139488Y+102108X0198Y0197R180 S2      
327GND              C2621 -2          A18X+141416Y+102301X0198Y0197R180 S2      
327GND              C2622 -2          A01X+142625Y+102893X0198Y0197R270 S1      
327GND              C2623 -2          A18X+141573Y+104276X0198Y0197     S2      
327GND              C2624 -2          A18X+143325Y+102301X0198Y0197R180 S2      
327GND              C2625 -2          A18X+136588Y+101076X0198Y0197R180 S2      
327GND              C2626 -2          A18X+136910Y+104349X0198Y0197     S2      
327GND              C2627 -2          A01X+139173Y+103230X0198Y0197R180 S1      
327GND              C2628 -2          A18X+146723Y+104076X0198Y0197     S2      
327GND              C2629 -2          A18X+137923Y+104726X0198Y0197     S2      
327GND              C2630 -2          A18X+145273Y+104076X0198Y0197     S2      
327GND              C2631 -2          A18X+137330Y+102256X0198Y0197R180 S2      
327GND              C2632 -2          A18X+137330Y+101902X0198Y0197R180 S2      
327GND              C2633 -2          A01X+143373Y+102893X0198Y0197R270 S1      
327GND              C2634 -2          A18X+142625Y+102893X0198Y0197R090 S2      
327GND              C2635 -2          A01X+142251Y+102893X0198Y0197R270 S1      
327GND              C2636 -2          A18X+141877Y+102893X0198Y0197R090 S2      
327GND              C2637 -2          A18X+138078Y+101547X0198Y0197R180 S2      
327GND              C2638 -2          A18X+139488Y+101734X0198Y0197R180 S2      
327GND              C2639 -2          A18X+146773Y+104726X0198Y0197     S2      
327GND              C2640 -2          A18X+143823Y+104726X0198Y0197     S2      
327GND              C2641 -2          A01X+142999Y+102893X0198Y0197R270 S1      
327GND              C2642 -2          A01X+140381Y+102893X0198Y0197R270 S1      
327GND              C2643 -2          A18X+137330Y+101547X0198Y0197R180 S2      
327GND              C2644 -2          A18X+139488Y+101360X0198Y0197R180 S2      
327GND              C2645 -2          A18X+144573Y+104076X0198Y0197     S2      
327GND              C2646 -2          A18X+142323Y+104726X0198Y0197     S2      
327GND              C2647 -2          A18X+145466Y+103726X0198Y0197     S2      
327GND              C2648 -2          A18X+141573Y+103876X0198Y0197     S2      
327GND              C2649 -2          A18X+138078Y+101902X0198Y0197R180 S2      
327GND              C2650 -2          A18X+136910Y+103099X0198Y0197     S2      
327GND              C2651 -2          A18X+146023Y+104076X0198Y0197     S2      
327GND              C2652 -2          A18X+146023Y+104726X0198Y0197     S2      
327GND              C2653 -2          A18X+143823Y+104076X0198Y0197     S2      
327GND              C2654 -2          A18X+136582Y+101902X0198Y0197R180 S2      
327GND              C2655 -2          A18X+136582Y+102256X0198Y0197R180 S2      
327GND              C2656 -2          A18X+143073Y+104726X0198Y0197     S2      
327GND              C2657 -2          A01X+142302Y+102301X0198Y0197     S1      
327GND              C2658 -2          A18X+142251Y+102893X0198Y0197R090 S2      
327GND              C2660 -2          A18X+041874Y+100986X0198Y0197R180 S2      
327GND              C2661 -2          A18X+038664Y+100377X0198Y0197     S2      
327GND              C2663 -2          A18X+039175Y+099449X0198Y0197R180 S2      
327GND              C2664 -2          A01X+042819Y+101477X0198Y0197     S1      
327GND              C2665 -2          A18X+039875Y+099449X0198Y0197R180 S2      
327GND              C2667 -2          A01X+041874Y+100986X0198Y0197     S1      
327GND              C2668 -2          A18X+042819Y+101477X0198Y0197R180 S2      
327GND              C2669 -2          A18X+039185Y+098777X0198Y0197R180 S2      
327GND              C2670 -2          A18X+039135Y+098177X0198Y0197R180 S2      
327GND              C2671 -2          A01X+041874Y+100612X0198Y0197     S1      
327GND              C2672 -2          A18X+039185Y+100027X0198Y0197R180 S2      
327GND              C2673 -2          A18X+039935Y+098777X0198Y0197R180 S2      
327GND              C3888 -2          A18X+142302Y+101474X0198Y0197R180 S2      
327GND              C3889 -2          A18X+141416Y+101474X0198Y0197R180 S2      
327GND              C3890 -2          A18X+140123Y+104726X0198Y0197     S2      
327GND              C3891 -2          A18X+143373Y+102893X0198Y0197R090 S2      
327GND              C3892 -2          A18X+143872Y+103230X0198Y0197     S2      
327GND              C3893 -2          A01X+143325Y+102301X0198Y0197     S1      
327GND              C3894 -2          A18X+143673Y+099776X0198Y0197     S2      
327GND              C3895 -2          A01X+140380Y+100950X0198Y0197R090 S1      
327GND              C3896 -2          A18X+144423Y+099126X0198Y0197     S2      
327GND              C3897 -2          A01X+139488Y+100986X0198Y0197     S1      
327GND              C3898 -2          A01X+140432Y+102301X0198Y0197     S1      
327GND              C3899 -2          A01X+140432Y+101888X0198Y0197     S1      
327GND              C3900 -2          A01X+045758Y+100950X0198Y0197R090 S1      
327GND              C3901 -2          A18X+044262Y+100950X0198Y0197R270 S2      
327GND              C3902 -2          A18X+042508Y+104077X0198Y0197     S2      
327GND              C3903 -2          A18X+041758Y+104077X0198Y0197     S2      
327GND              C3904 -2          A18X+043958Y+103877X0198Y0197     S2      
327GND              C3905 -2          A18X+043958Y+104277X0198Y0197     S2      
327GND              C3906 -2          A01X+045010Y+100950X0198Y0197R090 S1      
327GND              C3907 -2          A18X+045010Y+100950X0198Y0197R270 S2      
327GND              C3908 -2          A18X+044636Y+100950X0198Y0197R270 S2      
327GND              C3909 -2          A18X+041874Y+100612X0198Y0197R180 S2      
327GND              C3910 -2          A18X+041874Y+102108X0198Y0197R180 S2      
327GND              C3911 -2          A01X+041874Y+102856X0198Y0197     S1      
327GND              C3912 -2          A18X+047750Y+102256X0198Y0197     S2      
327GND              C3913 -2          A18X+048808Y+102774X0198Y0197     S2      
327GND              C3914 -2          A18X+047750Y+101547X0198Y0197     S2      
327GND              C3915 -2          A18X+048508Y+101547X0198Y0197     S2      
327GND              C3916 -2          A18X+047750Y+101902X0198Y0197     S2      
327GND              C3917 -2          A18X+048058Y+102774X0198Y0197     S2      
327GND              C3918 -2          A18X+048508Y+100727X0198Y0197     S2      
327GND              C3919 -2          A18X+048408Y+104727X0198Y0197     S2      
327GND              C3920 -2          A01X+041559Y+103230X0198Y0197R180 S1      
327GND              C3921 -2          A18X+042393Y+102893X0198Y0197R090 S2      
327GND              C3922 -2          A18X+039558Y+104727X0198Y0197     S2      
327GND              C3925 -2          A18X+141502Y+100950X0198Y0197R270 S2      
327GND              C3926 -2          A18X+142302Y+101888X0198Y0197R180 S2      
327GND              C3927 -2          A01X+141876Y+100950X0198Y0197R090 S1      
327GND              C3928 -2          A01X+141128Y+100950X0198Y0197R090 S1      
327GND              C3929 -2          A01X+141502Y+100950X0198Y0197R090 S1      
327GND              C3930 -2          A01X+140754Y+100950X0198Y0197R090 S1      
327GND              C3931 -2          A18X+141780Y+099376X0198Y0197R180 S2      
327GND              C3932 -2          A18X+139373Y+104726X0198Y0197     S2      
327GND              C3933 -2          A18X+138623Y+104726X0198Y0197     S2      
327GND              C3934 -2          A18X+140823Y+104726X0198Y0197     S2      
327GND              C3935 -2          A18X+139173Y+103230X0198Y0197     S2      
327GND              C4178 -2          A18X+137685Y+097826X0198Y0197R180 S2      
327GND              C4179 -2          A18X+143123Y+098776X0198Y0197     S2      
327GND              C10179-2          A18X+143873Y+098176X0198Y0197     S2      
327GND              PC6602-2          A01X+177104Y+167817X0198Y0197     S1      
327GND              PC6603-2          A01X+177104Y+168170X0198Y0197     S1      
327GND              PC6601-2          A01X+177138Y+167406X0198Y0197     S1      
327GND              PC6604-2          A01X+177104Y+168546X0198Y0197     S1      
327GND              PR6603-1          A01X+177104Y+166146X0198Y0197R180 S1      
327GND              PR6605-2          A01X+177146Y+167051X0198Y0197     S1      
327GND              PC6607-2          A01X+177150Y+166698X0198Y0197     S1      
327GND              PC6810-2          A01X+181441Y+162155X0630Y1190R090 S1      
327GND              PC6582-2          A01X+180801Y+160582X0400Y0500R180 S1      
327GND              PC6581-2          A01X+180801Y+159832X0400Y0500R180 S1      
327GND              PC6575-2          A01X+177366Y+157378X0198Y0197R090 S1      
327GND              PU6504-2   M      A01X+177878Y+157114X0090Y0240R090 S1      
327GND              PC6552-2          A01X+173791Y+157328X0198Y0197R090 S1      
327GND              PU6503-2   M      A01X+174304Y+157114X0090Y0240R090 S1      
327GND              PC6577-2          A01X+180235Y+156269X0198Y0197R270 S1      
327GND              PU6504-5          A01X+177878Y+156583X0090Y0240R090 S1      
327GND              PR6563-2          A01X+177169Y+155945X0198Y0197R090 S1      
327GND              PC6551-2   M      A01X+177366Y+156363X0198Y0197R270 S1      
327GND              PC6554-2          A01X+176661Y+156299X0198Y0197R270 S1      
327GND              PU6503-5          A01X+174304Y+156583X0090Y0240R090 S1      
327GND              PC6550-2          A01X+173791Y+156313X0198Y0197R270 S1      
327GND              PR6555-2          A01X+173594Y+155945X0198Y0197R090 S1      
327GND              PC6565-2          A01X+174069Y+153418X0198Y0197R090 S1      
327GND              PR6532-2   M      A01X+173315Y+153525X0198Y0197     S1      
327GND              PC6572-2          A01X+181948Y+148794X0630Y1190     S1      
327GND              PC6573-2          A01X+179548Y+148794X0630Y1190     S1      
327GND              PC6574-2          A01X+177148Y+148794X0630Y1190     S1      
327GND              PC6571-2          A01X+174748Y+148794X0630Y1190     S1      
327GND              PR6618-2          A18X+177244Y+166904X0198Y0197R180 S2      
327GND              PR6607-2          A18X+177124Y+167296X0198Y0197R180 S2      
317GND              VIA   -    MD0100PA00X+177494Y+166904X0200Y    R090 S0      
317GND              VIA   -    MD0100PA00X+106197Y+173192X0200Y    R180 S0      
327GND              PC534 -2          A18X+181939Y+148357X0950Y1110R090 S2      
327GND              PC6569-2          A18X+179539Y+148357X0950Y1110R090 S2      
327GND              PC6570-2          A18X+177139Y+148357X0950Y1110R090 S2      
327GND              PC6568-2          A18X+174869Y+148357X0950Y1110R090 S2      
327GND              VIA   -           A18X+180739Y+147817X0260Y    R090 S2      
327GND              VIA   -           A18X+178339Y+147817X0260Y    R090 S2      
327GND              VIA   -           A18X+175939Y+147817X0260Y    R090 S2      
327GND              VIA   -           A18X+173919Y+147817X0260Y    R090 S2      
327GND              PC89  -2          A01X+020398Y+062756X0630Y1190R270 S1      
327GND              PC83  -2          A01X+020179Y+059924X0400Y0500     S1      
327GND              PC88  -2          A01X+020179Y+059114X0400Y0500     S1      
317GND              VIA   -    MD0100PA00X+157204Y+130608X0200Y    R180 S0      
317GND              VIA   -    MD0100PA00X+005654Y+058952X0200Y    R090 S0      
317GND              VIA   -    MD0100PA00X+070761Y+006972X0200Y         S0      
317GND              VIA   -    MD0100PA00X+056125Y+010040X0200Y    R090 S0      
317GND              VIA   -    MD0100PA00X+056125Y+010698X0200Y    R090 S0      
317GND              VIA   -    MD0100PA00X+055050Y+011438X0200Y    R180 S0      
317GND              VIA   -    MD0100PA00X+055709Y+011438X0200Y    R180 S0      
327GND              VIA   -           A18X+049174Y+138207X0260Y         S2      
327GND              VIA   -           A18X+047174Y+138207X0260Y         S2      
327GND              VIA   -           A18X+045174Y+138207X0260Y         S2      
327GND              PC415_-2          A18X+024802Y+138405X0400Y0500R090 S2      
327GND              PC629_-2          A18X+011702Y+138405X0400Y0500R090 S2      
327GND              VIA   -           A18X+049174Y+136207X0260Y         S2      
327GND              VIA   -           A18X+047174Y+136207X0260Y         S2      
327GND              VIA   -           A18X+049174Y+134207X0260Y         S2      
327GND              PC144_-2          A18X+041280Y+133511X0400Y0500R270 S2      
327GND              PC145_-2          A18X+042118Y+133511X0400Y0500R270 S2      
327GND              VIA   -           A18X+049174Y+132207X0260Y         S2      
327GND              VIA   -           A18X+047174Y+132207X0260Y         S2      
327GND              PC106 -2          A18X+041066Y+132412X0950Y1110R270 S2      
327GND              PC426_-2          A18X+038860Y+131578X0400Y0500R270 S2      
327GND              PC427_-2          A18X+038022Y+131578X0400Y0500R270 S2      
327GND              PC384_-2          A18X+035580Y+131558X0400Y0500R270 S2      
327GND              PC381_-2          A18X+034742Y+131558X0400Y0500R270 S2      
327GND              PC380_-2          A18X+032289Y+131564X0400Y0500R270 S2      
327GND              PC382_-2          A18X+031451Y+131564X0400Y0500R270 S2      
327GND              PC412_-2          A18X+029000Y+131566X0400Y0500R270 S2      
327GND              PC416_-2          A18X+028162Y+131566X0400Y0500R270 S2      
327GND              VIA   -           A18X+049174Y+130207X0260Y         S2      
327GND              VIA   -           A18X+047174Y+130207X0260Y         S2      
327GND              VIA   -           A18X+045174Y+130207X0260Y         S2      
327GND              PR342 -2          A18X+043069Y+130632X0198Y0197R270 S2      
327GND              PC148_-2          A18X+042437Y+130787X0400Y0500R090 S2      
327GND              PC149_-2          A18X+039618Y+130775X0400Y0500R090 S2      
327GND              PC389 -2          A18X+037598Y+130479X0950Y1110R270 S2      
327GND              PC391 -2          A18X+034158Y+130482X0950Y1110R270 S2      
327GND              PC388 -2          A18X+030698Y+130490X0950Y1110R270 S2      
327GND              PC387 -2          A18X+027756Y+130490X0950Y1110R270 S2      
327GND              PC430_-2          A18X+038970Y+129021X0400Y0500R090 S2      
327GND              PC431_-2          A18X+036220Y+128841X0400Y0500R090 S2      
327GND              PC394_-2          A18X+035531Y+128833X0400Y0500R090 S2      
327GND              PC397_-2          A18X+032783Y+128821X0400Y0500R090 S2      
327GND              PC398_-2          A18X+032095Y+128819X0400Y0500R090 S2      
327GND              PC395_-2          A18X+029322Y+128788X0400Y0500R090 S2      
327GND              C1171 -2          A18X+073824Y+045284X0164Y0164R180 S2      
327GND              C1128 -2          A18X+073824Y+046080X0164Y0164R090 S2      
327GND              C361  -2          A18X+074139Y+045284X0164Y0164     S2      
327GND              C360  -2          A18X+074139Y+045765X0164Y0164     S2      
327GND              C1173 -2          A18X+073015Y+046080X0164Y0164R270 S2      
327GND              C1134 -2          A18X+073015Y+046395X0164Y0164R090 S2      
327GND              C1133 -2          A18X+073509Y+046080X0164Y0164R090 S2      
327GND              C1132 -2          A18X+072572Y+046395X0164Y0164R090 S2      
327GND              C1176 -2          A18X+072257Y+045284X0164Y0164     S2      
327GND              C355  -2          A18X+071942Y+045284X0164Y0164R180 S2      
327GND              C356  -2          A18X+074139Y+044828X0164Y0164     S2      
327GND              C1131 -2          A18X+072572Y+044198X0164Y0164R270 S2      
327GND              C362  -2          A18X+073015Y+044513X0164Y0164R090 S2      
327GND              C1126 -2          A18X+072264Y+044198X0164Y0164R270 S2      
327GND              PC6805-2          A01X+097441Y+125208X0630Y1190R180 S1      
327GND              PC6513-2          A01X+095041Y+125208X0630Y1190R180 S1      
327GND              PC6514-2          A01X+093591Y+124550X0198Y0197R090 S1      
327GND              PC6532-2          A01X+091542Y+125208X0630Y1190R180 S1      
327GND              PC6804-2          A01X+089142Y+125208X0630Y1190R180 S1      
327GND              PC6533-2          A01X+087692Y+124550X0198Y0197R090 S1      
327GND              PC6506-2          A01X+096947Y+115250X0198Y0197R270 S1      
327GND              PC6525-2          A01X+092245Y+115250X0198Y0197R270 S1      
327GND              PU6500-11_1       A01X+096278Y+114759X0315Y1240     S1      
327GND              PU6501-11_1       A01X+091576Y+114759X0315Y1240     S1      
327GND              PC6901-2          A01X+096530Y+113140X0400Y0500R180 S1      
327GND              PC6501-2          A01X+096542Y+112453X0400Y0500R180 S1      
327GND              PC6900-2          A01X+094450Y+112320X0400Y0500     S1      
327GND              PC6902-2          A01X+094450Y+113020X0400Y0500     S1      
327GND              PC6905-2          A01X+092170Y+113020X0400Y0500R180 S1      
327GND              PC6522-2          A01X+092170Y+112320X0400Y0500R180 S1      
327GND              PC6904-2          A01X+090150Y+113140X0400Y0500     S1      
327GND              PC6903-2          A01X+090150Y+112460X0400Y0500     S1      
327GND              PC6802-2          A01X+096542Y+111053X0400Y0500R180 S1      
327GND              PC6502-2          A01X+096542Y+111753X0400Y0500R180 S1      
327GND              PC6504-2          A01X+094450Y+110920X0400Y0500     S1      
327GND              PC6503-2          A01X+094450Y+111620X0400Y0500     S1      
327GND              PC6803-2          A01X+092170Y+110920X0400Y0500R180 S1      
327GND              PC6521-2          A01X+092170Y+111620X0400Y0500R180 S1      
327GND              PC6523-2          A01X+090150Y+111098X0400Y0500     S1      
327GND              PC6520-2          A01X+090150Y+111779X0400Y0500     S1      
327GND              PC6800-2          A01X+098784Y+109226X0630Y1380R270 S1      
327GND              PC6801-2          A01X+087610Y+109281X0630Y1380R090 S1      
317GND              VIA   -    MD0100PA00X+097211Y+113515X0200Y    R180 S0      
317GND              VIA   -    MD0100PA00X+096971Y+113702X0200Y    R180 S0      
317GND              VIA   -    MD0100PA00X+096732Y+113555X0200Y    R180 S0      
317GND              VIA   -    MD0100PA00X+096492Y+113742X0200Y    R180 S0      
317GND              VIA   -    MD0100PA00X+096301Y+113951X0200Y    R180 S0      
317GND              VIA   -    MD0100PA00X+097909Y+125774X0200Y         S0      
317GND              VIA   -    MD0100PA00X+097909Y+124592X0200Y         S0      
317GND              VIA   -    MD0100PA00X+097909Y+124892X0200Y         S0      
317GND              VIA   -    MD0100PA00X+097909Y+125474X0200Y         S0      
317GND              VIA   -    MD0100PA00X+097909Y+125174X0200Y         S0      
317GND              VIA   -    MD0100PA00X+096969Y+125774X0200Y         S0      
317GND              VIA   -    MD0100PA00X+096406Y+125218X0200Y         S0      
317GND              VIA   -    MD0100PA00X+096399Y+124592X0200Y         S0      
317GND              VIA   -    MD0100PA00X+096399Y+124892X0200Y         S0      
317GND              VIA   -    MD0100PA00X+096969Y+125174X0200Y         S0      
317GND              VIA   -    MD0100PA00X+096969Y+125474X0200Y         S0      
317GND              VIA   -    MD0100PA00X+095509Y+125774X0200Y         S0      
317GND              VIA   -    MD0100PA00X+095589Y+124892X0200Y         S0      
317GND              VIA   -    MD0100PA00X+095589Y+124592X0200Y         S0      
317GND              VIA   -    MD0100PA00X+095509Y+125174X0200Y         S0      
317GND              VIA   -    MD0100PA00X+095509Y+125474X0200Y         S0      
317GND              VIA   -    MD0100PA00X+094569Y+125774X0200Y         S0      
317GND              VIA   -    MD0100PA00X+093646Y+124884X0200Y         S0      
317GND              VIA   -    MD0100PA00X+094092Y+125186X0200Y         S0      
317GND              VIA   -    MD0100PA00X+094079Y+124592X0200Y         S0      
317GND              VIA   -    MD0100PA00X+094079Y+124892X0200Y         S0      
317GND              VIA   -    MD0100PA00X+094569Y+125174X0200Y         S0      
317GND              VIA   -    MD0100PA00X+094569Y+125474X0200Y         S0      
327GND              U263  -TH  M      A01X+028625Y+015480X0670Y0670     S1      
327GND              U263  -10         A01X+029176Y+015382X0090Y0240R270 S1      
327GND              OSC1  -2          A01X+085009Y+009965X0480Y0590R270 S1      
327GND              U326  -2          A01X+162154Y+055899X0070Y0320R090 S1      
327GND              U326  -6          A01X+162154Y+055269X0070Y0320R090 S1      
327GND              U326  -11_1       A01X+163167Y+055318X0315Y1240     S1      
327GND              U272  -4          A01X+039982Y+163415X0240Y0520     S1      
327GND              U6002 -TH  M      A01X+044409Y+012401X2362Y2362R090 S1      
327GND              U6001 -TH  M      A01X+052242Y+014517X2050Y2050R180 S1      
327GND              U6001 -40         A01X+050726Y+014990X0070Y0520R270 S1      
327GND              U6003 -4          A01X+043052Y+024877X0350Y0500R270 S1      
317GND              VIA   -    MD0100PA00X+173713Y+140124X0200Y         S0      
317GND              VIA   -    MD0100PA00X+173713Y+140384X0200Y         S0      
327GND              PC8004-2          A18X+173350Y+140250X0400Y0500     S2      
327GND              PC218_-2          A18X+171984Y+137877X0400Y0500R270 S2      
327GND              PC212_-2          A18X+171271Y+137862X0400Y0500R270 S2      
327GND              PC214_-2          A18X+170471Y+137862X0400Y0500R270 S2      
327GND              PC211_-2          A18X+167993Y+137852X0400Y0500R270 S2      
327GND              PC213_-2          A18X+167193Y+137852X0400Y0500R270 S2      
327GND              PC800 -2          A18X+172797Y+136558X0950Y1110R270 S2      
327GND              PC226 -2          A18X+170047Y+136696X0950Y1110R270 S2      
327GND              PC223 -2          A18X+166799Y+136678X0950Y1110R270 S2      
327GND              VIA   -           A18X+165130Y+136376X0260Y         S2      
327GND              VIA   -           A18X+174806Y+135819X0260Y         S2      
327GND              PC227_-2          A18X+171420Y+134965X0400Y0500R090 S2      
327GND              PC224_-2          A18X+168318Y+134999X0400Y0500R090 S2      
327GND              PC221_-2          A18X+165418Y+134999X0400Y0500R090 S2      
327GND              PC225_-2          A18X+164618Y+134999X0400Y0500R090 S2      
327GND              VIA   -           A18X+174806Y+132819X0260Y    R180 S2      
327GND              PR414 -2          A18X+168015Y+130798X0198Y0197R090 S2      
327GND              VIA   -           A18X+174806Y+129819X0260Y    R180 S2      
327GND              PC6818-2          A18X+011222Y+158831X0400Y0500R090 S2      
327GND              VIA   -           A18X+008618Y+145184X0260Y    R090 S2      
327GND              PC6814-2          A18X+009608Y+145724X0950Y1110R090 S2      
327GND              PC6627-2          A18X+007418Y+145724X0950Y1110R090 S2      
327GND              VIA   -           A18X+006218Y+145184X0260Y    R090 S2      
327GND              PC6626-2          A18X+005008Y+145724X0950Y1110R090 S2      
327GND              VIA   -           A18X+003818Y+145184X0260Y    R090 S2      
327GND              VIA   -           A18X+001668Y+145184X0260Y    R090 S2      
327GND              PC6628-2          A18X+002618Y+145724X0950Y1110R090 S2      
317GND              VIA   -    MD0100PA00X+011100Y+159202X0200Y    R180 S0      
317GND              VIA   -    MD0100PA00X+011350Y+159202X0200Y    R180 S0      
317GND              VIA   -    MD0100PA00X+011014Y+159783X0200Y    R180 S0      
317GND              VIA   -    MD0100PA00X+012862Y+156102X0200Y    R180 S0      
317GND              VIA   -    MD0100PA00X+012827Y+156874X0200Y    R180 S0      
317GND              VIA   -    MD0100PA00X+012577Y+156874X0200Y    R180 S0      
317GND              VIA   -    MD0100PA00X+012739Y+157552X0200Y    R180 S0      
317GND              VIA   -    MD0100PA00X+012737Y+157275X0200Y    R180 S0      
317GND              VIA   -    MD0100PA00X+012987Y+157275X0200Y    R180 S0      
317GND              VIA   -    MD0100PA00X+012989Y+157552X0200Y    R180 S0      
317GND              VIA   -    MD0100PA00X+090507Y+125218X0200Y         S0      
317GND              VIA   -    MD0100PA00X+072214Y+140841X0200Y    R090 S0      
317GND              VIA   -    MD0100PA00X+013987Y+068658X0200Y         S0      
317GND              VIA   -    MD0100PA00X+013186Y+066496X0200Y         S0      
317GND              VIA   -    MD0100PA00X+017330Y+066496X0200Y         S0      
317GND              VIA   -    MD0100PA00X+017280Y+068204X0200Y         S0      
317GND              VIA   -    MD0100PA00X+064994Y+057418X0200Y    R270 S0      
317GND              VIA   -    MD0100PA00X+064282Y+057418X0200Y    R270 S0      
317GND              VIA   -    MD0100PA00X+151519Y+081429X0200Y         S0      
327GND              R1391 -2          A01X+141912Y+157720X0120Y0150R180 S1      
327GND              R1392 -2          A01X+141905Y+158040X0120Y0150R180 S1      
327GND              R1372 -2          A01X+041125Y+154420X0120Y0150R180 S1      
327GND              PC114_-2          A01X+136998Y+135572X0198Y0197     S1      
317GND              VIA   -    MD0100PA00X+136892Y+135902X0200Y         S0      
317GND              VIA   -    MD0100PA00X+084866Y+065113X0200Y         S0      
327GND              PC6580-2          A18X+180058Y+155970X0400Y0500R270 S2      
327GND              PC6579-2          A18X+179218Y+155970X0400Y0500R270 S2      
327GND              PC6556-2          A18X+175690Y+155970X0400Y0500R270 S2      
327GND              PC6557-2          A18X+176531Y+155970X0400Y0500R270 S2      
327GND              VIA   -           A18X+174318Y+156358X0260Y    R090 S2      
327GND              PC6812-2          A18X+178709Y+154968X0950Y1110R270 S2      
327GND              PC6811-2          A18X+175819Y+154963X0950Y1110R270 S2      
327GND              VIA   -           A18X+173306Y+154377X0260Y    R090 S2      
327GND              PC6567-2          A18X+181692Y+153552X0400Y0500R090 S2      
327GND              PC6566-2          A18X+180842Y+153552X0400Y0500R090 S2      
327GND              PC6806-2          A18X+180198Y+153398X0198Y0197R270 S2      
327GND              PC6586-2          A18X+177335Y+153736X0400Y0500R090 S2      
327GND              PC6587-2          A18X+174415Y+153558X0400Y0500R090 S2      
327GND              PD17  -1          A01X+095336Y+146475X0500Y0560R270 S1      
327GND              PD17  -2          A01X+094518Y+146475X0500Y0560R270 S1      
327GND              PD111 -1          A01X+085348Y+152604X0500Y0560R270 S1      
327GND              PD111 -2          A01X+084529Y+152604X0500Y0560R270 S1      
317GND              VIA   -    MD0100PA00X+085857Y+152142X0200Y    R090 S0      
317GND              VIA   -    MD0100PA00X+085858Y+151857X0200Y    R090 S0      
317GND              VIA   -    MD0100PA00X+085585Y+151868X0200Y    R090 S0      
317GND              VIA   -    MD0100PA00X+085321Y+151863X0200Y    R090 S0      
317GND              VIA   -    MD0100PA00X+085015Y+151864X0200Y    R090 S0      
317GND              VIA   -    MD0100PA00X+085015Y+152126X0200Y    R090 S0      
317GND              VIA   -    MD0100PA00X+085321Y+152126X0200Y    R090 S0      
317GND              VIA   -    MD0100PA00X+085585Y+152131X0200Y    R090 S0      
317GND              VIA   -    MD0100PA00X+084127Y+152159X0200Y    R090 S0      
317GND              VIA   -    MD0100PA00X+083863Y+152154X0200Y    R090 S0      
317GND              VIA   -    MD0100PA00X+084131Y+151861X0200Y    R090 S0      
317GND              VIA   -    MD0100PA00X+083867Y+151856X0200Y    R090 S0      
317GND              VIA   -    MD0100PA00X+084701Y+151883X0200Y    R090 S0      
317GND              VIA   -    MD0100PA00X+084437Y+151878X0200Y    R090 S0      
317GND              VIA   -    MD0100PA00X+084437Y+152141X0200Y    R090 S0      
317GND              VIA   -    MD0100PA00X+084701Y+152146X0200Y    R090 S0      
317GND              VIA   -    MD0100PA00X+095090Y+145688X0200Y    R090 S0      
317GND              VIA   -    MD0100PA00X+094826Y+145683X0200Y    R090 S0      
317GND              VIA   -    MD0100PA00X+094520Y+145683X0200Y    R090 S0      
317GND              VIA   -    MD0100PA00X+094206Y+145703X0200Y    R090 S0      
317GND              VIA   -    MD0100PA00X+093942Y+145698X0200Y    R090 S0      
317GND              VIA   -    MD0100PA00X+095362Y+145961X0200Y    R090 S0      
317GND              VIA   -    MD0100PA00X+094826Y+145945X0200Y    R090 S0      
317GND              VIA   -    MD0100PA00X+095090Y+145950X0200Y    R090 S0      
317GND              VIA   -    MD0100PA00X+093942Y+145960X0200Y    R090 S0      
317GND              VIA   -    MD0100PA00X+094206Y+145965X0200Y    R090 S0      
317GND              VIA   -    MD0100PA00X+087748Y+124884X0200Y         S0      
317GND              VIA   -    MD0100PA00X+092312Y+113705X0200Y    R180 S0      
317GND              VIA   -    MD0100PA00X+092552Y+113517X0200Y    R180 S0      
317GND              VIA   -    MD0100PA00X+092148Y+113465X0200Y    R180 S0      
317GND              VIA   -    MD0100PA00X+091908Y+113652X0200Y    R180 S0      
317GND              VIA   -    MD0100PA00X+005579Y+150922X0200Y         S0      
317GND              VIA   -    MD0100PA00X+004933Y+150914X0200Y         S0      
317GND              VIA   -    MD0100PA00X+005233Y+150914X0200Y         S0      
317GND              VIA   -    MD0100PA00X+004940Y+151199X0200Y         S0      
317GND              VIA   -    MD0100PA00X+005240Y+151199X0200Y         S0      
317GND              VIA   -    MD0100PA00X+008890Y+150870X0200Y         S0      
317GND              VIA   -    MD0100PA00X+008540Y+150870X0200Y         S0      
317GND              VIA   -    MD0100PA00X+008190Y+150870X0200Y         S0      
317GND              VIA   -    MD0100PA00X+005856Y+157021X0200Y    R090 S0      
317GND              VIA   -    MD0100PA00X+006122Y+157028X0200Y    R090 S0      
317GND              VIA   -    MD0100PA00X+006392Y+155625X0200Y    R090 S0      
317GND              VIA   -    MD0100PA00X+006392Y+155880X0200Y    R090 S0      
317GND              VIA   -    MD0100PA00X+174040Y+154368X0200Y         S0      
317GND              VIA   -    MD0100PA00X+177261Y+154117X0200Y         S0      
317GND              VIA   -    MD0100PA00X+176911Y+154117X0200Y         S0      
317GND              VIA   -    MD0100PA00X+177611Y+154117X0200Y         S0      
317GND              VIA   -    MD0100PA00X+181625Y+161378X0200Y    R090 S0      
317GND              VIA   -    MD0100PA00X+181275Y+161378X0200Y    R090 S0      
317GND              VIA   -    MD0100PA00X+180925Y+161378X0200Y    R090 S0      
317GND              VIA   -    MD0100PA00X+181208Y+160022X0200Y    R090 S0      
317GND              VIA   -    MD0100PA00X+181200Y+160388X0200Y    R090 S0      
317GND              VIA   -    MD0100PA00X+181200Y+160738X0200Y    R090 S0      
317GND              VIA   -    MD0100PA00X+181208Y+159672X0200Y    R090 S0      
327GND              PC6561-2          A01X+174515Y+162165X0630Y1190R270 S1      
327GND              SW1   -1          A01X+166910Y+016676X0300Y0500R270 S1      
327GND              SW1   -3          A01X+166910Y+015676X0300Y0500R270 S1      
327GND              SW1   -9          A01X+166910Y+012676X0300Y0500R270 S1      
317GND              VIA   -    M      A01X+083443Y+043463X0200Y         S2      
017GND              VIA   -    M      A18X+083443Y+043463X0260Y         S2      
017GND                    -    MD0100PA00X+083443Y+043463                       
317GND              VIA   -    MD0100PA00X+080275Y+045534X0200Y         S0      
327GND              U6014 -FC9 M      A01X+018355Y+153162X0120Y         S1      
327GND              U6014 -V35 M      A01X+025401Y+150946X0100Y0130     S1      
327GND              U6014 -AE35M      A01X+024928Y+150946X0100Y0130     S1      
327GND              U6014 -AW35M      A01X+023984Y+150946X0100Y0130     S1      
327GND              U6014 -AM35M      A01X+024456Y+150946X0100Y0130     S1      
327GND              U6014 -BY35M      A01X+022566Y+150946X0100Y0130     S1      
327GND              U6014 -BN35M      A01X+023039Y+150946X0100Y0130     S1      
327GND              U6014 -BF35M      A01X+023511Y+150946X0100Y0130     S1      
327GND              U6014 -DA35M      A01X+021149Y+150946X0100Y0130     S1      
327GND              U6014 -CP35M      A01X+021621Y+150946X0100Y0130     S1      
327GND              U6014 -CG35M      A01X+022094Y+150946X0100Y0130     S1      
327GND              U6014 -EJ35M      A01X+019259Y+150946X0100Y0130     S1      
327GND              U6014 -EB35M      A01X+019732Y+150946X0100Y0130     S1      
327GND              U6014 -DR35M      A01X+020204Y+150946X0100Y0130     S1      
327GND              U6014 -DH35M      A01X+020676Y+150946X0100Y0130     S1      
327GND              U6014 -ET35M      A01X+018787Y+150946X0100Y0130     S1      
327GND              U6014 -FD35M      A01X+018314Y+150946X0100Y0130     S1      
327GND              U6015 -V35 M      A01X+038207Y+150946X0100Y0130     S1      
327GND              U6015 -AE35M      A01X+037734Y+150946X0100Y0130     S1      
327GND              U6015 -AW35M      A01X+036790Y+150946X0100Y0130     S1      
327GND              U6015 -AM35M      A01X+037262Y+150946X0100Y0130     S1      
327GND              U6015 -BY35M      A01X+035372Y+150946X0100Y0130     S1      
327GND              U6015 -BN35M      A01X+035845Y+150946X0100Y0130     S1      
327GND              U6015 -BF35M      A01X+036317Y+150946X0100Y0130     S1      
327GND              U6015 -DA35M      A01X+033955Y+150946X0100Y0130     S1      
327GND              U6015 -CP35M      A01X+034428Y+150946X0100Y0130     S1      
327GND              U6015 -CG35M      A01X+034900Y+150946X0100Y0130     S1      
327GND              U6015 -EJ35M      A01X+032065Y+150946X0100Y0130     S1      
327GND              U6015 -EB35M      A01X+032538Y+150946X0100Y0130     S1      
327GND              U6015 -DR35M      A01X+033010Y+150946X0100Y0130     S1      
327GND              U6015 -DH35M      A01X+033483Y+150946X0100Y0130     S1      
327GND              U6015 -ET35M      A01X+031593Y+150946X0100Y0130     S1      
327GND              U6017 -V35 M      A01X+051818Y+150946X0100Y0130     S1      
327GND              U6017 -AE35M      A01X+051346Y+150946X0100Y0130     S1      
327GND              U6017 -AW35M      A01X+050401Y+150946X0100Y0130     S1      
327GND              U6017 -AM35M      A01X+050873Y+150946X0100Y0130     S1      
327GND              U6017 -BY35M      A01X+048983Y+150946X0100Y0130     S1      
327GND              U6017 -BN35M      A01X+049456Y+150946X0100Y0130     S1      
327GND              U6017 -BF35M      A01X+049928Y+150946X0100Y0130     S1      
327GND              U6017 -DA35M      A01X+047566Y+150946X0100Y0130     S1      
327GND              U6017 -CP35M      A01X+048039Y+150946X0100Y0130     S1      
327GND              U6017 -CG35M      A01X+048511Y+150946X0100Y0130     S1      
327GND              U6017 -EJ35M      A01X+045676Y+150946X0100Y0130     S1      
327GND              U6017 -EB35M      A01X+046149Y+150946X0100Y0130     S1      
327GND              U6017 -DR35M      A01X+046621Y+150946X0100Y0130     S1      
327GND              U6017 -DH35M      A01X+047094Y+150946X0100Y0130     S1      
327GND              U6017 -ET35M      A01X+045204Y+150946X0100Y0130     S1      
327GND              U6017 -FD35M      A01X+044732Y+150946X0100Y0130     S1      
327GND              U6016 -V35 M      A01X+064624Y+150946X0100Y0130     S1      
327GND              U6016 -AE35M      A01X+064152Y+150946X0100Y0130     S1      
327GND              U6016 -AW35M      A01X+063207Y+150946X0100Y0130     S1      
327GND              U6016 -AM35M      A01X+063679Y+150946X0100Y0130     S1      
327GND              U6016 -BY35M      A01X+061790Y+150946X0100Y0130     S1      
327GND              U6016 -BN35M      A01X+062262Y+150946X0100Y0130     S1      
327GND              U6016 -BF35M      A01X+062734Y+150946X0100Y0130     S1      
327GND              U6016 -DA35M      A01X+060372Y+150946X0100Y0130     S1      
327GND              U6016 -CP35M      A01X+060845Y+150946X0100Y0130     S1      
327GND              U6016 -CG35M      A01X+061317Y+150946X0100Y0130     S1      
327GND              U6016 -EJ35M      A01X+058483Y+150946X0100Y0130     S1      
327GND              U6016 -EB35M      A01X+058955Y+150946X0100Y0130     S1      
327GND              U6016 -DR35M      A01X+059427Y+150946X0100Y0130     S1      
327GND              U6016 -DH35M      A01X+059900Y+150946X0100Y0130     S1      
327GND              U6016 -ET35M      A01X+058010Y+150946X0100Y0130     S1      
327GND              U6012 -V35 M      A01X+165412Y+154246X0100Y0130     S1      
327GND              U6012 -AE35M      A01X+164939Y+154246X0100Y0130     S1      
327GND              U6012 -AW35M      A01X+163994Y+154246X0100Y0130     S1      
327GND              U6012 -AM35M      A01X+164467Y+154246X0100Y0130     S1      
327GND              U6012 -BY35M      A01X+162577Y+154246X0100Y0130     S1      
327GND              U6012 -BN35M      A01X+163050Y+154246X0100Y0130     S1      
327GND              U6012 -BF35M      A01X+163522Y+154246X0100Y0130     S1      
327GND              U6012 -DA35M      A01X+161160Y+154246X0100Y0130     S1      
327GND              U6012 -CP35M      A01X+161632Y+154246X0100Y0130     S1      
327GND              U6012 -CG35M      A01X+162105Y+154246X0100Y0130     S1      
327GND              U6012 -EJ35M      A01X+159270Y+154246X0100Y0130     S1      
327GND              U6012 -EB35M      A01X+159742Y+154246X0100Y0130     S1      
327GND              U6012 -DR35M      A01X+160215Y+154246X0100Y0130     S1      
327GND              U6012 -DH35M      A01X+160687Y+154246X0100Y0130     S1      
327GND              U6012 -ET35M      A01X+158798Y+154246X0100Y0130     S1      
327GND              U6013 -V35 M      A01X+152606Y+154246X0100Y0130     S1      
327GND              U6013 -AE35M      A01X+152133Y+154246X0100Y0130     S1      
327GND              U6013 -AW35M      A01X+151188Y+154246X0100Y0130     S1      
327GND              U6013 -AM35M      A01X+151661Y+154246X0100Y0130     S1      
327GND              U6013 -BY35M      A01X+149771Y+154246X0100Y0130     S1      
327GND              U6013 -BN35M      A01X+150243Y+154246X0100Y0130     S1      
327GND              U6013 -BF35M      A01X+150716Y+154246X0100Y0130     S1      
327GND              U6013 -DA35M      A01X+148354Y+154246X0100Y0130     S1      
327GND              U6013 -CP35M      A01X+148826Y+154246X0100Y0130     S1      
327GND              U6013 -CG35M      A01X+149298Y+154246X0100Y0130     S1      
327GND              U6013 -EJ35M      A01X+146464Y+154246X0100Y0130     S1      
327GND              U6013 -EB35M      A01X+146936Y+154246X0100Y0130     S1      
327GND              U6013 -DR35M      A01X+147409Y+154246X0100Y0130     S1      
327GND              U6013 -DH35M      A01X+147881Y+154246X0100Y0130     S1      
327GND              U6013 -ET35M      A01X+145991Y+154246X0100Y0130     S1      
327GND              U6013 -FD35M      A01X+145519Y+154246X0100Y0130     S1      
327GND              U6011 -V35 M      A01X+138994Y+154246X0100Y0130     S1      
327GND              U6011 -AE35M      A01X+138522Y+154246X0100Y0130     S1      
327GND              U6011 -AW35M      A01X+137577Y+154246X0100Y0130     S1      
327GND              U6011 -AM35M      A01X+138049Y+154246X0100Y0130     S1      
327GND              U6011 -BY35M      A01X+136160Y+154246X0100Y0130     S1      
327GND              U6011 -BN35M      A01X+136632Y+154246X0100Y0130     S1      
327GND              U6011 -BF35M      A01X+137104Y+154246X0100Y0130     S1      
327GND              U6011 -DA35M      A01X+134742Y+154246X0100Y0130     S1      
327GND              U6011 -CP35M      A01X+135215Y+154246X0100Y0130     S1      
327GND              U6011 -CG35M      A01X+135687Y+154246X0100Y0130     S1      
327GND              U6011 -EJ35M      A01X+132853Y+154246X0100Y0130     S1      
327GND              U6011 -EB35M      A01X+133325Y+154246X0100Y0130     S1      
327GND              U6011 -DR35M      A01X+133797Y+154246X0100Y0130     S1      
327GND              U6011 -DH35M      A01X+134270Y+154246X0100Y0130     S1      
327GND              U6011 -ET35M      A01X+132380Y+154246X0100Y0130     S1      
327GND              PC261 -2          A18X+132744Y+060731X0400Y0500     S2      
327GND              C1094 -2          A18X+083800Y+128132X0198Y0197     S2      
317GND              VIA   -    MD0100PA00X+087604Y+144432X0200Y         S0      
317GND              VIA   -    MD0100PA00X+130056Y+155426X0200Y         S0      
327GND              U6010 -BY35M      A01X+123353Y+154246X0100Y0130     S1      
327GND              U6010 -AE35M      A01X+125716Y+154246X0100Y0130     S1      
327GND              U6010 -DA35M      A01X+121936Y+154246X0100Y0130     S1      
327GND              U6010 -CP35M      A01X+122409Y+154246X0100Y0130     S1      
327GND              U6010 -CG35M      A01X+122881Y+154246X0100Y0130     S1      
327GND              U6010 -BN35M      A01X+123826Y+154246X0100Y0130     S1      
327GND              U6010 -BF35M      A01X+124298Y+154246X0100Y0130     S1      
327GND              U6010 -AW35M      A01X+124771Y+154246X0100Y0130     S1      
327GND              U6010 -AM35M      A01X+125243Y+154246X0100Y0130     S1      
327GND              U6010 -V35 M      A01X+126188Y+154246X0100Y0130     S1      
317GND              VIA   -    MD0100PA00X+070617Y+155208X0200Y    R090 S0      
327GND              U6010 -DR35M      A01X+120991Y+154246X0100Y0130     S1      
327GND              U6010 -DH35M      A01X+121464Y+154246X0100Y0130     S1      
327GND              U6010 -ET35M      A01X+119574Y+154246X0100Y0130     S1      
327GND              U6010 -EJ35M      A01X+120046Y+154246X0100Y0130     S1      
327GND              U6010 -EB35M      A01X+120519Y+154246X0100Y0130     S1      
317GND              VIA   -    MD0100PA00X+048891Y+024275X0200Y    R270 S0      
317GND              VIA   -    MD0100PA00X+066417Y+044571X0200Y    R090 S0      
317GND              VIA   -    MD0100PA00X+056248Y+024272X0200Y    R180 S0      
317GND              VIA   -    MD0100PA00X+050172Y+024056X0200Y    R270 S0      
317GND              VIA   -    MD0100PA00X+108186Y+026986X0200Y    R180 S0      
317GND              VIA   -    MD0100PA00X+084120Y+136138X0200Y         S0      
317GND              VIA   -    MD0100PA00X+083919Y+134894X0200Y         S0      
317GND              VIA   -    MD0100PA00X+083407Y+134246X0200Y         S0      
317GND              VIA   -    MD0100PA00X+083402Y+133358X0200Y         S0      
317GND              VIA   -    MD0100PA00X+065301Y+044320X0200Y    R090 S0      
317GND              VIA   -    MD0100PA00X+059556Y+023913X0200Y    R180 S0      
317GND              VIA   -    MD0100PA00X+093304Y+131592X0200Y         S0      
317GND              VIA   -    MD0100PA00X+092787Y+131742X0200Y         S0      
317GND              VIA   -    MD0100PA00X+093359Y+132550X0200Y         S0      
317GND              VIA   -    MD0100PA00X+092368Y+133952X0200Y         S0      
317GND              VIA   -    MD0100PA00X+091976Y+134899X0200Y         S0      
317GND              VIA   -    MD0100PA00X+092074Y+132136X0200Y         S0      
317GND              VIA   -    MD0100PA00X+099223Y+037368X0200Y    R270 S0      
317GND              VIA   -    MD0100PA00X+099749Y+037029X0200Y    R270 S0      
317GND              VIA   -    MD0100PA00X+094100Y+112896X0200Y    R180 S0      
317GND              VIA   -    MD0100PA00X+094100Y+113156X0200Y    R180 S0      
317GND              VIA   -    MD0100PA00X+094100Y+112196X0200Y    R180 S0      
317GND              VIA   -    MD0100PA00X+094100Y+112456X0200Y    R180 S0      
317GND              VIA   -    MD0100PA00X+094100Y+111496X0200Y    R180 S0      
317GND              VIA   -    MD0100PA00X+094100Y+111756X0200Y    R180 S0      
317GND              VIA   -    MD0100PA00X+094100Y+110796X0200Y    R180 S0      
317GND              VIA   -    MD0100PA00X+094100Y+111056X0200Y    R180 S0      
317GND              VIA   -    MD0100PA00X+096892Y+111178X0200Y         S0      
317GND              VIA   -    MD0100PA00X+096892Y+110918X0200Y         S0      
317GND              VIA   -    MD0100PA00X+096892Y+111878X0200Y         S0      
317GND              VIA   -    MD0100PA00X+096892Y+111618X0200Y         S0      
317GND              VIA   -    MD0100PA00X+096892Y+112578X0200Y         S0      
317GND              VIA   -    MD0100PA00X+096892Y+112318X0200Y         S0      
317GND              VIA   -    MD0100PA00X+096880Y+113265X0200Y         S0      
317GND              VIA   -    MD0100PA00X+096880Y+113005X0200Y         S0      
317GND              VIA   -    MD0100PA00X+089800Y+111914X0200Y    R180 S0      
317GND              VIA   -    MD0100PA00X+089800Y+111654X0200Y    R180 S0      
317GND              VIA   -    MD0100PA00X+089800Y+112595X0200Y    R180 S0      
317GND              VIA   -    MD0100PA00X+089800Y+112335X0200Y    R180 S0      
317GND              VIA   -    MD0100PA00X+089800Y+113276X0200Y    R180 S0      
317GND              VIA   -    MD0100PA00X+089800Y+113016X0200Y    R180 S0      
317GND              VIA   -    MD0100PA00X+092520Y+112884X0200Y         S0      
317GND              VIA   -    MD0100PA00X+092520Y+113144X0200Y         S0      
317GND              VIA   -    MD0100PA00X+092520Y+112184X0200Y         S0      
317GND              VIA   -    MD0100PA00X+092520Y+112444X0200Y         S0      
317GND              VIA   -    MD0100PA00X+092520Y+111484X0200Y         S0      
317GND              VIA   -    MD0100PA00X+092520Y+111744X0200Y         S0      
317GND              VIA   -    MD0100PA00X+092520Y+110784X0200Y         S0      
317GND              VIA   -    MD0100PA00X+092520Y+111044X0200Y         S0      
317GND              VIA   -    MD0100PA00X+069764Y+073340X0190Y         S0      
327GND              R845  -2          A18X+100855Y+131050X0120Y0150     S2      
317GND              VIA   -    MD0100PA00X+101065Y+131050X0200Y    R180 S0      
317GND              VIA   -    MD0100PA00X+108382Y+035309X0200Y    R090 S0      
317GND              VIA   -    MD0100PA00X+101300Y+130650X0200Y         S0      
317GND              VIA   -    MD0100PA00X+101350Y+131250X0200Y         S0      
317GND              VIA   -    MD0100PA00X+101350Y+132550X0200Y         S0      
317GND              VIA   -    MD0100PA00X+101150Y+133500X0200Y         S0      
317GND              VIA   -    MD0100PA00X+101350Y+134450X0200Y         S0      
317GND              VIA   -    MD0100PA00X+105150Y+026513X0200Y    R180 S0      
317GND              VIA   -    MD0100PA00X+104401Y+026866X0200Y    R180 S0      
317GND              VIA   -    MD0100PA00X+105436Y+025870X0200Y    R180 S0      
317GND              VIA   -    MD0100PA00X+106184Y+051970X0200Y    R180 S0      
317GND              VIA   -    MD0100PA00X+105652Y+051279X0200Y    R180 S0      
317GND              VIA   -    MD0100PA00X+106555Y+027144X0200Y    R180 S0      
317GND              VIA   -    MD0100PA00X+116131Y+154820X0200Y         S0      
317GND              VIA   -    MD0100PA00X+144299Y+017620X0200Y    R090 S0      
317GND              VIA   -    MD0100PA00X+073701Y+008317X0200Y    R180 S0      
317GND              VIA   -    MD0100PA00X+073156Y+008368X0200Y    R180 S0      
317GND              VIA   -    MD0100PA00X+167942Y+168360X0200Y         S0      
317GND              VIA   -    MD0100PA00X+182311Y+153866X0200Y    R090 S0      
327GND              R1430 -2          A18X+064750Y+167985X0120Y0150R090 S2      
317GND              VIA   -    MD0100PA00X+064750Y+168285X0200Y         S0      
317GND              VIA   -    MD0100PA00X+143694Y+155428X0200Y    R090 S0      
317GND              VIA   -    MD0100PA00X+156484Y+155456X0200Y         S0      
327GND              Q133  -4          A01X+120795Y+167792X0170Y0200     S1      
317GND              VIA   -    MD0100PA00X+154777Y+156407X0200Y    R090 S0      
317GND              VIA   -    MD0100PA00X+154527Y+156407X0200Y    R090 S0      
317GND              VIA   -    MD0100PA00X+154277Y+156407X0200Y    R090 S0      
317GND              VIA   -    MD0100PA00X+141166Y+156407X0200Y    R090 S0      
317GND              VIA   -    MD0100PA00X+140916Y+156407X0200Y    R090 S0      
317GND              VIA   -    MD0100PA00X+140666Y+156407X0200Y    R090 S0      
317GND              VIA   -    MD0100PA00X+027572Y+153107X0200Y    R090 S0      
317GND              VIA   -    MD0100PA00X+027322Y+153107X0200Y    R090 S0      
317GND              VIA   -    MD0100PA00X+027072Y+153107X0200Y    R090 S0      
327GND              R1409 -2          A01X+167140Y+166735X0120Y0150R270 S1      
317GND              VIA   -    MD0100PA00X+003470Y+151524X0200Y    R090 S0      
327GND              R1365 -2          A18X+120985Y+168540X0120Y0150     S2      
317GND              VIA   -    MD0100PA00X+173458Y+156207X0200Y         S0      
317GND              VIA   -    MD0100PA00X+004776Y+152951X0200Y         S0      
327GND              PC6618-2          A18X+006752Y+155789X0400Y0500R180 S2      
327GND              R1370 -2          A01X+128332Y+156827X0120Y0150R180 S1      
317GND              VIA   -    MD0100PA00X+180179Y+153674X0200Y    R090 S0      
327GND              R1414 -2          A01X+154750Y+156827X0120Y0150R180 S1      
317GND              VIA   -    MD0100PA00X+173754Y+154371X0200Y         S0      
317GND              VIA   -    MD0100PA00X+128359Y+156407X0200Y    R090 S0      
317GND              VIA   -    MD0100PA00X+128109Y+156407X0200Y    R090 S0      
317GND              VIA   -    MD0100PA00X+127859Y+156407X0200Y    R090 S0      
317GND              VIA   -    MD0100PA00X+179626Y+155876X0193Y         S0      
317GND              VIA   -    MD0100PA00X+179626Y+156126X0193Y         S0      
317GND              VIA   -    MD0100PA00X+176571Y+155605X0200Y         S0      
327GND              R1373 -2          A01X+037085Y+163940X0120Y0150     S1      
317GND              VIA   -    MD0100PA00X+037231Y+164176X0200Y         S0      
317GND              VIA   -    MD0100PA00X+116559Y+056912X0200Y         S0      
317GND              VIA   -    MD0100PA00X+125256Y+007268X0200Y    R180 S0      
317GND              VIA   -    MD0100PA00X+124649Y+048330X0200Y         S0      
327GND              R1381 -2          A01X+018849Y+165877X0120Y0150R180 S1      
317GND              VIA   -    MD0100PA00X+073652Y+005807X0200Y         S0      
327GND              R1429 -2          A01X+053965Y+153471X0120Y0150R180 S1      
317GND              VIA   -    MD0100PA00X+040378Y+153107X0200Y    R090 S0      
317GND              VIA   -    MD0100PA00X+040128Y+153107X0200Y    R090 S0      
317GND              VIA   -    MD0100PA00X+039878Y+153107X0200Y    R090 S0      
327GND              R1378 -2          A01X+041350Y+153344X0120Y0150R180 S1      
327GND              R1389 -2          A01X+027545Y+153527X0120Y0150R180 S1      
327GND              R1380 -2          A01X+027545Y+153837X0120Y0150R180 S1      
327GND              R637  -2          A01X+056367Y+152133X0120Y0150R090 S1      
327GND              R641  -2          A01X+043561Y+152133X0120Y0150R090 S1      
327GND              R627  -2          A01X+017143Y+152133X0120Y0150R090 S1      
327GND              R625  -2          A01X+029950Y+152133X0120Y0150R090 S1      
317GND              VIA   -    MD0100PA00X+158703Y+130714X0200Y    R180 S0      
317GND              VIA   -    MD0100PA00X+144139Y+016394X0200Y    R090 S0      
317GND              VIA   -    MD0100PA00X+135081Y+120232X0200Y    R090 S0      
317GND              VIA   -    MD0100PA00X+106361Y+073341X0200Y         S0      
317GND              VIA   -    MD0100PA00X+136424Y+120795X0200Y    R270 S0      
317GND              VIA   -    MD0100PA00X+145918Y+016380X0200Y    R180 S0      
317GND              VIA   -    MD0100PA00X+108163Y+064885X0200Y         S0      
317GND              VIA   -    MD0100PA00X+104089Y+073572X0200Y         S0      
317GND              VIA   -    MD0100PA00X+082270Y+005671X0200Y         S0      
317GND              VIA   -    MD0100PA00X+121486Y+042102X0200Y         S0      
317GND              VIA   -    MD0100PA00X+170298Y+170033X0200Y    R270 S0      
317GND              VIA   -    MD0100PA00X+146046Y+168516X0200Y         S0      
317GND              VIA   -    MD0100PA00X+097362Y+031765X0200Y         S0      
317GND              VIA   -    MD0100PA00X+142797Y+006041X0200Y    R270 S0      
317GND              VIA   -    MD0100PA00X+145135Y+011616X0200Y         S0      
317GND              VIA   -    MD0100PA00X+120271Y+008765X0200Y    R180 S0      
317GND              VIA   -    MD0100PA00X+123555Y+007529X0200Y    R180 S0      
317GND              VIA   -    MD0100PA00X+144598Y+011695X0200Y    R090 S0      
317GND              VIA   -    MD0100PA00X+081036Y+044208X0200Y         S0      
317GND              VIA   -    MD0100PA00X+140321Y+011894X0200Y    R180 S0      
317GND              VIA   -    MD0100PA00X+082040Y+031183X0200Y    R090 S0      
317GND              VIA   -    MD0100PA00X+125490Y+141703X0200Y         S0      
317GND              VIA   -    MD0100PA00X+125232Y+141708X0200Y         S0      
317GND              VIA   -    MD0100PA00X+130394Y+143073X0200Y    R090 S0      
317GND              VIA   -    MD0100PA00X+130236Y+141870X0200Y    R090 S0      
317GND              VIA   -    MD0100PA00X+129252Y+142160X0200Y    R090 S0      
317GND              VIA   -    MD0100PA00X+131858Y+142524X0200Y         S0      
317GND              VIA   -    MD0100PA00X+132258Y+142524X0200Y         S0      
317GND              VIA   -    MD0100PA00X+132658Y+142524X0200Y         S0      
317GND              VIA   -    MD0100PA00X+133058Y+142524X0200Y         S0      
317GND              VIA   -    MD0100PA00X+133458Y+142524X0200Y         S0      
317GND              VIA   -    MD0100PA00X+133858Y+142524X0200Y         S0      
317GND              VIA   -    MD0100PA00X+134258Y+142524X0200Y         S0      
317GND              VIA   -    MD0100PA00X+134658Y+142524X0200Y         S0      
317GND              VIA   -    MD0100PA00X+135058Y+142524X0200Y         S0      
317GND              VIA   -    MD0100PA00X+135458Y+142524X0200Y         S0      
317GND              VIA   -    MD0100PA00X+135858Y+142524X0200Y         S0      
317GND              VIA   -    MD0100PA00X+136258Y+142524X0200Y         S0      
317GND              VIA   -    MD0100PA00X+143046Y+136106X0200Y         S0      
317GND              VIA   -    MD0100PA00X+142856Y+136530X0200Y         S0      
317GND              VIA   -    MD0100PA00X+142644Y+136943X0200Y         S0      
317GND              VIA   -    MD0100PA00X+142416Y+137324X0200Y         S0      
317GND              VIA   -    MD0100PA00X+142077Y+137711X0200Y         S0      
317GND              VIA   -    MD0100PA00X+141749Y+138118X0200Y         S0      
317GND              VIA   -    MD0100PA00X+141495Y+138494X0200Y         S0      
317GND              VIA   -    MD0100PA00X+141151Y+138838X0200Y         S0      
317GND              VIA   -    MD0100PA00X+140854Y+139183X0200Y         S0      
317GND              VIA   -    MD0100PA00X+140521Y+139548X0200Y         S0      
317GND              VIA   -    MD0100PA00X+140176Y+139993X0200Y         S0      
317GND              VIA   -    MD0100PA00X+139838Y+140369X0200Y         S0      
317GND              VIA   -    MD0100PA00X+139546Y+140692X0200Y         S0      
317GND              VIA   -    MD0100PA00X+139202Y+141036X0200Y         S0      
317GND              VIA   -    MD0100PA00X+138731Y+141364X0200Y         S0      
317GND              VIA   -    MD0100PA00X+138328Y+141597X0200Y         S0      
317GND              VIA   -    MD0100PA00X+137910Y+141862X0200Y         S0      
317GND              VIA   -    MD0100PA00X+137534Y+142127X0200Y         S0      
317GND              VIA   -    MD0100PA00X+137216Y+142381X0200Y         S0      
317GND              VIA   -    MD0100PA00X+136830Y+142524X0200Y         S0      
317GND              VIA   -    MD0100PA00X+131058Y+142524X0200Y         S0      
317GND              VIA   -    MD0100PA00X+131458Y+142524X0200Y         S0      
317GND              VIA   -    MD0100PA00X+037506Y+139374X0200Y         S0      
317GND              VIA   -    MD0100PA00X+037961Y+139178X0200Y         S0      
317GND              VIA   -    MD0100PA00X+038427Y+138988X0200Y         S0      
317GND              VIA   -    MD0100PA00X+038872Y+138739X0200Y         S0      
317GND              VIA   -    MD0100PA00X+039332Y+138563X0200Y         S0      
317GND              VIA   -    MD0100PA00X+039719Y+138335X0200Y         S0      
317GND              VIA   -    MD0100PA00X+040195Y+138049X0200Y         S0      
317GND              VIA   -    MD0100PA00X+040598Y+137779X0200Y         S0      
317GND              VIA   -    MD0100PA00X+041000Y+137509X0200Y         S0      
317GND              VIA   -    MD0100PA00X+041413Y+137223X0200Y         S0      
317GND              VIA   -    MD0100PA00X+021710Y+141386X0200Y         S0      
317GND              VIA   -    MD0100PA00X+022080Y+141212X0200Y         S0      
317GND              VIA   -    MD0100PA00X+022488Y+141068X0200Y         S0      
317GND              VIA   -    MD0100PA00X+022869Y+140888X0200Y         S0      
317GND              VIA   -    MD0100PA00X+023319Y+140735X0200Y         S0      
317GND              VIA   -    MD0100PA00X+143111Y+132522X0200Y         S0      
317GND              VIA   -    MD0100PA00X+143031Y+132241X0200Y         S0      
317GND              VIA   -    MD0100PA00X+142952Y+131945X0200Y         S0      
317GND              VIA   -    MD0100PA00X+142846Y+131648X0200Y         S0      
317GND              VIA   -    MD0100PA00X+142731Y+131348X0200Y         S0      
317GND              VIA   -    MD0100PA00X+142620Y+131075X0200Y         S0      
317GND              VIA   -    MD0100PA00X+142544Y+130818X0200Y         S0      
317GND              VIA   -    MD0100PA00X+142456Y+130557X0200Y         S0      
317GND              VIA   -    MD0100PA00X+034576Y+140145X0200Y         S0      
317GND              VIA   -    MD0100PA00X+034976Y+140145X0200Y         S0      
317GND              VIA   -    MD0100PA00X+035376Y+140145X0200Y         S0      
317GND              VIA   -    MD0100PA00X+035776Y+140145X0200Y         S0      
317GND              VIA   -    MD0100PA00X+033776Y+140145X0200Y         S0      
317GND              VIA   -    MD0100PA00X+034176Y+140145X0200Y         S0      
317GND              VIA   -    MD0100PA00X+031040Y+140055X0200Y         S0      
317GND              VIA   -    MD0100PA00X+031420Y+140055X0200Y         S0      
317GND              VIA   -    MD0100PA00X+031820Y+140055X0200Y         S0      
317GND              VIA   -    MD0100PA00X+032200Y+140055X0200Y         S0      
317GND              VIA   -    MD0100PA00X+045491Y+132672X0200Y         S0      
317GND              VIA   -    MD0100PA00X+045460Y+132403X0200Y         S0      
317GND              VIA   -    MD0100PA00X+045382Y+132144X0200Y         S0      
317GND              VIA   -    MD0100PA00X+045294Y+131878X0200Y         S0      
317GND              VIA   -    MD0100PA00X+045209Y+131607X0200Y         S0      
317GND              VIA   -    MD0100PA00X+045108Y+131335X0200Y         S0      
317GND              VIA   -    MD0100PA00X+045022Y+131083X0200Y         S0      
317GND              VIA   -    MD0100PA00X+044944Y+130839X0200Y         S0      
317GND              VIA   -    MD0100PA00X+044869Y+130595X0200Y         S0      
317GND              VIA   -    MD0100PA00X+151283Y+165959X0180Y         S0      
317GND              VIA   -    MD0100PA00X+053519Y+153107X0200Y    R090 S0      
317GND              VIA   -    MD0100PA00X+053769Y+153107X0200Y    R090 S0      
317GND              VIA   -    MD0100PA00X+054019Y+153107X0200Y    R090 S0      
317GND              VIA   -    MD0100PA00X+058049Y+155080X0180Y         S0      
317GND              VIA   -    MD0100PA00X+059466Y+155070X0180Y         S0      
317GND              VIA   -    MD0100PA00X+058994Y+155090X0180Y         S0      
317GND              VIA   -    MD0100PA00X+058521Y+155080X0180Y         S0      
317GND              VIA   -    MD0100PA00X+060884Y+155070X0180Y         S0      
317GND              VIA   -    MD0100PA00X+060411Y+155090X0180Y         S0      
317GND              VIA   -    MD0100PA00X+059939Y+155090X0180Y         S0      
317GND              VIA   -    MD0100PA00X+062773Y+155090X0180Y         S0      
317GND              VIA   -    MD0100PA00X+062301Y+155090X0180Y         S0      
317GND              VIA   -    MD0100PA00X+061828Y+155090X0180Y         S0      
317GND              VIA   -    MD0100PA00X+061356Y+155080X0180Y         S0      
317GND              VIA   -    MD0100PA00X+064191Y+155090X0180Y         S0      
317GND              VIA   -    MD0100PA00X+063718Y+155070X0180Y         S0      
317GND              VIA   -    MD0100PA00X+063246Y+155090X0180Y         S0      
317GND              VIA   -    MD0100PA00X+065136Y+155080X0180Y         S0      
317GND              VIA   -    MD0100PA00X+064663Y+155090X0180Y         S0      
317GND              VIA   -    MD0100PA00X+132419Y+158380X0180Y         S0      
317GND              VIA   -    MD0100PA00X+133836Y+158370X0180Y         S0      
317GND              VIA   -    MD0100PA00X+133364Y+158390X0180Y         S0      
317GND              VIA   -    MD0100PA00X+132891Y+158380X0180Y         S0      
317GND              VIA   -    MD0100PA00X+135254Y+158370X0180Y         S0      
317GND              VIA   -    MD0100PA00X+134781Y+158390X0180Y         S0      
317GND              VIA   -    MD0100PA00X+134309Y+158390X0180Y         S0      
317GND              VIA   -    MD0100PA00X+137143Y+158390X0180Y         S0      
317GND              VIA   -    MD0100PA00X+136671Y+158390X0180Y         S0      
317GND              VIA   -    MD0100PA00X+136198Y+158390X0180Y         S0      
317GND              VIA   -    MD0100PA00X+135726Y+158380X0180Y         S0      
317GND              VIA   -    MD0100PA00X+138561Y+158390X0180Y         S0      
317GND              VIA   -    MD0100PA00X+138088Y+158370X0180Y         S0      
317GND              VIA   -    MD0100PA00X+137616Y+158390X0180Y         S0      
317GND              VIA   -    MD0100PA00X+139506Y+158380X0180Y         S0      
317GND              VIA   -    MD0100PA00X+139033Y+158390X0180Y         S0      
317GND              VIA   -    MD0100PA00X+146030Y+158380X0180Y         S0      
317GND              VIA   -    MD0100PA00X+147447Y+158370X0180Y         S0      
317GND              VIA   -    MD0100PA00X+146975Y+158390X0180Y         S0      
317GND              VIA   -    MD0100PA00X+146502Y+158380X0180Y         S0      
317GND              VIA   -    MD0100PA00X+148865Y+158370X0180Y         S0      
317GND              VIA   -    MD0100PA00X+148392Y+158390X0180Y         S0      
317GND              VIA   -    MD0100PA00X+147920Y+158390X0180Y         S0      
317GND              VIA   -    MD0100PA00X+150755Y+158390X0180Y         S0      
317GND              VIA   -    MD0100PA00X+150282Y+158390X0180Y         S0      
317GND              VIA   -    MD0100PA00X+149810Y+158390X0180Y         S0      
317GND              VIA   -    MD0100PA00X+149337Y+158380X0180Y         S0      
317GND              VIA   -    MD0100PA00X+152172Y+158390X0180Y         S0      
317GND              VIA   -    MD0100PA00X+151699Y+158370X0180Y         S0      
317GND              VIA   -    MD0100PA00X+151227Y+158390X0180Y         S0      
317GND              VIA   -    MD0100PA00X+153117Y+158380X0180Y         S0      
317GND              VIA   -    MD0100PA00X+152644Y+158390X0180Y         S0      
317GND              VIA   -    MD0100PA00X+158836Y+158380X0180Y         S0      
317GND              VIA   -    MD0100PA00X+160254Y+158370X0180Y         S0      
317GND              VIA   -    MD0100PA00X+159781Y+158390X0180Y         S0      
317GND              VIA   -    MD0100PA00X+159309Y+158380X0180Y         S0      
317GND              VIA   -    MD0100PA00X+161671Y+158370X0180Y         S0      
317GND              VIA   -    MD0100PA00X+161198Y+158390X0180Y         S0      
317GND              VIA   -    MD0100PA00X+160726Y+158390X0180Y         S0      
317GND              VIA   -    MD0100PA00X+163561Y+158390X0180Y         S0      
317GND              VIA   -    MD0100PA00X+163088Y+158390X0180Y         S0      
317GND              VIA   -    MD0100PA00X+162616Y+158390X0180Y         S0      
317GND              VIA   -    MD0100PA00X+162143Y+158380X0180Y         S0      
317GND              VIA   -    MD0100PA00X+164978Y+158390X0180Y         S0      
317GND              VIA   -    MD0100PA00X+164506Y+158370X0180Y         S0      
317GND              VIA   -    MD0100PA00X+164033Y+158390X0180Y         S0      
317GND              VIA   -    MD0100PA00X+165923Y+158380X0180Y         S0      
317GND              VIA   -    MD0100PA00X+165450Y+158390X0180Y         S0      
317GND              VIA   -    MD0100PA00X+050440Y+155090X0180Y         S0      
317GND              VIA   -    MD0100PA00X+050912Y+155070X0180Y         S0      
317GND              VIA   -    MD0100PA00X+051384Y+155090X0180Y         S0      
317GND              VIA   -    MD0100PA00X+051857Y+155090X0180Y         S0      
317GND              VIA   -    MD0100PA00X+052329Y+155080X0180Y         S0      
317GND              VIA   -    MD0100PA00X+046660Y+155070X0180Y         S0      
317GND              VIA   -    MD0100PA00X+047132Y+155090X0180Y         S0      
317GND              VIA   -    MD0100PA00X+047605Y+155090X0180Y         S0      
317GND              VIA   -    MD0100PA00X+048077Y+155070X0180Y         S0      
317GND              VIA   -    MD0100PA00X+045715Y+155080X0180Y         S0      
317GND              VIA   -    MD0100PA00X+045243Y+155080X0180Y         S0      
317GND              VIA   -    MD0100PA00X+046188Y+155090X0180Y         S0      
327GND              PC6817-2          A18X+180801Y+159832X0400Y0500     S2      
327GND              PC1856-2          A18X+162306Y+059235X0400Y0500R270 S2      
327GND              PC1855-2          A18X+163026Y+059232X0400Y0500R270 S2      
327GND              PC1852-2          A18X+160914Y+059533X0198Y0197R090 S2      
327GND              U25   -CV10       A01X+152102Y+112906X0177Y    R180 S1      
327GND              U25   -CW15       A01X+150066Y+113224X0177Y    R180 S1      
327GND              U25   -CV15       A01X+150251Y+112906X0177Y    R180 S1      
327GND              U25   -CV19       A01X+148771Y+112906X0177Y    R180 S1      
327GND              U25   -CV34       A01X+143220Y+112906X0177Y    R180 S1      
327GND              U25   -CV42       A01X+140259Y+112906X0177Y    R180 S1      
327GND              U25   -CV51       A01X+136928Y+112906X0177Y    R180 S1      
327GND              U25   -CV66       A01X+131377Y+112906X0177Y    R180 S1      
327GND              U25   -M10        A01X+151984Y+090937X0177Y    R180 S1      
327GND              U25   -M15        A01X+150133Y+090937X0177Y    R180 S1      
327GND              U25   -M25        A01X+146432Y+090937X0177Y    R180 S1      
327GND              U25   -M34        A01X+143102Y+090937X0177Y    R180 S1      
327GND              U25   -M42        A01X+140141Y+090937X0177Y    R180 S1      
327GND              U25   -M57        A01X+134590Y+090937X0177Y    R180 S1      
327GND              U25   -M61        A01X+133109Y+090937X0177Y    R180 S1      
327GND              U25   -M66        A01X+131259Y+090937X0177Y    R180 S1      
317GND              VIA   -    MD0100PA00X+162119Y+058859X0200Y    R180 S0      
317GND              VIA   -    MD0100PA00X+162407Y+058847X0200Y    R180 S0      
317GND              VIA   -    MD0100PA00X+162876Y+058859X0200Y    R180 S0      
317GND              VIA   -    MD0100PA00X+163156Y+058851X0200Y    R180 S0      
327GND              U26   -CV19       A01X+051157Y+112906X0177Y    R180 S1      
317GND              VIA   -    MD0100PA00X+160936Y+059279X0200Y    R180 S0      
327GND              U26   -CV10       A01X+054487Y+112906X0177Y    R180 S1      
327GND              U26   -CV15       A01X+052637Y+112906X0177Y    R180 S1      
327GND              VIA   -           A18X+030586Y+059697X0260Y    R180 S2      
317GND              VIA   -    MD0100PA00X+031396Y+060459X0200Y         S0      
317GND              VIA   -    MD0100PA00X+031396Y+060709X0200Y         S0      
317GND              VIA   -    MD0100PA00X+023473Y+057121X0200Y    R180 S0      
327GND              U26   -CV34       A01X+045606Y+112906X0177Y    R180 S1      
327GND              U26   -M34        A01X+045487Y+090937X0177Y    R180 S1      
327GND              U26   -M25        A01X+048818Y+090937X0177Y    R180 S1      
327GND              U26   -M15        A01X+052519Y+090937X0177Y    R180 S1      
327GND              U26   -M10        A01X+054369Y+090937X0177Y    R180 S1      
317GND              VIA   -    MD0100PA00X+078000Y+135750X0200Y    R090 S0      
327GND              U26   -M66        A01X+033645Y+090937X0177Y    R180 S1      
327GND              U26   -M61        A01X+035495Y+090937X0177Y    R180 S1      
327GND              U26   -M57        A01X+036976Y+090937X0177Y    R180 S1      
327GND              U26   -M48        A01X+040306Y+090937X0177Y    R180 S1      
327GND              U26   -M42        A01X+042527Y+090937X0177Y    R180 S1      
327GND              U26   -CV42       A01X+042645Y+112906X0177Y    R180 S1      
327GND              U26   -CV51       A01X+039314Y+112906X0177Y    R180 S1      
327GND              PC8011-2          A18X+049528Y+061916X0400Y0500R090 S2      
327GND              U26   -CV61       A01X+035613Y+112906X0177Y    R180 S1      
327GND              U26   -CV66       A01X+033763Y+112906X0177Y    R180 S1      
327GND              U25   -CV61       A01X+133228Y+112906X0177Y    R180 S1      
327GND              C216  -2          A18X+158638Y+123987X0198Y0197R180 S2      
327GND              C215  -2          A18X+157623Y+123987X0198Y0197     S2      
327GND              Y2    -2          A18X+156848Y+124981X0480Y0590R090 S2      
327GND              Y2    -4          A18X+156013Y+124351X0480Y0590R090 S2      
327GND              C214  -2          A18X+156784Y+123766X0198Y0197R180 S2      
327GND              C213  -2          A18X+155769Y+123766X0198Y0197     S2      
327GND              PC6544-2          A01X+003806Y+159890X0198Y0197R180 S1      
327GND              PC6583-2          A18X+180801Y+160582X0400Y0500     S2      
327GND              PC6816-2          A18X+175728Y+160495X0400Y0500R180 S2      
327GND              PC6560-2          A18X+175728Y+159755X0400Y0500R180 S2      
327GND              PC6636-2          A18X+010489Y+152657X0400Y0500R270 S2      
327GND              PC6635-2          A18X+011283Y+152663X0400Y0500R270 S2      
327GND              PC6614-2          A18X+007840Y+152717X0400Y0500R270 S2      
327GND              PC6615-2          A18X+007048Y+152717X0400Y0500R270 S2      
327GND              VIA   -           A18X+005622Y+153511X0260Y    R090 S2      
327GND              PC6807-2          A18X+010318Y+150895X0198Y0197R270 S2      
327GND              PC6643-2          A18X+007775Y+151152X0400Y0500R090 S2      
327GND              PC6642-2          A18X+007086Y+151149X0400Y0500R090 S2      
327GND              VIA   -           A18X+004402Y+151899X0260Y    R090 S2      
327GND              PC6625-2          A18X+004296Y+151158X0400Y0500R090 S2      
327GND              PC6624-2          A18X+003615Y+151158X0400Y0500R090 S2      
327GND              PR6625-2          A18X+003000Y+151090X0280Y0320     S2      
327GND              PC6616-2          A18X+006752Y+157169X0400Y0500R180 S2      
327GND              PC6617-2          A18X+006752Y+156479X0400Y0500R180 S2      
327GND              PC6819-2          A18X+006744Y+157856X0400Y0500R180 S2      
317GND              VIA   -    MD0100PA00X+126699Y+158380X0180Y         S0      
317GND              VIA   -    MD0100PA00X+126227Y+158390X0180Y         S0      
317GND              VIA   -    MD0100PA00X+125754Y+158390X0180Y         S0      
317GND              VIA   -    MD0100PA00X+125282Y+158370X0180Y         S0      
317GND              VIA   -    MD0100PA00X+124810Y+158390X0180Y         S0      
317GND              VIA   -    MD0100PA00X+124337Y+158390X0180Y         S0      
317GND              VIA   -    MD0100PA00X+123865Y+158390X0180Y         S0      
317GND              VIA   -    MD0100PA00X+123392Y+158390X0180Y         S0      
317GND              VIA   -    MD0100PA00X+122920Y+158380X0180Y         S0      
317GND              VIA   -    MD0100PA00X+122447Y+158370X0180Y         S0      
317GND              VIA   -    MD0100PA00X+121975Y+158390X0180Y         S0      
317GND              VIA   -    MD0100PA00X+121502Y+158390X0180Y         S0      
317GND              VIA   -    MD0100PA00X+121030Y+158370X0180Y         S0      
317GND              VIA   -    MD0100PA00X+120558Y+158390X0180Y         S0      
317GND              VIA   -    MD0100PA00X+120085Y+158380X0180Y         S0      
317GND              VIA   -    MD0100PA00X+119613Y+158380X0180Y         S0      
317GND              VIA   -    MD0100PA00X+049967Y+155090X0180Y         S0      
317GND              VIA   -    MD0100PA00X+049495Y+155090X0180Y         S0      
317GND              VIA   -    MD0100PA00X+049022Y+155090X0180Y         S0      
317GND              VIA   -    MD0100PA00X+048550Y+155080X0180Y         S0      
327GND              PC867 -2          A18X+059572Y+031817X0400Y0500R180 S2      
327GND              VIA   -           A18X+058530Y+031817X0260Y    R180 S2      
327GND              PC850 -2          A18X+059572Y+030206X0400Y0500R180 S2      
327GND              PC865 -2          A18X+059572Y+031012X0400Y0500R180 S2      
327GND              VIA   -           A18X+058530Y+030317X0260Y    R180 S2      
327GND              PC866 -2          A18X+059572Y+029401X0400Y0500R180 S2      
327GND              VIA   -           A18X+167611Y+043418X0260Y    R090 S2      
327GND              VIA   -           A18X+167611Y+041918X0260Y         S2      
327GND              VIA   -           A18X+166111Y+041918X0260Y    R270 S2      
327GND              VIA   -           A18X+167611Y+040418X0260Y    R270 S2      
327GND              VIA   -           A18X+166111Y+040418X0260Y    R270 S2      
327GND              VIA   -           A18X+167611Y+038918X0260Y    R270 S2      
327GND              VIA   -           A18X+166111Y+038918X0260Y    R090 S2      
327GND              D8000 -C          A01X+141825Y+024445X0240Y0280R180 S1      
327GND              D8001 -C          A01X+015032Y+023083X0240Y0280R090 S1      
317GND              H37   -1   MD1470PA00X+124981Y+135754X2440Y         S3      
317GND              H44   -1   MD1470PA00X+141713Y+133982X2440Y         S3      
317GND              H50   -1   MD1470PA00X+105296Y+136935X2440Y         S3      
327GND              PR3828-2          A01X+029809Y+006713X0198Y0197R180 S1      
327GND              C1107 -2          A01X+129328Y+040812X0198Y0197     S1      
327GND              PC511 -2          A01X+071022Y+143881X0198Y0197R090 S1      
327GND              PC506 -2          A01X+073844Y+139522X0198Y0197R090 S1      
327GND              PU44  -2   M      A01X+071071Y+139024X0090Y0240R090 S1      
327GND              PC505 -2          A01X+070566Y+139512X0198Y0197R090 S1      
327GND              PC510_-2          A01X+077122Y+138193X0198Y0197R270 S1      
327GND              PC512_-2          A01X+076734Y+138193X0198Y0197R270 S1      
327GND              PU45  -5          A01X+074349Y+138502X0090Y0240R090 S1      
327GND              PR519 -2          A01X+073846Y+137790X0198Y0197R090 S1      
327GND              PC508_-2          A01X+073844Y+138157X0198Y0197R270 S1      
327GND              PC511_-2          A01X+073456Y+138183X0198Y0197R270 S1      
327GND              PU44  -5          A01X+071071Y+138492X0090Y0240R090 S1      
327GND              PR520 -2          A01X+070568Y+137780X0198Y0197R090 S1      
327GND              PC507_-2          A01X+070566Y+138147X0198Y0197R270 S1      
327GND              PR395 -2          A01X+069870Y+134894X0198Y0197R090 S1      
327GND              PR288 -2          A01X+067418Y+130800X0198Y0197     S1      
327GND              PC524 -2          A01X+067807Y+130861X0198Y0197R270 S1      
327GND              PC530 -2          A01X+076464Y+130136X0630Y1190     S1      
327GND              PC532 -2          A01X+074064Y+130136X0630Y1190     S1      
327GND              PC531 -2          A01X+071664Y+130136X0630Y1190     S1      
327GND              PC803 -2          A01X+069276Y+130132X0630Y1190     S1      
317GND              H8    -1   MD1470PA00X+087362Y+114528X2440Y         S3      
317GND              H2    -1   MD1470PA00X+182457Y+157099X2440Y         S3      
317GND              H10   -1   MD1470PA00X+171433Y+157098X2440Y         S3      
317GND              H3    -1   MD1470PA00X+002705Y+153323X2440Y         S3      
327GND              PC6025-2          A18X+050872Y+030917X0400Y0500R180 S2      
327GND              PC6018-2          A18X+050872Y+029306X0400Y0500R180 S2      
327GND              PC6024-2          A18X+050872Y+030112X0400Y0500R180 S2      
327GND              PC6026-2          A18X+050872Y+028501X0400Y0500R180 S2      
327GND              C6085 -2          A18X+048114Y+028109X0198Y0197R180 S2      
327GND              PC563_-2          A18X+154605Y+076749X0400Y0500R270 S2      
327GND              PC565_-2          A18X+151730Y+074977X0400Y0500R270 S2      
327GND              PC562_-2          A18X+151045Y+074979X0400Y0500R270 S2      
327GND              PC564_-2          A18X+148290Y+074944X0400Y0500R270 S2      
327GND              PC501_-2          A18X+145233Y+074974X0400Y0500R270 S2      
327GND              PC602_-2          A18X+158015Y+072734X0400Y0500R270 S2      
327GND              PC604_-2          A18X+155250Y+072734X0400Y0500R270 S2      
327GND              PC557_-2          A18X+152906Y+072345X0400Y0500R090 S2      
327GND              PC559_-2          A18X+152106Y+072345X0400Y0500R090 S2      
327GND              PC496 -2          A18X+153103Y+073333X0950Y1110R090 S2      
327GND              PC556_-2          A18X+148826Y+072345X0400Y0500R090 S2      
327GND              PC558_-2          A18X+149626Y+072345X0400Y0500R090 S2      
327GND              PC108 -2          A18X+149665Y+073331X0950Y1110R090 S2      
327GND              PC488_-2          A18X+146281Y+072270X0400Y0500R090 S2      
327GND              PC498 -2          A18X+146779Y+073348X0950Y1110R090 S2      
327GND              PC486_-2          A18X+145443Y+072270X0400Y0500R090 S2      
327GND              PC499_-2          A18X+142339Y+072967X0400Y0500R270 S2      
327GND              PC601 -2          A18X+156644Y+071137X0950Y1110R090 S2      
327GND              PC494 -2          A18X+143726Y+071374X0950Y1110R090 S2      
327GND              PC600_-2          A18X+161480Y+069424X0400Y0500R270 S2      
327GND              PC603_-2          A18X+158732Y+070033X0400Y0500R270 S2      
327GND              PC589_-2          A18X+156219Y+070151X0400Y0500R090 S2      
327GND              PC591_-2          A18X+155419Y+070151X0400Y0500R090 S2      
327GND              PC555_-2          A18X+152833Y+070109X0400Y0500R270 S2      
327GND              PC485_-2          A18X+143026Y+070387X0400Y0500R090 S2      
327GND              PC487_-2          A18X+142226Y+070387X0400Y0500R090 S2      
327GND              PC575_-2          A18X+141504Y+070388X0400Y0500R270 S2      
327GND              PC576_-2          A18X+138750Y+069694X0400Y0500R270 S2      
327GND              PC615_-2          A18X+164985Y+067527X0400Y0500R270 S2      
327GND              PR334 -2          A18X+165515Y+067673X0198Y0197R090 S2      
327GND              PC614_-2          A18X+162230Y+067527X0400Y0500R270 S2      
327GND              PC598 -2          A18X+160105Y+067775X0950Y1110R090 S2      
327GND              PC587_-2          A18X+156146Y+067916X0400Y0500R270 S2      
327GND              PC495 -2          A18X+140129Y+068128X0950Y1110R090 S2      
327GND              VIA   -           A18X+167602Y+067013X0260Y    R270 S2      
327GND              VIA   -           A18X+166102Y+067013X0260Y    R270 S2      
327GND              PC590_-2          A18X+159496Y+066774X0400Y0500R090 S2      
327GND              PC592_-2          A18X+158696Y+066774X0400Y0500R090 S2      
327GND              PC595_-2          A18X+158007Y+066776X0400Y0500R090 S2      
327GND              PC8009-2          A18X+157039Y+067080X0400Y0500R090 S2      
327GND              PC593_-2          A18X+156209Y+067110X0400Y0500     S2      
327GND              PC573_-2          A18X+139766Y+067129X0400Y0500R090 S2      
327GND              PC572_-2          A18X+138966Y+067129X0400Y0500R090 S2      
327GND              PC502_-2          A18X+137964Y+067111X0400Y0500R270 S2      
327GND              PC500_-2          A18X+136860Y+066495X0400Y0500R270 S2      
327GND              PC166_-2          A18X+136028Y+066495X0400Y0500R270 S2      
327GND              PC163_-2          A18X+135193Y+066495X0400Y0500R270 S2      
327GND              PR447 -2          A18X+134672Y+066631X0198Y0197R090 S2      
327GND              VIA   -           A18X+133694Y+066122X0260Y    R180 S2      
327GND              PC610_-2          A18X+161996Y+064874X0400Y0500R090 S2      
327GND              PC613_-2          A18X+162796Y+064874X0400Y0500R090 S2      
327GND              PC597 -2          A18X+163610Y+065862X0950Y1110R090 S2      
327GND              PC588_-2          A18X+159418Y+064534X0400Y0500R270 S2      
327GND              VIA   -           A18X+137944Y+064622X0260Y    R180 S2      
327GND              VIA   -           A18X+133694Y+064622X0260Y    R180 S2      
327GND              PC612_-2          A18X+161269Y+064330X0400Y0500R090 S2      
327GND              PC8010-2          A18X+160450Y+064223X0400Y0500R090 S2      
327GND              PC158_-2          A18X+136496Y+063839X0400Y0500R090 S2      
327GND              PC159_-2          A18X+135696Y+063839X0400Y0500R090 S2      
327GND              PC611_-2          A18X+162718Y+062638X0400Y0500R270 S2      
327GND              VIA   -           A18X+032217Y+012747X0260Y         S2      
327GND              VIA   -           A18X+032217Y+011247X0260Y         S2      
327GND              VIA   -           A18X+032217Y+009747X0260Y         S2      
317GND              H103  -1   MD2210PA00X+180630Y+171496X3940Y         S3      
317GND              VIA   -    MD0100PA00X+167313Y+169074X0200Y         S0      
317GND              H128  -1   MD2210PA00X+146181Y+171496X3940Y         S3      
317GND              H104  -1   MD2210PA00X+115571Y+171496X3940Y         S3      
317GND              H106  -1   MD2210PA00X+070768Y+171496X3940Y         S3      
317GND              H94   -1   MD2210PA00X+039567Y+171496X3940Y         S3      
317GND              H97   -1   MD2210PA00X+005118Y+171496X3940Y         S3      
327GND              U6005 -TH  M      A01X+168907Y+168624X0670Y0670R090 S1      
317GND              VIA   -    MD0100PA00X+169136Y+168842X0200Y    R090 S0      
317GND              VIA   -    MD0100PA00X+168686Y+168392X0200Y    R090 S0      
327GND              U6005 -10         A01X+169006Y+169176X0090Y0240     S1      
317GND              VIA   -    MD0100PA00X+167324Y+167348X0200Y         S0      
317GND              VIA   -    MD0100PA00X+019515Y+167977X0200Y         S0      
327GND              Q72   -1          A18X+019515Y+167687X0170Y0200R270 S2      
317GND              VIA   -    MD0100PA00X+018525Y+168687X0200Y         S0      
327GND              Q107  -4          A18X+018782Y+168687X0170Y0200R270 S2      
317GND              VIA   -    MD0100PA00X+016284Y+167427X0200Y    R090 S0      
317GND              VIA   -    MD0100PA00X+016285Y+167936X0200Y    R090 S0      
317GND              VIA   -    MD0100PA00X+015991Y+167681X0200Y    R090 S0      
317GND              VIA   -    MD0100PA00X+168824Y+166380X0200Y    R270 S0      
327GND              R6251 -1          A01X+168824Y+166623X0198Y0197R090 S1      
317GND              VIA   -    MD0100PA00X+167053Y+167015X0200Y         S0      
327GND              C989  -2          A01X+166827Y+167015X0120Y0150     S1      
317GND              VIA   -    M      A01X+167697Y+166858X0200Y    R270 S2      
017GND              VIA   -    M      A18X+167697Y+166858X0260Y    R270 S2      
017GND                    -    MD0100PA00X+167697Y+166858                       
327GND              R6250 -1          A01X+167982Y+166623X0198Y0197R090 S1      
317GND              VIA   -    MD0100PA00X+166110Y+167163X0200Y         S0      
327GND              U16   -7          A01X+166110Y+167593X0350Y0500R180 S1      
327GND              U47   -5          A18X+166104Y+167687X0130Y0250     S2      
317GND              VIA   -    MD0100PA00X+145944Y+165979X0180Y         S0      
327GND              Q72   -4          A18X+018767Y+167175X0170Y0200R270 S2      
317GND              VIA   -    MD0100PA00X+019027Y+167175X0200Y         S0      
317GND              VIA   -    MD0100PA00X+019637Y+166482X0200Y         S0      
327GND              Q96   -1          A18X+019515Y+166185X0170Y0200R270 S2      
317GND              VIA   -    MD0100PA00X+016300Y+166646X0200Y    R090 S0      
317GND              VIA   -    MD0100PA00X+016001Y+166393X0200Y    R090 S0      
317GND              VIA   -    MD0100PA00X+016300Y+166138X0200Y    R090 S0      
317GND              VIA   -    MD0100PA00X+145944Y+165480X0180Y         S0      
317GND              VIA   -    MD0100PA00X+019550Y+164536X0200Y    R090 S0      
317GND              VIA   -    MD0100PA00X+019024Y+165664X0200Y         S0      
327GND              Q96   -4          A18X+018767Y+165674X0170Y0200R270 S2      
317GND              VIA   -    MD0100PA00X+019608Y+163935X0200Y    R090 S0      
317GND              VIA   -    MD0100PA00X+016124Y+163119X0180Y    R090 S0      
317GND              VIA   -    MD0100PA00X+016124Y+163615X0180Y    R090 S0      
317GND              VIA   -    MD0100PA00X+018739Y+162679X0180Y         S0      
317GND              VIA   -    MD0100PA00X+062040Y+158988X0180Y         S0      
317GND              VIA   -    MD0100PA00X+063246Y+158988X0180Y         S0      
317GND              VIA   -    MD0100PA00X+060834Y+158988X0180Y         S0      
317GND              VIA   -    MD0100PA00X+059628Y+158988X0180Y         S0      
317GND              VIA   -    MD0100PA00X+058422Y+158988X0180Y         S0      
317GND              VIA   -    MD0100PA00X+056010Y+158988X0180Y         S0      
317GND              VIA   -    MD0100PA00X+057216Y+158988X0180Y         S0      
317GND              VIA   -    MD0100PA00X+054804Y+158988X0180Y         S0      
317GND              VIA   -    MD0100PA00X+053598Y+158988X0180Y         S0      
317GND              VIA   -    MD0100PA00X+052392Y+158988X0180Y         S0      
317GND              VIA   -    MD0100PA00X+051186Y+158988X0180Y         S0      
317GND              VIA   -    MD0100PA00X+048774Y+158988X0180Y         S0      
317GND              VIA   -    MD0100PA00X+049980Y+158988X0180Y         S0      
317GND              VIA   -    MD0100PA00X+047568Y+158988X0180Y         S0      
317GND              VIA   -    MD0100PA00X+037324Y+158988X0180Y         S0      
317GND              VIA   -    MD0100PA00X+036118Y+158988X0180Y         S0      
317GND              VIA   -    MD0100PA00X+034912Y+158988X0180Y         S0      
317GND              VIA   -    MD0100PA00X+033706Y+158988X0180Y         S0      
317GND              VIA   -    MD0100PA00X+032500Y+158988X0180Y         S0      
317GND              VIA   -    MD0100PA00X+031294Y+158988X0180Y         S0      
317GND              VIA   -    MD0100PA00X+030088Y+158988X0180Y         S0      
317GND              VIA   -    MD0100PA00X+028882Y+158988X0180Y         S0      
317GND              VIA   -    MD0100PA00X+027676Y+158988X0180Y         S0      
317GND              VIA   -    MD0100PA00X+026470Y+158988X0180Y         S0      
317GND              VIA   -    MD0100PA00X+025264Y+158988X0180Y         S0      
317GND              VIA   -    MD0100PA00X+024058Y+158988X0180Y         S0      
317GND              VIA   -    MD0100PA00X+022852Y+158988X0180Y         S0      
317GND              VIA   -    MD0100PA00X+021646Y+158988X0180Y         S0      
317GND              VIA   -    MD0100PA00X+020440Y+158988X0180Y         S0      
317GND              VIA   -    MD0100PA00X+019234Y+158988X0180Y         S0      
317GND              VIA   -    MD0100PA00X+024967Y+155090X0180Y         S0      
317GND              VIA   -    MD0100PA00X+025440Y+155090X0180Y         S0      
317GND              VIA   -    MD0100PA00X+025912Y+155080X0180Y         S0      
317GND              VIA   -    MD0100PA00X+024495Y+155070X0180Y         S0      
317GND              VIA   -    MD0100PA00X+024022Y+155090X0180Y         S0      
317GND              VIA   -    MD0100PA00X+023550Y+155090X0180Y         S0      
317GND              VIA   -    MD0100PA00X+023077Y+155090X0180Y         S0      
317GND              VIA   -    MD0100PA00X+020715Y+155090X0180Y         S0      
317GND              VIA   -    MD0100PA00X+021188Y+155090X0180Y         S0      
317GND              VIA   -    MD0100PA00X+020243Y+155070X0180Y         S0      
317GND              VIA   -    MD0100PA00X+018825Y+155080X0180Y         S0      
317GND              VIA   -    MD0100PA00X+019298Y+155080X0180Y         S0      
317GND              VIA   -    MD0100PA00X+019770Y+155090X0180Y         S0      
317GND              VIA   -    MD0100PA00X+117359Y+153430X0200Y    R270 S0      
317GND              VIA   -    MD0100PA00X+122821Y+150790X0200Y         S0      
317GND              VIA   -    MD0100PA00X+074608Y+150693X0200Y    R090 S0      
317GND              VIA   -    MD0100PA00X+016571Y+150130X0200Y    R270 S0      
317GND              VIA   -    MD0100PA00X+005088Y+142196X0200Y         S0      
317GND              H112  -2   MD0220PA00X+102909Y+142033X0360Y         S3      
317GND              H112  -3   MD0220PA00X+102533Y+142942X0360Y         S3      
317GND              H112  -4   MD0220PA00X+101624Y+143318X0360Y         S3      
317GND              H112  -5   MD0220PA00X+100715Y+142942X0360Y         S3      
317GND              H112  -6   MD0220PA00X+100339Y+142033X0360Y         S3      
317GND              H112  -7   MD0220PA00X+100715Y+141124X0360Y         S3      
317GND              H112  -9   MD0220PA00X+102533Y+141124X0360Y         S3      
317GND              H112  -8   MD0220PA00X+101624Y+140748X0360Y         S3      
317GND              H111  -2   MD0220PA00X+085409Y+142033X0360Y         S3      
317GND              H111  -3   MD0220PA00X+085033Y+142942X0360Y         S3      
317GND              H111  -4   MD0220PA00X+084124Y+143318X0360Y         S3      
317GND              H111  -5   MD0220PA00X+083215Y+142942X0360Y         S3      
317GND              H111  -6   MD0220PA00X+082839Y+142033X0360Y         S3      
317GND              H111  -7   MD0220PA00X+083215Y+141124X0360Y         S3      
317GND              H111  -9   MD0220PA00X+085033Y+141124X0360Y         S3      
317GND              H111  -8   MD0220PA00X+084124Y+140748X0360Y         S3      
317GND              VIA   -    MD0100PA00X+005835Y+141273X0200Y         S0      
317GND              VIA   -    MD0100PA00X+005088Y+141256X0200Y    R180 S0      
317GND              H105  -1   MD2210PA00X+093169Y+138780X3940Y         S3      
317GND              H95   -1   MD2210PA00X+181677Y+136890X3940Y         S3      
317GND              H102  -1   MD2210PA00X+004071Y+136891X3940Y         S3      
317GND              H100  -1   MD2210PA00X+093169Y+107284X3940Y         S3      
317GND              H99   -1   MD2210PA00X+093169Y+075787X3940Y         S3      
317GND              H98   -1   MD2210PA00X+181677Y+063189X3940Y         S3      
317GND              H101  -1   MD2210PA00X+127126Y+063189X3940Y         S3      
317GND              H89   -1   MD2210PA00X+066102Y+063189X3940Y         S3      
317GND              H88   -1   MD2210PA00X+004071Y+063189X3940Y         S3      
317GND              H96   -1   MD2210PA00X+182992Y+008780X3940Y         S3      
317GND              H87   -1   MD2210PA00X+149961Y+008780X3940Y         S3      
317GND              H86   -1   MD2210PA00X+104587Y+008780X3940Y         S3      
317GND              H92   -1   MD2210PA00X+080079Y+008780X3940Y         S3      
317GND              H93   -1   MD2210PA00X+037362Y+008780X3940Y         S3      
317GND              H91   -1   MD2210PA00X+002756Y+008780X3940Y         S3      
317GND              VIA   -    MD0100PA00X+142497Y+156426X0200Y         S0      
317GND              VIA   -    MD0100PA00X+142497Y+156676X0200Y         S0      
317GND              VIA   -    MD0100PA00X+112573Y+166607X0200Y         S0      
317GND              VIA   -    MD0100PA00X+112923Y+166617X0200Y         S0      
317GND              VIA   -    MD0100PA00X+109103Y+165303X0200Y         S0      
317GND              VIA   -    MD0100PA00X+109014Y+164362X0200Y         S0      
327GND              R1060 -2          A01X+168207Y+153814X0120Y0150R180 S1      
317GND              VIA   -    M      A01X+168417Y+153814X0200Y         S2      
017GND              VIA   -    M      A18X+168417Y+153814X0260Y         S2      
017GND                    -    MD0100PA00X+168417Y+153814                       
327GND              R6903 -2          A18X+054102Y+150740X0120Y0150     S2      
317GND              VIA   -    MD0100PA00X+171989Y+160964X0200Y         S0      
317GND              VIA   -    MD0100PA00X+171989Y+160634X0200Y         S0      
317GND              VIA   -    M      A01X+171989Y+160304X0200Y         S2      
017GND              VIA   -    M      A18X+171989Y+160304X0260Y         S2      
017GND                    -    MD0100PA00X+171989Y+160304                       
317GND              VIA   -    MD0100PA00X+171989Y+159974X0200Y         S0      
317GND              VIA   -    MD0100PA00X+171989Y+159494X0200Y         S0      
317GND              VIA   -    M      A01X+171989Y+161294X0200Y         S2      
017GND              VIA   -    M      A18X+171989Y+161294X0260Y         S2      
017GND                    -    MD0100PA00X+171989Y+161294                       
327GND              R1406 -2          A01X+171779Y+159974X0120Y0150R180 S1      
327GND              R1401 -2          A01X+171779Y+161294X0120Y0150R180 S1      
327GND              R1400 -2          A01X+171779Y+160634X0120Y0150R180 S1      
317GND              VIA   -    MD0100PA00X+071336Y+153521X0200Y         S0      
327GND              R1408 -2          A01X+154750Y+157137X0120Y0150R180 S1      
327GND              R1102 -2          A01X+155770Y+153800X0120Y0150R180 S1      
327GND              R1412 -2          A01X+155250Y+153610X0120Y0150R180 S1      
327GND              R1398 -2          A01X+142137Y+156644X0120Y0150R180 S1      
327GND              R1364 -2          A01X+128332Y+157137X0120Y0150R180 S1      
327GND              R969  -2          A01X+129352Y+153800X0120Y0150R180 S1      
327GND              R1368 -2          A01X+128832Y+153610X0120Y0150R180 S1      
317GND              VIA   -    MD0100PA00X+142374Y+153672X0200Y         S0      
327GND              R1018 -2          A01X+142158Y+153800X0120Y0150R180 S1      
317GND              VIA   -    MD0100PA00X+167367Y+156358X0200Y         S0      
317GND              VIA   -    MD0100PA00X+154962Y+156976X0200Y    R090 S0      
317GND              VIA   -    MD0100PA00X+155212Y+156976X0200Y    R090 S0      
317GND              VIA   -    MD0100PA00X+128544Y+156976X0200Y    R090 S0      
317GND              VIA   -    MD0100PA00X+128794Y+156976X0200Y    R090 S0      
317GND              VIA   -    MD0100PA00X+071699Y+153725X0200Y         S0      
317GND              VIA   -    MD0100PA00X+071346Y+154092X0200Y         S0      
317GND              VIA   -    MD0100PA00X+071522Y+153908X0200Y         S0      
317GND              VIA   -    MD0100PA00X+071512Y+153338X0200Y         S0      
317GND              VIA   -    MD0100PA00X+071677Y+153146X0200Y         S0      
327GND              R1417 -2          A01X+071125Y+155170X0120Y0150R180 S1      
327GND              R1416 -2          A01X+071125Y+154510X0120Y0150R180 S1      
327GND              R1427 -2          A01X+071125Y+153850X0120Y0150R180 S1      
317GND              VIA   -    MD0100PA00X+054376Y+153688X0200Y    R090 S0      
327GND              R1433 -2          A01X+054462Y+150310X0120Y0150R180 S1      
327GND              R949  -2          A01X+055044Y+150396X0120Y0150R180 S1      
317GND              VIA   -    MD0100PA00X+028007Y+153676X0200Y    R090 S0      
317GND              VIA   -    MD0100PA00X+027757Y+153676X0200Y    R090 S0      
327GND              R1387 -2          A01X+028045Y+150310X0120Y0150R180 S1      
317GND              VIA   -    MD0100PA00X+041710Y+153126X0200Y    R180 S0      
317GND              VIA   -    MD0100PA00X+041710Y+153376X0200Y    R180 S0      
327GND              R796  -2          A01X+041371Y+150500X0120Y0150R180 S1      
317GND              VIA   -    MD0100PA00X+041586Y+150372X0200Y         S0      
327GND              R6717 -2          A01X+028565Y+150500X0120Y0150R180 S1      
317GND              VIA   -    MD0100PA00X+036311Y+139831X0200Y         S0      
317GND              VIA   -    MD0100PA00X+035911Y+139831X0200Y         S0      
317GND              VIA   -    MD0100PA00X+035511Y+139831X0200Y         S0      
317GND              VIA   -    MD0100PA00X+035111Y+139831X0200Y         S0      
317GND              VIA   -    MD0100PA00X+034711Y+139831X0200Y         S0      
327GND              PR3854-2          A01X+025149Y+010468X0198Y0197R270 S1      
327GND              PC1320-2          A01X+025149Y+009763X0280Y0320R090 S1      
327GND              PR3842-2          A01X+172661Y+010581X0198Y0197R270 S1      
327GND              PC2158-2          A01X+172661Y+009973X0280Y0320R090 S1      
327GND              C27   -2          A01X+173229Y+005365X0198Y0197R180 S1      
327GND              C1236 -2          A01X+173229Y+005765X0198Y0197R180 S1      
327GND              C1213 -2          A01X+173010Y+006305X0400Y0500     S1      
327GND              PC2080-2          A18X+172939Y+008635X0400Y0500R180 S2      
327GND              R1896 -2          A18X+172446Y+007668X0198Y0197R270 S2      
327GND              R1898 -2          A18X+172046Y+007668X0198Y0197R270 S2      
327GND              C1235 -2          A18X+173229Y+005365X0198Y0197     S2      
327GND              C21   -2          A18X+173229Y+005765X0198Y0197     S2      
327GND              C34   -2          A18X+173010Y+006305X0400Y0500R180 S2      
317GND              VIA   -    MD0100PA00X+172734Y+005452X0200Y         S0      
317GND              VIA   -    MD0100PA00X+172984Y+005452X0200Y         S0      
327GND              C1238 -2          A18X+171634Y+004765X0198Y0197R180 S2      
327GND              C1237 -2          A18X+171634Y+005165X0198Y0197R180 S2      
327GND              C1240 -2          A18X+171634Y+003965X0198Y0197R180 S2      
327GND              C1239 -2          A18X+171634Y+004365X0198Y0197R180 S2      
327GND              C1279 -2          A01X+096544Y+016481X0198Y0197R270 S1      
327GND              C1276 -2          A01X+095845Y+016210X0400Y0500R090 S1      
327GND              C1278 -2          A01X+096544Y+017496X0198Y0197R090 S1      
327GND              C1277 -2          A01X+096044Y+017592X0400Y0500R180 S1      
327GND              PC2143-2          A01X+025197Y+007893X0400Y0500     S1      
327GND              PC2152-2          A01X+025472Y+007340X0198Y0197R180 S1      
327GND              C1829 -2          A01X+025317Y+006783X0400Y0500     S1      
327GND              C1831 -2          A01X+025582Y+006240X0198Y0197R180 S1      
327GND              R3164 -1          A01X+024530Y+007586X0198Y0197R180 S1      
327GND              R3217 -2          A01X+024530Y+007186X0198Y0197     S1      
327GND              C1833 -2          A01X+025582Y+005840X0198Y0197R180 S1      
327GND              C1832 -2          A01X+025582Y+005440X0198Y0197R180 S1      
327GND              PC2141-2          A18X+025197Y+007893X0400Y0500R180 S2      
327GND              C1830 -2          A18X+025317Y+006783X0400Y0500R180 S2      
327GND              C1834 -2          A18X+025582Y+006240X0198Y0197     S2      
327GND              C1839 -2          A18X+025582Y+005840X0198Y0197     S2      
327GND              PR3962-2          A01X+098144Y+018266X0198Y0197R090 S1      
327GND              C1108 -2          A01X+156959Y+030182X0198Y0197     S1      
327GND              C1097 -2          A01X+156959Y+029732X0198Y0197     S1      
327GND              U55   -10         A01X+156173Y+029943X0090Y0240R270 S1      
327GND              R1309 -1          A01X+153894Y+030082X0198Y0197     S1      
327GND              R1306 -1          A01X+153894Y+030482X0198Y0197     S1      
327GND              C1096 -2          A01X+129328Y+040362X0198Y0197     S1      
327GND              U52   -10         A01X+128541Y+040574X0090Y0240R270 S1      
327GND              R1305 -1          A01X+126263Y+041112X0198Y0197     S1      
327GND              R1308 -1          A01X+126263Y+040712X0198Y0197     S1      
327GND              C1106 -2          A01X+010483Y+015369X0198Y0197     S1      
327GND              U56   -10         A01X+009697Y+015581X0090Y0240R270 S1      
327GND              C1109 -2          A01X+010483Y+015819X0198Y0197     S1      
327GND              R1310 -1          A01X+007418Y+015719X0198Y0197     S1      
327GND              R1307 -1          A01X+007418Y+016119X0198Y0197     S1      
327GND              R3208 -2          A18X+024680Y+005976X0198Y0197R090 S2      
327GND              R3216 -2          A18X+024179Y+005976X0198Y0197R090 S2      
317GND              VIA   -    MD0100PA00X+098144Y+018539X0200Y         S0      
317GND              VIA   -    M      A01X+025179Y+010085X0200Y         S2      
017GND              VIA   -    M      A18X+025179Y+010085X0260Y         S2      
017GND                    -    MD0100PA00X+025179Y+010085                       
317GND              VIA   -    MD0100PA00X+172681Y+010297X0200Y         S0      
317GND              VIA   -    MD0100PA00X+172660Y+006428X0200Y         S0      
317GND              VIA   -    MD0100PA00X+172984Y+005702X0200Y         S0      
317GND              VIA   -    MD0100PA00X+172660Y+006178X0200Y         S0      
317GND              VIA   -    MD0100PA00X+172734Y+005702X0200Y         S0      
317GND              VIA   -    M      A01X+157228Y+030182X0200Y         S2      
017GND              VIA   -    M      A18X+157228Y+030182X0260Y         S2      
017GND                    -    MD0100PA00X+157228Y+030182                       
317GND              VIA   -    M      A01X+156959Y+029482X0200Y         S2      
017GND              VIA   -    M      A18X+156959Y+029482X0260Y         S2      
017GND                    -    MD0100PA00X+156959Y+029482                       
317GND              VIA   -    MD0100PA00X+156452Y+029943X0200Y         S0      
317GND              VIA   -    MD0100PA00X+155848Y+030268X0200Y         S0      
317GND              VIA   -    MD0100PA00X+155391Y+029812X0200Y         S0      
327GND              U55   -TH  M      A01X+155622Y+030042X0670Y0670     S1      
317GND              VIA   -    M      A01X+153654Y+030482X0200Y         S2      
017GND              VIA   -    M      A18X+153654Y+030482X0260Y         S2      
017GND                    -    MD0100PA00X+153654Y+030482                       
317GND              VIA   -    MD0100PA00X+153654Y+030082X0200Y         S0      
317GND              VIA   -    M      A01X+129623Y+040812X0200Y         S2      
017GND              VIA   -    M      A18X+129623Y+040812X0260Y         S2      
017GND                    -    MD0100PA00X+129623Y+040812                       
317GND              VIA   -    M      A01X+129328Y+040112X0200Y         S2      
017GND              VIA   -    M      A18X+129328Y+040112X0260Y         S2      
017GND                    -    MD0100PA00X+129328Y+040112                       
317GND              VIA   -    MD0100PA00X+128820Y+040574X0200Y         S0      
317GND              VIA   -    MD0100PA00X+128216Y+040899X0200Y         S0      
317GND              VIA   -    MD0100PA00X+127760Y+040443X0200Y         S0      
327GND              U52   -TH  M      A01X+127990Y+040672X0670Y0670     S1      
317GND              VIA   -    M      A01X+126023Y+041113X0200Y         S2      
017GND              VIA   -    M      A18X+126023Y+041113X0260Y         S2      
017GND                    -    MD0100PA00X+126023Y+041113                       
317GND              VIA   -    MD0100PA00X+126023Y+040713X0200Y         S0      
317GND              VIA   -    MD0100PA00X+097569Y+015395X0200Y         S0      
317GND              VIA   -    MD0100PA00X+097569Y+015695X0200Y         S0      
327GND              PD112 -A   M      A01X+097441Y+015316X0670Y0990R180 S1      
317GND              VIA   -    MD0100PA00X+096042Y+015770X0200Y    R270 S0      
317GND              VIA   -    MD0100PA00X+095742Y+015770X0200Y    R270 S0      
317GND              VIA   -    MD0100PA00X+096398Y+017715X0200Y    R270 S0      
317GND              VIA   -    MD0100PA00X+096474Y+017992X0200Y    R270 S0      
317GND              VIA   -    MD0100PA00X+096224Y+017992X0200Y    R270 S0      
317GND              VIA   -    MD0100PA00X+029627Y+006913X0200Y         S0      
317GND              VIA   -    MD0100PA00X+009975Y+015581X0200Y         S0      
317GND              VIA   -    M      A01X+010793Y+015877X0200Y         S2      
017GND              VIA   -    M      A18X+010793Y+015877X0260Y         S2      
017GND                    -    MD0100PA00X+010793Y+015877                       
317GND              VIA   -    M      A01X+010483Y+015119X0200Y         S2      
017GND              VIA   -    M      A18X+010483Y+015119X0260Y         S2      
017GND                    -    MD0100PA00X+010483Y+015119                       
317GND              VIA   -    MD0100PA00X+009372Y+015905X0200Y         S0      
317GND              VIA   -    MD0100PA00X+008915Y+015449X0200Y         S0      
327GND              U56   -TH  M      A01X+009145Y+015679X0670Y0670     S1      
317GND              VIA   -    M      A01X+007178Y+016119X0200Y         S2      
017GND              VIA   -    M      A18X+007178Y+016119X0260Y         S2      
017GND                    -    MD0100PA00X+007178Y+016119                       
317GND              VIA   -    MD0100PA00X+007178Y+015719X0200Y         S0      
317GND              VIA   -    MD0100PA00X+024772Y+007186X0200Y         S0      
317GND              VIA   -    MD0100PA00X+024772Y+007586X0200Y         S0      
317GND              VIA   -    MD0100PA00X+024430Y+005976X0200Y         S0      
327GND              PC2174-2          A01X+027684Y+009918X0198Y0197     S1      
327GND              PC2206-2          A01X+098884Y+019188X0198Y0197R270 S1      
327GND              PC2217-2          A01X+098470Y+018935X0198Y0197     S1      
327GND              PC2082-2          A01X+175764Y+009308X0400Y0500R180 S1      
327GND              PC2160-2          A01X+175196Y+010031X0198Y0197     S1      
327GND              PC2092-2          A01X+175651Y+008541X0198Y0197     S1      
327GND              PC2211-1          A01X+098960Y+018263X0198Y0197R270 S1      
327GND              R3511 -2          A18X+020051Y+166448X0198Y0197     S2      
317GND              VIA   -    MD0100PA00X+019904Y+166692X0200Y         S0      
317GND              VIA   -    MD0100PA00X+131311Y+120090X0200Y    R090 S0      
317GND              VIA   -    MD0100PA00X+131311Y+119540X0200Y    R090 S0      
317GND              VIA   -    MD0100PA00X+134048Y+120901X0200Y    R090 S0      
317GND              VIA   -    MD0100PA00X+133949Y+120230X0200Y    R090 S0      
317GND              VIA   -    MD0100PA00X+134861Y+121846X0200Y    R270 S0      
317GND              VIA   -    MD0100PA00X+134861Y+121296X0200Y    R270 S0      
317GND              VIA   -    MD0100PA00X+136814Y+122230X0200Y    R090 S0      
317GND              VIA   -    MD0100PA00X+136814Y+122780X0200Y    R090 S0      
327GND              U51   -4          A18X+086460Y+128429X0140Y0630R270 S2      
317GND              VIA   -    MD0100PA00X+085945Y+128429X0200Y         S0      
317GND              VIA   -    MD0100PA00X+072192Y+141694X0200Y    R090 S0      
317GND              VIA   -    MD0100PA00X+072192Y+141434X0200Y    R090 S0      
317GND              VIA   -    MD0100PA00X+078276Y+140525X0200Y    R090 S0      
317GND              VIA   -    MD0100PA00X+078011Y+140537X0200Y    R090 S0      
327GND              PC8007-2          A01X+078149Y+140956X0400Y0500R180 S1      
327GND              PC8006-2          A18X+072550Y+141550X0400Y0500R180 S2      
327GND              PR603 -2          A01X+014700Y+144242X0198Y0197R270 S1      
317GND              VIA   -    MD0100PA00X+014698Y+144000X0200Y         S0      
327GND              PC29  -2          A01X+014103Y+145219X0198Y0197R090 S1      
327GND              PC366 -2          A01X+013712Y+145223X0198Y0197R090 S1      
327GND              PC93  -2          A01X+013312Y+145223X0198Y0197R090 S1      
317GND              VIA   -    M      A01X+014103Y+145470X0200Y    R090 S2      
017GND              VIA   -    M      A18X+014103Y+145470X0260Y    R090 S2      
017GND                    -    MD0100PA00X+014103Y+145470                       
317GND              VIA   -    MD0100PA00X+013712Y+145475X0200Y    R090 S0      
317GND              VIA   -    M      A01X+013312Y+145475X0200Y    R090 S2      
017GND              VIA   -    M      A18X+013312Y+145475X0260Y    R090 S2      
017GND                    -    MD0100PA00X+013312Y+145475                       
317GND              VIA   -    MD0100PA00X+097100Y+130000X0200Y    R090 S0      
327GND              C1083 -2          A18X+095792Y+126700X0198Y0197     S2      
327GND              C1082 -2          A18X+095792Y+127100X0198Y0197     S2      
327GND              C1080 -2          A18X+095792Y+127500X0198Y0197     S2      
327GND              C1081 -2          A18X+095792Y+127900X0198Y0197     S2      
327GND              C1075 -2          A18X+096750Y+129758X0198Y0197R270 S2      
327GND              C1077 -2          A18X+096200Y+129900X0400Y0500R090 S2      
317GND              VIA   -    MD0100PA00X+088446Y+144697X0200Y         S0      
317GND              VIA   -    MD0100PA00X+068854Y+145514X0200Y    R180 S0      
317GND              VIA   -    MD0100PA00X+069730Y+145414X0200Y    R180 S0      
327GND              C1068 -2          A18X+062860Y+163595X0120Y0150     S2      
317GND              VIA   -    MD0100PA00X+064052Y+163548X0200Y         S0      
327GND              Q108  -4          A18X+044476Y+164144X0170Y0200R270 S2      
317GND              VIA   -    MD0100PA00X+044739Y+164144X0200Y         S0      
327GND              R3028 -2          A01X+045308Y+164701X0198Y0197R090 S1      
317GND              VIA   -    MD0100PA00X+029252Y+139813X0200Y         S0      
317GND              VIA   -    MD0100PA00X+029252Y+140063X0200Y         S0      
317GND              VIA   -    MD0100PA00X+030780Y+139827X0200Y         S0      
317GND              VIA   -    MD0100PA00X+030780Y+140077X0200Y         S0      
317GND              VIA   -    MD0100PA00X+029512Y+140063X0200Y         S0      
317GND              VIA   -    MD0100PA00X+029512Y+139813X0200Y         S0      
317GND              VIA   -    MD0100PA00X+030520Y+140077X0200Y         S0      
317GND              VIA   -    MD0100PA00X+030520Y+139827X0200Y         S0      
317GND              VIA   -    MD0100PA00X+032431Y+139410X0200Y         S0      
317GND              VIA   -    MD0100PA00X+032431Y+140180X0200Y         S0      
317GND              VIA   -    MD0100PA00X+032431Y+139920X0200Y         S0      
317GND              VIA   -    MD0100PA00X+032431Y+139660X0200Y         S0      
317GND              VIA   -    MD0100PA00X+033383Y+139380X0200Y         S0      
317GND              VIA   -    MD0100PA00X+033383Y+140150X0200Y         S0      
317GND              VIA   -    MD0100PA00X+033383Y+139890X0200Y         S0      
317GND              VIA   -    MD0100PA00X+033383Y+139630X0200Y         S0      
327GND              PC390 -2          A01X+032899Y+139791X0630Y1380     S1      
327GND              PC393 -2          A01X+030004Y+140830X0630Y1380     S1      
327GND              PR6557-2          A18X+182351Y+153489X0280Y0320     S2      
317GND              VIA   -    MD0100PA00X+017272Y+143267X0200Y    R180 S0      
317GND              VIA   -    MD0100PA00X+016342Y+143267X0200Y    R180 S0      
317GND              VIA   -    MD0100PA00X+016342Y+143017X0200Y    R180 S0      
317GND              VIA   -    MD0100PA00X+016342Y+142767X0200Y    R180 S0      
317GND              VIA   -    MD0100PA00X+016342Y+142517X0200Y    R180 S0      
317GND              VIA   -    MD0100PA00X+017272Y+142767X0200Y    R180 S0      
317GND              VIA   -    MD0100PA00X+017272Y+143017X0200Y    R180 S0      
317GND              VIA   -    MD0100PA00X+017272Y+142517X0200Y    R180 S0      
327GND              PC454 -2          A01X+016807Y+143273X0630Y1380     S1      
327GND              PC6813-2   M      A18X+005646Y+152259X0950Y1110R270 S2      
327GND              PC6815-2   M      A18X+009148Y+152259X0950Y1110R270 S2      
327GND              R3032 -2          A18X+041392Y+165350X0198Y0197     S2      
327GND              PR532 -2          A18X+123100Y+141158X0198Y0197R270 S2      
317GND              VIA   -    MD0100PA00X+141257Y+155695X0200Y         S0      
317GND              VIA   -    MD0100PA00X+101707Y+129035X0200Y         S0      
317GND              VIA   -    MD0100PA00X+101931Y+128916X0200Y         S0      
317GND              VIA   -    MD0100PA00X+102191Y+128912X0200Y         S0      
327GND              C1074 -2          A18X+101430Y+129010X0198Y0197R180 S2      
327GND              C1076 -2          A18X+101814Y+128479X0400Y0500     S2      
317GND              VIA   -    MD0100PA00X+083555Y+128132X0200Y         S0      
327GND              C1079 -2          A18X+099744Y+126713X0198Y0197R180 S2      
317GND              VIA   -    MD0100PA00X+099989Y+126713X0200Y    R180 S0      
327GND              R3441 -2   M      A01X+073747Y+169028X0198Y0197R090 S1      
327GND              C1085 -2          A18X+100849Y+127975X0198Y0197R180 S2      
327GND              C1084 -2          A18X+100842Y+127577X0198Y0197R180 S2      
327GND              C1078 -2          A18X+100844Y+127174X0198Y0197R180 S2      
317GND              VIA   -    MD0100PA00X+101094Y+127975X0200Y    R180 S0      
317GND              VIA   -    MD0100PA00X+101086Y+127577X0200Y    R180 S0      
317GND              VIA   -    MD0100PA00X+101089Y+127174X0200Y    R180 S0      
317GND              VIA   -    MD0100PA00X+096850Y+130000X0200Y    R090 S0      
317GND              VIA   -    MD0100PA00X+096600Y+130000X0200Y    R090 S0      
327GND              R1240 -2          A18X+083943Y+129607X0198Y0197     S2      
327GND              R1242 -2          A18X+083944Y+129177X0198Y0197     S2      
327GND              C1095 -2          A18X+083813Y+128547X0198Y0197     S2      
327GND              R1268 -2          A18X+084918Y+126978X0198Y0197     S2      
317GND              VIA   -    MD0100PA00X+083659Y+129533X0200Y         S0      
317GND              VIA   -    MD0100PA00X+083667Y+129136X0200Y         S0      
317GND              VIA   -    MD0100PA00X+083568Y+128547X0200Y         S0      
317GND              VIA   -    MD0100PA00X+084672Y+126978X0200Y         S0      
327GND              R1223 -2          A18X+092600Y+128305X0198Y0197R180 S2      
327GND              R1220 -2          A18X+092616Y+127871X0198Y0197R180 S2      
327GND              R1221 -2          A18X+092603Y+127459X0198Y0197R180 S2      
327GND              R1229 -2          A18X+092608Y+127041X0198Y0197R180 S2      
327GND              R1226 -2          A18X+092593Y+126635X0198Y0197R180 S2      
317GND              VIA   -    MD0100PA00X+092883Y+128305X0200Y    R180 S0      
317GND              VIA   -    MD0100PA00X+092898Y+127871X0200Y    R180 S0      
317GND              VIA   -    MD0100PA00X+092885Y+127459X0200Y    R180 S0      
317GND              VIA   -    MD0100PA00X+092890Y+127041X0200Y    R180 S0      
317GND              VIA   -    MD0100PA00X+092875Y+126635X0200Y    R180 S0      
327GND              R1225 -2          A18X+092616Y+129596X0198Y0197R180 S2      
327GND              R1222 -2          A18X+092608Y+129168X0198Y0197R180 S2      
327GND              R1224 -2          A18X+092611Y+128719X0198Y0197R180 S2      
317GND              VIA   -    MD0100PA00X+092898Y+129596X0200Y    R180 S0      
317GND              VIA   -    MD0100PA00X+092891Y+129168X0200Y    R180 S0      
317GND              VIA   -    MD0100PA00X+092893Y+128719X0200Y    R180 S0      
327GND              C1090 -2          A18X+090087Y+129803X0198Y0197R180 S2      
327GND              C1088 -2          A18X+090083Y+129385X0198Y0197R180 S2      
327GND              C1089 -2          A18X+090110Y+128963X0198Y0197R180 S2      
327GND              C1091 -2          A18X+090112Y+128542X0198Y0197R180 S2      
327GND              C1087 -2          A18X+090108Y+128120X0198Y0197R180 S2      
327GND              C1086 -2          A18X+090112Y+127697X0198Y0197R180 S2      
327GND              C1092 -2          A18X+090120Y+127269X0198Y0197R180 S2      
327GND              C1093 -2          A18X+090116Y+126842X0198Y0197R180 S2      
317GND              VIA   -    MD0100PA00X+090369Y+129803X0200Y    R180 S0      
317GND              VIA   -    MD0100PA00X+090365Y+129385X0200Y    R180 S0      
317GND              VIA   -    MD0100PA00X+090392Y+128963X0200Y    R180 S0      
317GND              VIA   -    MD0100PA00X+090394Y+128542X0200Y    R180 S0      
317GND              VIA   -    MD0100PA00X+090390Y+128120X0200Y    R180 S0      
317GND              VIA   -    MD0100PA00X+090395Y+127697X0200Y    R180 S0      
317GND              VIA   -    MD0100PA00X+090402Y+127269X0200Y    R180 S0      
317GND              VIA   -    MD0100PA00X+090398Y+126842X0200Y    R180 S0      
317GND              VIA   -    MD0100PA00X+042106Y+156917X0200Y         S0      
317GND              VIA   -    MD0100PA00X+043024Y+158173X0200Y         S0      
317GND              VIA   -    MD0100PA00X+012726Y+158858X0200Y    R180 S0      
317GND              VIA   -    MD0100PA00X+012725Y+158580X0200Y    R180 S0      
317GND              VIA   -    MD0100PA00X+061297Y+044726X0200Y         S0      
327GND              U24   -S          A01X+060817Y+044726X0400Y0560R270 S1      
317GND              VIA   -    MD0100PA00X+010886Y+152641X0193Y         S0      
317GND              VIA   -    MD0100PA00X+010886Y+152884X0193Y         S0      
327GND              U23   -3          A01X+060922Y+042524X0220Y0320R090 S1      
317GND              VIA   -    MD0100PA00X+060580Y+042558X0200Y         S0      
327GND              C9007 -2          A01X+060608Y+041200X0198Y0197     S1      
327GND              C1059 -2          A01X+080863Y+038679X0198Y0197     S1      
317GND              VIA   -    MD0100PA00X+081157Y+038767X0200Y         S0      
327GND              U28   -3          A01X+078790Y+037745X0220Y0530R270 S1      
317GND              VIA   -    MD0100PA00X+079249Y+037745X0200Y         S0      
327GND              C1060 -2          A01X+083542Y+047500X0198Y0197R180 S1      
317GND              VIA   -    MD0100PA00X+083542Y+047789X0200Y         S0      
327GND              U9001 -3          A01X+085224Y+046728X0220Y0320     S1      
317GND              VIA   -    MD0100PA00X+085224Y+047095X0200Y         S0      
327GND              U9002 -3          A01X+084550Y+039044X0400Y0150     S1      
317GND              VIA   -    MD0100PA00X+084186Y+039044X0200Y         S0      
327GND              C9008 -2          A01X+086208Y+039550X0198Y0197     S1      
317GND              VIA   -    MD0100PA00X+086208Y+039854X0200Y         S0      
317GND              VIA   -    MD0100PA00X+039492Y+159002X0200Y         S0      
317GND              VIA   -    MD0100PA00X+096859Y+128819X0200Y    R180 S0      
317GND              VIA   -    MD0100PA00X+099930Y+128569X0200Y         S0      
327GND              U50   -2          A18X+099433Y+128819X0150Y0630R270 S2      
327GND              U50   -3          A18X+099433Y+128569X0150Y0630R270 S2      
327GND              U50   -4          A18X+099433Y+128319X0150Y0630R270 S2      
327GND              U50   -15         A18X+097342Y+128819X0150Y0630R270 S2      
317GND              VIA   -    M      A01X+099930Y+128922X0300Y         S1      
017GND              VIA   -    M      A18X+099930Y+128922X0200Y         S1      
017GND                    -    MD0100PA00X+099930Y+128922                       
317GND              VIA   -    M      A01X+099930Y+128257X0300Y         S1      
017GND              VIA   -    M      A18X+099930Y+128257X0200Y         S1      
017GND                    -    MD0100PA00X+099930Y+128257                       
317GND              VIA   -    MD0100PA00X+095500Y+127900X0200Y         S0      
317GND              VIA   -    MD0100PA00X+095500Y+127500X0200Y         S0      
317GND              VIA   -    MD0100PA00X+095500Y+127100X0200Y         S0      
317GND              VIA   -    MD0100PA00X+095500Y+126700X0200Y         S0      
327GND              C552  -2          A01X+061508Y+044000X0198Y0197     S1      
327GND              U30   -3          A01X+066274Y+037068X0220Y0530     S1      
317GND              VIA   -    MD0100PA00X+066274Y+037524X0200Y         S0      
317GND              VIA   -    MD0100PA00X+014078Y+163804X0180Y    R090 S0      
327GND              R1212 -1          A18X+065541Y+167148X0120Y0150R270 S2      
327GND              U41   -5          A18X+065987Y+166975X0130Y0250R270 S2      
317GND              VIA   -    MD0100PA00X+065591Y+166874X0200Y         S0      
327GND              C1066 -2          A18X+067096Y+166745X0120Y0150R090 S2      
327GND              R1217 -1          A18X+164891Y+167647X0120Y0150R180 S2      
327GND              Q131  -4          A18X+066320Y+170070X0170Y0200R090 S2      
317GND              VIA   -    MD0100PA00X+066400Y+170311X0200Y         S0      
317GND              VIA   -    MD0100PA00X+064953Y+170927X0200Y         S0      
327GND              C13   -2          A18X+064726Y+171784X0198Y0197R270 S2      
327GND              Q102  -4          A01X+066465Y+171706X0170Y0200R090 S1      
327GND              R4124 -2          A18X+064326Y+169370X0198Y0197R090 S2      
327GND              U175  -4          A01X+064656Y+169216X0140Y0560     S1      
327GND              R1083 -2          A18X+167343Y+154207X0120Y0150     S2      
327GND              C1058 -2          A01X+064950Y+037958X0198Y0197R090 S1      
317GND              VIA   -    MD0100PA00X+064950Y+038250X0200Y         S0      
327GND              U42   -5          A01X+045429Y+158344X0130Y0250R180 S1      
327GND              R1213 -1   M      A01X+044622Y+159052X0120Y0150R270 S1      
327GND              C7502 -2          A01X+043456Y+156391X0120Y0150R180 S1      
317GND              VIA   -    MD0080PA00X+022905Y+152145X0160Y         S0      
327GND              C125  -2          A18X+022905Y+152165X0120Y0150R090 S2      
327GND              U48   -5          A01X+114854Y+155603X0130Y0250R090 S1      
317GND              VIA   -    MD0100PA00X+115138Y+155603X0200Y         S0      
327GND              U19   -4          A01X+042537Y+159028X0350Y0500R180 S1      
317GND              VIA   -    MD0100PA00X+042201Y+159233X0200Y         S0      
327GND              C1072 -2          A01X+113732Y+155401X0120Y0150R270 S1      
317GND              VIA   -    MD0100PA00X+113504Y+155337X0200Y         S0      
327GND              R1218 -1          A01X+115219Y+156752X0120Y0150R270 S1      
317GND              VIA   -    MD0100PA00X+115219Y+157057X0200Y         S0      
327GND              U33   -3          A01X+037268Y+030376X0220Y0530R270 S1      
317GND              VIA   -    MD0100PA00X+036790Y+030376X0200Y         S0      
327GND              C1069 -2          A01X+038446Y+159394X0120Y0150R090 S1      
327GND              R1056 -2          A01X+169198Y+157052X0120Y0150     S1      
327GND              R1058 -2          A01X+169198Y+157372X0120Y0150     S1      
317GND              VIA   -    MD0100PA00X+117260Y+155456X0200Y    R270 S0      
317GND              VIA   -    M      A01X+039332Y+157335X0200Y         S2      
017GND              VIA   -    M      A18X+039332Y+157335X0260Y         S2      
017GND                    -    MD0100PA00X+039332Y+157335                       
327GND              R984  -2          A18X+117926Y+154594X0120Y0150     S2      
327GND              R973  -2          A18X+117926Y+154284X0120Y0150     S2      
327GND              R982  -2          A18X+117926Y+155234X0120Y0150     S2      
327GND              R971  -2          A01X+117252Y+156460X0120Y0150R180 S1      
327GND              R997  -2          A01X+117252Y+157550X0120Y0150R180 S1      
327GND              R1001 -2          A01X+117252Y+157100X0120Y0150R180 S1      
327GND              R995  -2          A01X+117926Y+154380X0120Y0150R180 S1      
327GND              R980  -2          A01X+117926Y+154742X0120Y0150R180 S1      
327GND              C2329 -2          A18X+113465Y+165347X0198Y0197R090 S2      
327GND              C1073 -2          A18X+117783Y+168213X0120Y0150R180 S2      
317GND              VIA   -    M      A01X+117893Y+168670X0200Y         S2      
017GND              VIA   -    M      A18X+117893Y+168670X0260Y         S2      
017GND                    -    MD0100PA00X+117893Y+168670                       
327GND              R9025 -2          A01X+063800Y+041542X0198Y0197R270 S1      
327GND              C9005 -2          A01X+063800Y+042558X0198Y0197R090 S1      
327GND              C2662 -2          A18X+038804Y+105327X0198Y0197     S2      
327GND              C2659 -2          A18X+038604Y+104977X0198Y0197     S2      
327GND              C2515 -2          A18X+136273Y+104976X0198Y0197     S2      
327GND              C2512 -2          A18X+136423Y+105326X0198Y0197     S2      
327GND              C1065 -2          A01X+022108Y+015650X0198Y0197     S1      
327GND              C1062 -2          A01X+027550Y+023408X0198Y0197R090 S1      
327GND              C1064 -2          A01X+029300Y+021942X0198Y0197R270 S1      
327GND              C1061 -2          A01X+039458Y+031150X0198Y0197     S1      
327GND              C1063 -2          A01X+034208Y+028500X0198Y0197     S1      
327GND              C672  -2          A01X+169123Y+155953X0198Y0197     S1      
327GND              C669  -2          A01X+169123Y+156353X0198Y0197     S1      
327GND              C665  -2   M      A01X+169007Y+155430X0400Y0500R270 S1      
327GND              C666  -2   M      A01X+168157Y+155420X0400Y0500R180 S1      
327GND              C798  -2   M      A01X+168151Y+156974X0400Y0500R180 S1      
327GND              C795  -2   M      A01X+168151Y+157660X0400Y0500R180 S1      
317GND              VIA   -    MD0100PA00X+169123Y+155953X0200Y         S0      
317GND              VIA   -    MD0100PA00X+169155Y+155529X0200Y    R090 S0      
317GND              VIA   -    MD0100PA00X+168858Y+155328X0200Y    R090 S0      
317GND              VIA   -    MD0100PA00X+168256Y+155273X0200Y         S0      
317GND              VIA   -    MD0100PA00X+168056Y+155569X0200Y         S0      
317GND              VIA   -    MD0100PA00X+169553Y+154519X0200Y    R180 S0      
317GND              VIA   -    MD0100PA00X+169123Y+156353X0200Y         S0      
317GND              VIA   -    MD0100PA00X+168988Y+157207X0200Y         S0      
317GND              VIA   -    MD0100PA00X+168049Y+157124X0200Y         S0      
317GND              VIA   -    MD0100PA00X+168049Y+157809X0200Y         S0      
317GND              VIA   -    MD0100PA00X+168249Y+157512X0200Y         S0      
317GND              VIA   -    MD0100PA00X+168249Y+156827X0200Y         S0      
327GND              C564  -2   M      A01X+119983Y+159210X0400Y0500R180 S1      
327GND              C556  -2          A01X+119981Y+159895X0400Y0500R180 S1      
327GND              C559  -2          A01X+119891Y+160595X0400Y0500R090 S1      
327GND              R1016 -2   M      A01X+142214Y+155685X0120Y0150R270 S1      
327GND              R1014 -2          A01X+141894Y+155685X0120Y0150R270 S1      
327GND              R1042 -2          A18X+141278Y+154040X0120Y0150     S2      
317GND              VIA   -    MD0100PA00X+118136Y+155104X0200Y    R270 S0      
317GND              VIA   -    MD0100PA00X+118136Y+154742X0200Y    R270 S0      
317GND              VIA   -    MD0100PA00X+118136Y+154380X0200Y    R270 S0      
317GND              VIA   -    M      A01X+117252Y+157325X0200Y         S2      
017GND              VIA   -    M      A18X+117252Y+157325X0260Y         S2      
017GND                    -    MD0100PA00X+117252Y+157325                       
317GND              VIA   -    MD0100PA00X+117252Y+156235X0200Y         S0      
317GND              VIA   -    MD0100PA00X+120082Y+159350X0200Y    R090 S0      
327GND              U49   -5          A18X+117545Y+167106X0130Y0250     S2      
317GND              VIA   -    MD0100PA00X+117545Y+166805X0200Y         S0      
327GND              R1219 -1          A18X+116201Y+166976X0120Y0150R180 S2      
317GND              VIA   -    MD0100PA00X+115974Y+166976X0200Y         S0      
317GND              VIA   -    MD0100PA00X+039624Y+031551X0200Y         S0      
327GND              U32   -S          A01X+017817Y+014726X0400Y0560R270 S1      
317GND              VIA   -    MD0100PA00X+018255Y+014726X0200Y         S0      
317GND              VIA   -    MD0100PA00X+022200Y+016000X0200Y         S0      
327GND              U31   -3          A01X+020278Y+014876X0220Y0320R270 S1      
317GND              VIA   -    MD0100PA00X+020676Y+014876X0200Y         S0      
327GND              U37   -3          A01X+027150Y+022044X0400Y0150     S1      
317GND              VIA   -    MD0100PA00X+026750Y+022044X0200Y         S0      
317GND              VIA   -    MD0100PA00X+027950Y+023408X0200Y         S0      
327GND              U35   -3          A01X+028526Y+023722X0220Y0320R180 S1      
317GND              VIA   -    MD0100PA00X+028526Y+023400X0200Y         S0      
317GND              VIA   -    MD0100PA00X+029300Y+021650X0200Y         S0      
327GND              U43   -5          A18X+063033Y+164703X0130Y0250R180 S2      
317GND              VIA   -    MD0100PA00X+034208Y+028792X0200Y         S0      
317GND              VIA   -    MD0100PA00X+062796Y+165411X0200Y         S0      
327GND              U34   -3          A01X+032618Y+027026X0220Y0530R270 S1      
317GND              VIA   -    MD0100PA00X+033100Y+027026X0200Y         S0      
327GND              R1214 -1          A18X+063861Y+165064X0120Y0150     S2      
327GND              C1071 -2          A18X+166322Y+168802X0120Y0150R180 S2      
317GND              VIA   -    MD0100PA00X+166426Y+169079X0200Y         S0      
317GND              VIA   -    MD0100PA00X+164770Y+167423X0200Y         S0      
317GND              VIA   -    MD0100PA00X+143398Y+165566X0200Y    R270 S0      
327GND              R2838 -2          A18X+141709Y+164972X0198Y0197R180 S2      
317GND              VIA   -    MD0100PA00X+142004Y+164972X0200Y         S0      
327GND              C1774 -2          A18X+141824Y+164143X0198Y0197R180 S2      
317GND              VIA   -    MD0100PA00X+141636Y+164403X0200Y         S0      
317GND              VIA   -    MD0100PA00X+003585Y+070573X0200Y    R180 S0      
327GND              R1127 -2          A01X+148058Y+166892X0120Y0150     S1      
317GND              VIA   -    MD0100PA00X+147162Y+167010X0200Y         S0      
327GND              U17   -4          A18X+148258Y+166385X0350Y0500R090 S2      
317GND              VIA   -    MD0100PA00X+146903Y+166779X0200Y         S0      
327GND              U17   -7          A18X+146211Y+167385X0350Y0500R090 S2      
317GND              VIA   -    MD0100PA00X+146626Y+167516X0200Y         S0      
317GND              VIA   -    MD0100PA00X+091989Y+017950X0200Y         S0      
317GND              VIA   -    MD0100PA00X+091989Y+017700X0200Y         S0      
317GND              VIA   -    MD0100PA00X+091989Y+017450X0200Y         S0      
317GND              VIA   -    MD0100PA00X+091989Y+017200X0200Y         S0      
317GND              VIA   -    MD0100PA00X+091989Y+016950X0200Y         S0      
317GND              VIA   -    MD0100PA00X+091989Y+016700X0200Y         S0      
317GND              VIA   -    MD0100PA00X+091739Y+016700X0200Y         S0      
317GND              VIA   -    MD0100PA00X+091739Y+017450X0200Y         S0      
317GND              VIA   -    MD0100PA00X+091739Y+017200X0200Y         S0      
317GND              VIA   -    MD0100PA00X+091739Y+016950X0200Y         S0      
317GND              VIA   -    MD0100PA00X+091739Y+017700X0200Y         S0      
327GND              U46   -5          A01X+146965Y+167940X0130Y0250R270 S1      
317GND              VIA   -    MD0100PA00X+146660Y+167940X0200Y         S0      
327GND              C1070 -2          A01X+148100Y+168405X0120Y0150R090 S1      
317GND              VIA   -    MD0100PA00X+147938Y+168598X0200Y         S0      
327GND              R1216 -1          A01X+146550Y+166845X0120Y0150R090 S1      
317GND              VIA   -    MD0100PA00X+146650Y+166600X0200Y         S0      
327GND              C1057 -2          A18X+145395Y+167900X0120Y0150     S2      
317GND              VIA   -    MD0100PA00X+145395Y+168145X0200Y         S0      
327GND              U96   -4          A18X+096313Y+088706X0240Y0460     S2      
317GND              VIA   -    MD0100PA00X+096313Y+088294X0200Y         S0      
327GND              U5    -4          A18X+094406Y+088692X0240Y0460     S2      
317GND              VIA   -    MD0100PA00X+094406Y+088289X0200Y         S0      
327GND              U100  -2          A01X+066338Y+051626X0320Y0400R270 S1      
317GND              VIA   -    MD0100PA00X+065940Y+051626X0200Y         S0      
327GND              C6122 -2          A01X+067950Y+052408X0198Y0197R090 S1      
317GND              VIA   -    MD0100PA00X+067950Y+052683X0200Y         S0      
327GND              U8002 -1          A01X+031724Y+025653X0260Y0380R180 S1      
317GND              VIA   -    MD0100PA00X+031724Y+025297X0200Y         S0      
327GND              C8004 -2          A01X+005408Y+030350X0198Y0197     S1      
317GND              VIA   -    MD0100PA00X+005662Y+030350X0200Y         S0      
327GND              U8001 -1          A01X+164224Y+039603X0260Y0380R180 S1      
317GND              VIA   -    MD0100PA00X+164224Y+039960X0200Y         S0      
327GND              Q9001 -1          A01X+068978Y+164589X0170Y0200R090 S1      
317GND              VIA   -    MD0100PA00X+068682Y+164743X0200Y         S0      
327GND              Q108  -1          A18X+045224Y+164656X0170Y0200R270 S2      
317GND              VIA   -    MD0100PA00X+045410Y+164958X0200Y         S0      
317GND              VIA   -    MD0100PA00X+068758Y+142505X0200Y         S0      
327GND              C8011 -2          A01X+076738Y+167332X0198Y0197R090 S1      
317GND              VIA   -    M      A01X+076738Y+167659X0200Y         S2      
017GND              VIA   -    M      A18X+076738Y+167659X0260Y         S2      
017GND                    -    MD0100PA00X+076738Y+167659                       
317GND              VIA   -    M      A01X+067163Y+169079X0200Y         S2      
017GND              VIA   -    M      A18X+067163Y+169079X0260Y         S2      
017GND                    -    MD0100PA00X+067163Y+169079                       
327GND              R6787 -2          A01X+007841Y+160463X0198Y0197R270 S1      
317GND              VIA   -    MD0100PA00X+008040Y+160222X0200Y         S0      
327GND              R9007 -2          A01X+067773Y+164784X0198Y0197R180 S1      
317GND              VIA   -    MD0100PA00X+067449Y+164784X0200Y         S0      
327GND              C9001 -2          A01X+067773Y+163584X0198Y0197R180 S1      
317GND              VIA   -    M      A01X+067348Y+166267X0200Y         S2      
017GND              VIA   -    M      A18X+067348Y+166267X0260Y         S2      
017GND                    -    MD0100PA00X+067348Y+166267                       
327GND              U21   -7          A01X+067297Y+165855X0350Y0500R180 S1      
327GND              C7504 -2          A01X+067454Y+165276X0120Y0150R180 S1      
327GND              Q9001 -4          A01X+069726Y+164077X0170Y0200R090 S1      
317GND              VIA   -    MD0100PA00X+069315Y+164077X0200Y         S0      
327GND              U181  -12         A01X+074020Y+164333X0240Y0540     S1      
317GND              VIA   -    MD0100PA00X+074304Y+164333X0200Y         S0      
327GND              R2694 -2          A01X+070380Y+162762X0198Y0197R270 S1      
327GND              R6233 -2          A18X+071593Y+168228X0198Y0197R270 S2      
317GND              VIA   -    MD0100PA00X+071235Y+168228X0200Y         S0      
317GND              VIA   -    MD0100PA00X+066580Y+165234X0200Y         S0      
317GND              VIA   -    MD0100PA00X+064215Y+164996X0200Y         S0      
317GND              VIA   -    MD0100PA00X+019295Y+156050X0200Y    R090 S0      
327GND              C229  -2          A01X+019104Y+157295X0400Y0500R090 S1      
327GND              C247  -2   M      A01X+019196Y+155910X0400Y0500R180 S1      
327GND              C240  -2          A01X+019193Y+156595X0400Y0500R180 S1      
327GND              R3440 -2          A01X+074133Y+168689X0198Y0197R090 S1      
327GND              R6721 -2          A01X+016465Y+153160X0120Y0150R180 S1      
327GND              PC2201-2          A01X+079134Y+028182X0198Y0197     S1      
327GND              C8010 -2          A01X+087792Y+030150X0198Y0197R180 S1      
317GND              VIA   -    MD0100PA00X+087545Y+030150X0200Y         S0      
327GND              R2696 -2          A01X+069676Y+168200X0198Y0197R180 S1      
317GND              VIA   -    MD0100PA00X+069800Y+168469X0200Y    R090 S0      
327GND              R3442 -2          A01X+073243Y+168825X0198Y0197R090 S1      
327GND              R3443 -2          A01X+072845Y+168808X0198Y0197R090 S1      
317GND              VIA   -    MD0100PA00X+073855Y+169322X0200Y         S0      
317GND              VIA   -    MD0100PA00X+073243Y+169066X0200Y         S0      
317GND              VIA   -    M      A01X+072845Y+169049X0200Y         S2      
017GND              VIA   -    M      A18X+072845Y+169049X0260Y         S2      
017GND                    -    MD0100PA00X+072845Y+169049                       
317GND              VIA   -    MD0100PA00X+016465Y+152935X0200Y         S0      
327GND              R728  -2          A01X+016465Y+153800X0120Y0150R180 S1      
327GND              R726  -2          A01X+016465Y+154250X0120Y0150R180 S1      
317GND              VIA   -    MD0100PA00X+016465Y+154025X0200Y         S0      
327GND              C1713 -2          A01X+070662Y+166300X0198Y0197R270 S1      
317GND              VIA   -    MD0100PA00X+070347Y+166300X0200Y         S0      
327GND              R126  -2          A01X+083698Y+043555X0198Y0197R180 S1      
327GND              Q9003 -4          A01X+062476Y+042156X0170Y0200R270 S1      
317GND              VIA   -    MD0100PA00X+062476Y+042457X0200Y         S0      
327GND              C9003 -2          A18X+070977Y+165739X0198Y0197R090 S2      
327GND              C6084 -2          A18X+070582Y+165738X0198Y0197R090 S2      
317GND              VIA   -    MD0100PA00X+070977Y+165493X0200Y         S0      
317GND              VIA   -    MD0100PA00X+070582Y+165492X0200Y         S0      
327GND              R6235 -2          A18X+071775Y+165738X0198Y0197R090 S2      
317GND              VIA   -    MD0100PA00X+071775Y+165492X0200Y         S0      
317GND              VIA   -    MD0100PA00X+063520Y+041542X0200Y         S0      
327GND              C8015 -2          A18X+072630Y+166066X0198Y0197R090 S2      
317GND              VIA   -    MD0100PA00X+072630Y+165802X0200Y         S0      
327GND              R8109 -2          A18X+073030Y+166066X0198Y0197R090 S2      
317GND              VIA   -    MD0100PA00X+073030Y+165805X0200Y         S0      
327GND              U192  -4          A18X+071077Y+164341X0140Y0560R090 S2      
317GND              VIA   -    MD0100PA00X+070609Y+164341X0200Y         S0      
327GND              R6797 -2          A18X+066555Y+150907X0120Y0150     S2      
317GND              VIA   -    MD0100PA00X+067462Y+153527X0200Y         S0      
317GND              VIA   -    MD0100PA00X+067262Y+153824X0200Y         S0      
327GND              C401  -2   M      A01X+067363Y+153674X0400Y0500R180 S1      
317GND              VIA   -    MD0100PA00X+067469Y+151973X0200Y         S0      
317GND              VIA   -    MD0100PA00X+067268Y+152269X0200Y         S0      
327GND              C367  -2   M      A01X+067370Y+152120X0400Y0500R180 S1      
317GND              VIA   -    MD0100PA00X+068367Y+152229X0200Y    R090 S0      
317GND              VIA   -    MD0100PA00X+068071Y+152028X0200Y    R090 S0      
327GND              C366  -2   M      A01X+068220Y+152130X0400Y0500R270 S1      
317GND              VIA   -    MD0100PA00X+067262Y+154509X0200Y         S0      
317GND              VIA   -    MD0100PA00X+067462Y+154212X0200Y         S0      
327GND              C398  -2   M      A01X+067363Y+154360X0400Y0500R180 S1      
317GND              VIA   -    MD0100PA00X+068812Y+151960X0200Y         S0      
317GND              VIA   -    MD0100PA00X+068335Y+152653X0200Y         S0      
327GND              C370  -2          A01X+068335Y+152653X0198Y0197     S1      
317GND              VIA   -    MD0100PA00X+068335Y+153053X0200Y         S0      
327GND              C373  -2          A01X+068335Y+153053X0198Y0197     S1      
327GND              R892  -2          A01X+067420Y+150514X0120Y0150R180 S1      
317GND              VIA   -    MD0100PA00X+066580Y+153058X0200Y         S0      
317GND              VIA   -    MD0100PA00X+015161Y+166393X0200Y    R090 S0      
317GND              VIA   -    MD0100PA00X+015151Y+167681X0200Y    R090 S0      
317GND              VIA   -    MD0100PA00X+010194Y+166273X0200Y    R270 S0      
317GND              VIA   -    MD0100PA00X+010194Y+165774X0200Y    R270 S0      
317GND              VIA   -    MD0100PA00X+010657Y+166024X0200Y    R090 S0      
317GND              VIA   -    MD0100PA00X+011497Y+166024X0200Y    R090 S0      
317GND              VIA   -    MD0100PA00X+010224Y+168226X0200Y    R090 S0      
317GND              VIA   -    MD0100PA00X+010224Y+168926X0200Y    R090 S0      
317GND              VIA   -    MD0100PA00X+010507Y+168576X0200Y    R090 S0      
317GND              VIA   -    MD0100PA00X+011347Y+168576X0200Y    R090 S0      
317GND              VIA   -    MD0100PA00X+008540Y+167531X0200Y    R090 S0      
317GND              VIA   -    MD0100PA00X+008540Y+167033X0200Y    R090 S0      
317GND              VIA   -    MD0100PA00X+008334Y+165933X0200Y    R090 S0      
317GND              VIA   -    MD0100PA00X+008334Y+165435X0200Y    R090 S0      
317GND              VIA   -    MD0100PA00X+004458Y+167761X0200Y    R090 S0      
317GND              VIA   -    MD0100PA00X+004458Y+167243X0200Y    R090 S0      
317GND              VIA   -    MD0100PA00X+003843Y+165906X0200Y    R090 S0      
317GND              VIA   -    MD0100PA00X+003843Y+165408X0200Y    R090 S0      
317GND              VIA   -    MD0100PA00X+008000Y+170245X0200Y    R090 S0      
317GND              VIA   -    MD0100PA00X+007950Y+172045X0200Y    R090 S0      
317GND              VIA   -    MD0100PA00X+009303Y+170522X0200Y         S0      
317GND              VIA   -    MD0100PA00X+009768Y+172248X0200Y         S0      
317GND              VIA   -    MD0100PA00X+013000Y+171945X0200Y    R135 S0      
317GND              VIA   -    MD0100PA00X+012511Y+170267X0200Y    R180 S0      
317GND              VIA   -    MD0100PA00X+015245Y+162357X0180Y    R090 S0      
317GND              VIA   -    MD0100PA00X+015245Y+162853X0180Y    R090 S0      
327GND              R863  -2          A01X+068411Y+153752X0120Y0150     S1      
327GND              R865  -2          A01X+068411Y+154072X0120Y0150     S1      
317GND              VIA   -    MD0100PA00X+068202Y+153907X0200Y         S0      
317GND              VIA   -    MD0100PA00X+012975Y+158580X0200Y    R180 S0      
317GND              VIA   -    MD0100PA00X+003682Y+146208X0200Y    R090 S0      
317GND              VIA   -    MD0100PA00X+003682Y+145908X0200Y    R090 S0      
317GND              VIA   -    MD0100PA00X+003682Y+145608X0200Y    R090 S0      
317GND              VIA   -    MD0100PA00X+003682Y+146508X0200Y    R090 S0      
317GND              VIA   -    MD0100PA00X+005835Y+140333X0200Y    R180 S0      
317GND              VIA   -    MD0100PA00X+007151Y+144438X0200Y    R180 S0      
327GND              PR533 -2          A18X+013000Y+142508X0198Y0197R270 S2      
327GND              PR231 -2          A18X+013442Y+142900X0198Y0197     S2      
317GND              VIA   -    MD0100PA00X+065219Y+142128X0200Y         S0      
317GND              VIA   -    MD0100PA00X+065587Y+142884X0200Y         S0      
317GND              VIA   -    MD0100PA00X+055909Y+145218X0200Y         S0      
327GND              PQ16  -S   M      A01X+007974Y+141867X0400Y0560     S1      
317GND              VIA   -    M      A01X+007638Y+140662X0200Y         S2      
017GND              VIA   -    M      A18X+007638Y+140662X0260Y         S2      
017GND                    -    MD0100PA00X+007638Y+140662                       
327GND              Q8001 -1          A01X+074844Y+021276X0170Y0200R180 S1      
317GND              VIA   -    MD0100PA00X+074571Y+021276X0200Y         S0      
327GND              Q8001 -4          A01X+075356Y+022024X0170Y0200R180 S1      
317GND              VIA   -    MD0100PA00X+075608Y+022024X0200Y         S0      
327GND              Q3    -4          A01X+082256Y+052824X0170Y0200R180 S1      
317GND              VIA   -    MD0100PA00X+082256Y+053088X0200Y         S0      
327GND              U8008 -2          A01X+051918Y+044200X0240Y0420R270 S1      
317GND              VIA   -    MD0100PA00X+052283Y+044371X0200Y         S0      
327GND              R8122 -2          A01X+057508Y+046200X0198Y0197     S1      
327GND              C8021 -2   M      A01X+057508Y+046600X0198Y0197     S1      
317GND              VIA   -    MD0100PA00X+057780Y+046600X0200Y         S0      
317GND              VIA   -    MD0100PA00X+064927Y+165013X0200Y         S0      
327GND              R6790 -2   M      A01X+064136Y+168597X0120Y0150     S1      
327GND              U20   -4          A01X+063928Y+167880X0350Y0500R180 S1      
317GND              VIA   -    MD0100PA00X+063928Y+168305X0200Y         S0      
327GND              PQ14  -S          A01X+114412Y+144599X0400Y0560R270 S1      
317GND              VIA   -    MD0100PA00X+114412Y+144963X0200Y         S0      
327GND              U15   -4          A01X+113307Y+157945X0350Y0500R270 S1      
327GND              U12   -4          A01X+040038Y+159028X0350Y0500R180 S1      
327GND              C664  -2          A01X+116262Y+159116X0120Y0150R270 S1      
317GND              VIA   -    MD0100PA00X+116003Y+159116X0200Y         S0      
317GND              VIA   -    MD0100PA00X+113183Y+160724X0200Y         S0      
317GND              VIA   -    MD0100PA00X+113179Y+159798X0200Y         S0      
317GND              VIA   -    MD0100PA00X+111726Y+160153X0200Y         S0      
317GND              VIA   -    MD0100PA00X+111378Y+160146X0200Y         S0      
317GND              VIA   -    MD0100PA00X+114506Y+158884X0200Y         S0      
317GND              VIA   -    MD0100PA00X+114306Y+158033X0200Y         S0      
317GND              VIA   -    MD0100PA00X+111800Y+158491X0200Y         S0      
317GND              VIA   -    MD0100PA00X+111833Y+159412X0200Y         S0      
317GND              VIA   -    MD0100PA00X+054593Y+145134X0200Y         S0      
327GND              R1044 -2          A01X+113848Y+157200X0120Y0150R090 S1      
317GND              VIA   -    MD0100PA00X+113617Y+157364X0200Y         S0      
317GND              VIA   -    MD0100PA00X+113752Y+157945X0200Y         S0      
327GND              U15   -7          A01X+115354Y+158945X0350Y0500R270 S1      
317GND              VIA   -    M      A01X+114928Y+158945X0200Y         S2      
017GND              VIA   -    M      A18X+114928Y+158945X0260Y         S2      
017GND                    -    MD0100PA00X+114928Y+158945                       
327GND              C79   -2          A18X+113223Y+164978X0198Y0197     S2      
327GND              C78   -2          A18X+111829Y+164951X0198Y0197R180 S2      
327GND              C2334 -2          A18X+111840Y+165390X0198Y0197R090 S2      
327GND              C2339 -2          A18X+112323Y+165335X0198Y0197R090 S2      
327GND              C80   -2          A18X+112950Y+163858X0198Y0197R270 S2      
327GND              C81   -2          A18X+112296Y+164038X0198Y0197R270 S2      
327GND              C9004 -2          A01X+058650Y+045792X0198Y0197R270 S1      
317GND              VIA   -    MD0100PA00X+058350Y+045792X0200Y         S0      
327GND              C2328 -2          A01X+111539Y+162275X0198Y0197R270 S1      
317GND              VIA   -    M      A01X+111539Y+162031X0200Y         S2      
017GND              VIA   -    M      A18X+111539Y+162031X0260Y         S2      
017GND                    -    MD0100PA00X+111539Y+162031                       
327GND              R2656 -2          A18X+041612Y+162060X0198Y0197R090 S2      
327GND              C6    -2          A18X+042083Y+162058X0198Y0197R090 S2      
327GND              R6788 -2          A01X+040090Y+159856X0120Y0150     S1      
317GND              VIA   -    MD0100PA00X+040090Y+159609X0200Y         S0      
327GND              R6789 -2          A01X+042939Y+159698X0120Y0150     S1      
317GND              VIA   -    MD0100PA00X+116214Y+165804X0200Y         S0      
317GND              VIA   -    MD0100PA00X+114313Y+164907X0200Y         S0      
317GND              VIA   -    MD0100PA00X+114164Y+164002X0200Y         S0      
317GND              VIA   -    MD0100PA00X+114632Y+164942X0200Y         S0      
317GND              VIA   -    MD0100PA00X+114648Y+165844X0200Y         S0      
317GND              VIA   -    MD0100PA00X+044085Y+157653X0200Y         S0      
317GND              VIA   -    MD0100PA00X+041067Y+156117X0200Y         S0      
327GND              R719  -2          A18X+017139Y+151934X0120Y0150     S2      
327GND              R715  -2          A01X+017139Y+151442X0120Y0150R180 S1      
327GND              R723  -2          A18X+017139Y+151294X0120Y0150     S2      
327GND              R725  -2          A01X+017139Y+151080X0120Y0150R180 S1      
327GND              R6723 -2          A18X+017139Y+150984X0120Y0150     S2      
317GND              VIA   -    MD0100PA00X+017349Y+151804X0200Y    R270 S0      
317GND              VIA   -    MD0100PA00X+017349Y+151442X0200Y    R270 S0      
317GND              VIA   -    MD0100PA00X+017349Y+151080X0200Y    R270 S0      
327GND              R1106 -2          A18X+144344Y+154380X0120Y0150     S2      
327GND              C5022 -1          A18X+008692Y+144000X0198Y0197R180 S2      
317GND              VIA   -    MD0100PA00X+008450Y+144000X0200Y         S0      
327GND              C5020 -1          A01X+009008Y+143550X0198Y0197R180 S1      
327GND              C7510 -2          A01X+119033Y+166628X0120Y0150R090 S1      
317GND              VIA   -    MD0100PA00X+119290Y+166628X0200Y         S0      
327GND              U11   -7          A01X+117919Y+166216X0350Y0500R180 S1      
317GND              VIA   -    MD0100PA00X+117919Y+166643X0200Y         S0      
327GND              R6822 -2          A01X+118568Y+169508X0120Y0150R270 S1      
317GND              VIA   -    M      A01X+118568Y+169725X0200Y         S2      
017GND              VIA   -    M      A18X+118568Y+169725X0260Y         S2      
017GND                    -    MD0100PA00X+118568Y+169725                       
327GND              U11   -4          A01X+116919Y+168263X0350Y0500R180 S1      
317GND              VIA   -    M      A01X+116919Y+168712X0200Y         S2      
017GND              VIA   -    M      A18X+116919Y+168712X0260Y         S2      
017GND                    -    MD0100PA00X+116919Y+168712                       
327GND              R2666 -2          A18X+112893Y+168606X0198Y0197     S2      
317GND              VIA   -    MD0100PA00X+112893Y+168860X0200Y         S0      
327GND              C1708 -2          A18X+113639Y+168252X0198Y0197     S2      
317GND              VIA   -    MD0100PA00X+113749Y+168524X0200Y         S0      
327GND              U176  -4          A01X+112889Y+167473X0140Y0560R270 S1      
317GND              VIA   -    M      A01X+113221Y+167203X0200Y         S2      
017GND              VIA   -    M      A18X+113221Y+167203X0260Y         S2      
017GND                    -    MD0100PA00X+113221Y+167203                       
327GND              R4518 -2          A01X+114411Y+166864X0198Y0197R090 S1      
317GND              VIA   -    MD0100PA00X+114411Y+167112X0200Y         S0      
327GND              R6802 -2          A01X+114012Y+166873X0198Y0197R090 S1      
317GND              VIA   -    MD0100PA00X+114012Y+167142X0200Y         S0      
327GND              C8360 -2          A01X+009592Y+144000X0198Y0197R180 S1      
317GND              VIA   -    MD0100PA00X+009300Y+144000X0200Y         S0      
327GND              R965  -2          A01X+129087Y+155685X0120Y0150R270 S1      
327GND              R1098 -2          A01X+155505Y+155685X0120Y0150R270 S1      
317GND              VIA   -    MD0100PA00X+129267Y+155975X0200Y    R090 S0      
317GND              VIA   -    MD0100PA00X+142074Y+155975X0200Y    R090 S0      
317GND              VIA   -    MD0100PA00X+155685Y+155975X0200Y    R090 S0      
327GND              PC357 -2          A01X+014808Y+143750X0198Y0197     S1      
327GND              PC364 -2          A01X+014350Y+144242X0198Y0197R270 S1      
327GND              PC365 -2          A01X+014503Y+145219X0198Y0197R090 S1      
317GND              VIA   -    MD0100PA00X+015108Y+143665X0200Y         S0      
317GND              VIA   -    MD0100PA00X+014348Y+144000X0200Y         S0      
317GND              VIA   -    MD0100PA00X+014503Y+145470X0200Y    R090 S0      
327GND              R4519 -2          A01X+113610Y+162339X0198Y0197R270 S1      
317GND              VIA   -    MD0100PA00X+113875Y+162463X0200Y         S0      
327GND              R4520 -2          A01X+113217Y+162339X0198Y0197R270 S1      
317GND              VIA   -    M      A01X+113217Y+162086X0200Y         S2      
017GND              VIA   -    M      A18X+113217Y+162086X0260Y         S2      
017GND                    -    MD0100PA00X+113217Y+162086                       
327GND              R903  -2          A01X+054717Y+152385X0120Y0150R270 S1      
327GND              R592  -2          A01X+044158Y+160020X0198Y0197     S1      
317GND              VIA   -    MD0100PA00X+044413Y+160020X0200Y         S0      
327GND              R6803 -2          A01X+044158Y+160420X0198Y0197     S1      
317GND              VIA   -    M      A01X+044413Y+160420X0200Y         S2      
017GND              VIA   -    M      A18X+044413Y+160420X0260Y         S2      
017GND                    -    MD0100PA00X+044413Y+160420                       
327GND              C15   -2          A01X+140821Y+162217X0198Y0197     S1      
317GND              VIA   -    MD0100PA00X+140966Y+161985X0200Y         S0      
327GND              R4154 -2          A01X+139806Y+162217X0198Y0197R180 S1      
317GND              VIA   -    MD0100PA00X+139806Y+161968X0200Y         S0      
317GND              VIA   -    MD0100PA00X+042875Y+152173X0200Y    R090 S0      
317GND              VIA   -    MD0100PA00X+055696Y+152156X0200Y    R090 S0      
317GND              VIA   -    MD0100PA00X+055054Y+152691X0200Y    R090 S0      
327GND              U8010 -2          A01X+056582Y+046250X0240Y0420R090 S1      
317GND              VIA   -    MD0100PA00X+056946Y+046214X0200Y         S0      
327GND              R741  -2          A01X+041106Y+152385X0120Y0150R270 S1      
317GND              VIA   -    MD0100PA00X+041286Y+152675X0200Y    R090 S0      
317GND              VIA   -    MD0100PA00X+016473Y+152156X0200Y    R090 S0      
327GND              R6713 -2          A01X+028300Y+152385X0120Y0150R270 S1      
327GND              C76   -2          A01X+112030Y+167951X0198Y0197R090 S1      
327GND              C77   -2          A01X+110500Y+167958X0198Y0197R090 S1      
327GND              Q74   -4          A18X+042256Y+163926X0170Y0200     S2      
317GND              VIA   -    MD0100PA00X+042135Y+163667X0200Y         S0      
327GND              Q148  -4          A18X+042744Y+163774X0170Y0200R180 S2      
327GND              C1988 -2          A18X+045715Y+163587X0198Y0197R090 S2      
327GND              C1978 -2          A18X+020381Y+168372X0198Y0197R090 S2      
327GND              R3472 -1          A01X+172863Y+170512X0198Y0197R090 S1      
327GND              PC85  -2          A01X+131836Y+140828X0198Y0197R180 S1      
317GND              VIA   -    MD0100PA00X+131836Y+141140X0200Y    R270 S0      
327GND              PR32  -2          A18X+122550Y+141158X0198Y0197R270 S2      
327GND              PR67  -2          A18X+122892Y+141700X0198Y0197     S2      
327GND              PR244 -2          A18X+012692Y+143650X0198Y0197     S2      
327GND              PR12  -2          A18X+012450Y+142508X0198Y0197R270 S2      
327GND              C8072 -2          A01X+119692Y+141450X0198Y0197R180 S1      
327GND              C5005 -1          A18X+118792Y+141450X0198Y0197R180 S2      
327GND              PC73  -2   M      A01X+119692Y+141900X0198Y0197R180 S1      
327GND              C305  -2          A01X+118792Y+140550X0198Y0197R180 S1      
327GND              C304  -2          A01X+118792Y+141000X0198Y0197R180 S1      
327GND              PR40  -2          A01X+118792Y+139650X0198Y0197R180 S1      
327GND              C303  -2          A01X+118792Y+140100X0198Y0197R180 S1      
327GND              R8042 -2          A18X+120008Y+140100X0198Y0197R180 S2      
327GND              PC75  -2          A01X+124900Y+143708X0198Y0197R090 S1      
327GND              PR600 -2          A01X+124900Y+143008X0198Y0197R090 S1      
327GND              PC14  -2   M      A01X+124500Y+143708X0198Y0197R090 S1      
327GND              PC76  -2          A01X+124500Y+144408X0198Y0197R090 S1      
327GND              PC15  -2   M      A01X+124100Y+144408X0198Y0197R090 S1      
327GND              PC74  -2   M      A01X+124500Y+143008X0198Y0197R090 S1      
327GND              C5013 -2          A01X+118792Y+143750X0198Y0197R180 S1      
327GND              C8069 -2          A01X+119692Y+142850X0198Y0197R180 S1      
327GND              C8070 -2          A01X+119692Y+143300X0198Y0197R180 S1      
327GND              C5004 -1          A01X+118102Y+143300X0198Y0197     S1      
327GND              R8219 -2          A18X+009908Y+141250X0198Y0197R180 S2      
327GND              C5006 -1          A18X+008692Y+142600X0198Y0197R180 S2      
327GND              C309  -2          A01X+008692Y+142150X0198Y0197R180 S1      
327GND              C310  -2          A01X+008692Y+141700X0198Y0197R180 S1      
327GND              C308  -2          A01X+008692Y+141250X0198Y0197R180 S1      
327GND              PR217 -2          A01X+008692Y+140800X0198Y0197R180 S1      
327GND              PC367 -2          A01X+014808Y+142950X0198Y0197     S1      
327GND              PC368 -2          A01X+014808Y+143350X0198Y0197     S1      
327GND              C8359 -2          A01X+009592Y+143550X0198Y0197R180 S1      
317GND              VIA   -    MD0100PA00X+118792Y+141700X0200Y         S0      
317GND              VIA   -    MD0100PA00X+119400Y+141800X0200Y         S0      
317GND              VIA   -    MD0100PA00X+118500Y+140550X0200Y         S0      
317GND              VIA   -    MD0100PA00X+118410Y+141000X0200Y         S0      
317GND              VIA   -    MD0100PA00X+118500Y+140100X0200Y         S0      
317GND              VIA   -    MD0100PA00X+118500Y+139650X0200Y         S0      
317GND              VIA   -    MD0100PA00X+122086Y+141256X0200Y    R180 S0      
317GND              VIA   -    MD0100PA00X+122836Y+141256X0200Y    R180 S0      
317GND              VIA   -    MD0100PA00X+121336Y+141256X0200Y    R180 S0      
317GND              VIA   -    MD0100PA00X+120248Y+140247X0200Y         S0      
317GND              VIA   -    MD0100PA00X+124250Y+143708X0200Y         S0      
317GND              VIA   -    MD0100PA00X+123710Y+144250X0200Y         S0      
317GND              VIA   -    MD0100PA00X+124250Y+143008X0200Y         S0      
317GND              VIA   -    MD0100PA00X+122086Y+142756X0200Y    R180 S0      
317GND              VIA   -    MD0100PA00X+122836Y+142006X0200Y    R180 S0      
317GND              VIA   -    MD0100PA00X+122836Y+142756X0200Y    R180 S0      
317GND              VIA   -    MD0100PA00X+121336Y+142006X0200Y    R180 S0      
327GND              PU12  -TH  M      A01X+122100Y+142000X1740Y1740R270 S1      
317GND              VIA   -    MD0100PA00X+121336Y+142756X0200Y    R180 S0      
317GND              VIA   -    MD0100PA00X+118792Y+144040X0200Y         S0      
317GND              VIA   -    MD0100PA00X+119400Y+143300X0200Y         S0      
317GND              VIA   -    MD0100PA00X+119400Y+142850X0200Y         S0      
317GND              VIA   -    MD0100PA00X+117840Y+143300X0200Y         S0      
317GND              VIA   -    MD0100PA00X+011236Y+143356X0200Y    R180 S0      
317GND              VIA   -    MD0100PA00X+011236Y+142606X0200Y    R180 S0      
317GND              VIA   -    MD0100PA00X+009753Y+141025X0200Y         S0      
317GND              VIA   -    MD0100PA00X+008400Y+142600X0200Y         S0      
317GND              VIA   -    MD0100PA00X+008400Y+142150X0200Y         S0      
317GND              VIA   -    MD0100PA00X+008400Y+141700X0200Y         S0      
317GND              VIA   -    MD0100PA00X+008400Y+141250X0200Y         S0      
317GND              VIA   -    MD0100PA00X+008400Y+140800X0200Y         S0      
317GND              VIA   -    MD0100PA00X+009300Y+143050X0200Y         S0      
317GND              VIA   -    MD0100PA00X+015090Y+142950X0200Y         S0      
317GND              VIA   -    MD0100PA00X+012736Y+142606X0200Y    R180 S0      
317GND              VIA   -    MD0100PA00X+012736Y+143356X0200Y    R180 S0      
317GND              VIA   -    MD0100PA00X+011986Y+142606X0200Y    R180 S0      
317GND              VIA   -    MD0100PA00X+015090Y+143350X0200Y         S0      
317GND              VIA   -    MD0100PA00X+012736Y+144106X0200Y    R180 S0      
317GND              VIA   -    MD0100PA00X+011986Y+144106X0200Y    R180 S0      
317GND              VIA   -    MD0100PA00X+011236Y+144106X0200Y    R180 S0      
327GND              PU34  -TH  M      A01X+012000Y+143350X1740Y1740R270 S1      
317GND              VIA   -    MD0100PA00X+009300Y+143550X0200Y         S0      
327GND              C8005 -2          A01X+082399Y+042310X0198Y0197     S1      
327GND              C8007 -2          A18X+074228Y+056924X0198Y0197R180 S2      
327GND              C8006 -2          A01X+102142Y+040200X0198Y0197R180 S1      
327GND              C8001 -2          A18X+004000Y+032108X0198Y0197R270 S2      
327GND              C8002 -2          A18X+003650Y+032108X0198Y0197R270 S2      
327GND              C8003 -2          A01X+006758Y+029000X0198Y0197     S1      
327GND              C29   -2          A01X+082450Y+051158X0198Y0197R090 S1      
327GND              C6500 -2          A01X+046850Y+048992X0198Y0197R270 S1      
327GND              C8000 -2          A18X+038264Y+167398X0198Y0197     S2      
327GND              C8008 -2          A01X+163542Y+038150X0198Y0197R180 S1      
327GND              C8009 -2          A01X+031042Y+024100X0198Y0197R180 S1      
327GND              C8013 -2          A18X+079150Y+054142X0198Y0197R090 S2      
327GND              C8012 -2          A18X+078500Y+056642X0198Y0197R090 S2      
327GND              C8014 -2          A18X+073492Y+166300X0198Y0197     S2      
327GND              C8016 -2          A18X+073815Y+168884X0198Y0197     S2      
327GND              C8017 -2          A01X+050150Y+042958X0198Y0197R090 S1      
327GND              C8018 -2          A01X+051850Y+042942X0198Y0197R270 S1      
327GND              C8019 -2          A01X+053958Y+044550X0198Y0197     S1      
327GND              C8020 -2          A01X+056358Y+045100X0198Y0197     S1      
327GND              C8022 -2          A01X+054592Y+045900X0198Y0197R180 S1      
327GND              C68   -2          A01X+044508Y+161870X0198Y0197     S1      
327GND              C84   -2          A01X+041942Y+163400X0198Y0197R180 S1      
327GND              C58   -2          A18X+042690Y+160837X0198Y0197     S2      
327GND              C90   -2          A01X+039403Y+160702X0198Y0197R180 S1      
327GND              C98   -2          A18X+041308Y+161540X0198Y0197R180 S2      
327GND              C99   -2          A18X+041305Y+161016X0198Y0197R180 S2      
327GND              C75   -2          A18X+042424Y+161517X0198Y0197     S2      
327GND              C286  -2          A18X+024327Y+153606X0198Y0197R090 S2      
327GND              C241  -2          A18X+023855Y+153606X0198Y0197R090 S2      
327GND              C261  -2          A18X+021493Y+153606X0198Y0197R090 S2      
327GND              C256  -2          A18X+021020Y+153606X0198Y0197R090 S2      
327GND              C227  -2          A18X+019603Y+153606X0198Y0197R090 S2      
327GND              C250  -2          A18X+018658Y+153606X0198Y0197R090 S2      
327GND              C122  -2          A18X+028367Y+152420X0198Y0197R270 S2      
327GND              C118  -2          A18X+028767Y+152420X0198Y0197R270 S2      
327GND              C119  -2          A18X+022438Y+153606X0198Y0197R090 S2      
327GND              C121  -2          A18X+021965Y+153606X0198Y0197R090 S2      
327GND              PC6578-2          A01X+179183Y+158710X0198Y0197R180 S1      
327GND              PC6576-2          A01X+177290Y+158240X0198Y0197R180 S1      
327GND              PC6555-2          A01X+176905Y+158240X0198Y0197     S1      
327GND              PC6562-2          A01X+176485Y+163569X0198Y0197R180 S1      
327GND              PC6553-2          A01X+173928Y+158755X0198Y0197R090 S1      
327GND              C101  -2          A01X+172689Y+168146X0198Y0197R180 S1      
327GND              PC6605-2          A01X+176346Y+168904X0198Y0197R090 S1      
327GND              PC6606-2          A01X+175896Y+168904X0198Y0197R090 S1      
327GND              C83   -2          A01X+041942Y+163900X0198Y0197R180 S1      
327GND              C82   -2          A01X+044508Y+162270X0198Y0197     S1      
327GND              C28   -2          A01X+039403Y+161102X0198Y0197R180 S1      
327GND              C195  -2          A18X+034771Y+153606X0198Y0197R090 S2      
327GND              C199  -2          A18X+035244Y+153606X0198Y0197R090 S2      
327GND              C127  -2          A18X+041173Y+152420X0198Y0197R270 S2      
327GND              C200  -2          A18X+041573Y+152420X0198Y0197R270 S2      
327GND              C321  -2          A18X+032882Y+153606X0198Y0197R090 S2      
327GND              C325  -2          A18X+032409Y+153606X0198Y0197R090 S2      
327GND              C332  -2          A18X+031464Y+153606X0198Y0197R090 S2      
327GND              C338  -2          A18X+033826Y+153606X0198Y0197R090 S2      
327GND              C354  -2          A18X+038551Y+153606X0198Y0197R090 S2      
327GND              C333  -2          A18X+034299Y+153606X0198Y0197R090 S2      
327GND              PC6500-2   M      A01X+097715Y+105548X0198Y0197R180 S1      
327GND              PC6519-2   M      A01X+088906Y+105603X0198Y0197     S1      
327GND              PC6505-2   M      A01X+095350Y+116117X0198Y0197R180 S1      
327GND              PC6518-2   M      A01X+094148Y+114907X0198Y0197R180 S1      
327GND              C6758 -2          A18X+093666Y+114106X0198Y0197     S2      
327GND              C6757 -2          A01X+094107Y+113784X0198Y0197R180 S1      
327GND              PC6524-2   M      A01X+090647Y+116117X0198Y0197R180 S1      
327GND              PC6537-2   M      A01X+089446Y+114907X0198Y0197R180 S1      
327GND              C109  -2          A18X+088963Y+114106X0198Y0197     S2      
327GND              C105  -2          A01X+089405Y+113784X0198Y0197R180 S1      
327GND              PC6633-2          A01X+010455Y+155407X0198Y0197R180 S1      
327GND              PC6646-2          A01X+008562Y+154937X0198Y0197R180 S1      
327GND              PC6613-2          A01X+008177Y+154937X0198Y0197     S1      
327GND              PC6611-2          A01X+005200Y+155452X0198Y0197R090 S1      
327GND              C107  -2          A01X+007681Y+159633X0198Y0197R270 S1      
327GND              PC6546-2          A01X+005013Y+159532X0198Y0197R270 S1      
327GND              PC6545-2          A01X+004563Y+159532X0198Y0197R270 S1      
327GND              PC523 -2          A01X+003806Y+161740X0198Y0197R180 S1      
327GND              PC514 -2          A01X+003806Y+161290X0198Y0197R180 S1      
327GND              PC6543-2          A01X+003806Y+160340X0198Y0197R180 S1      
327GND              PC819 -2          A01X+003806Y+160790X0198Y0197R180 S1      
327GND              C9000 -2          A01X+143292Y+162350X0198Y0197R180 S1      
327GND              C9002 -2          A01X+143273Y+161390X0198Y0197R180 S1      
327GND              C371  -2          A18X+061189Y+153606X0198Y0197R090 S2      
327GND              C372  -2          A18X+061661Y+153606X0198Y0197R090 S2      
327GND              C406  -2          A18X+058826Y+153606X0198Y0197R090 S2      
327GND              C410  -2          A18X+057881Y+153606X0198Y0197R090 S2      
327GND              C429  -2          A18X+059299Y+153606X0198Y0197R090 S2      
327GND              C431  -2          A18X+064968Y+153606X0198Y0197R090 S2      
327GND              C414  -2          A18X+060716Y+153606X0198Y0197R090 S2      
327GND              C419  -2          A18X+060244Y+153606X0198Y0197R090 S2      
327GND              C437  -2          A18X+048855Y+153606X0198Y0197R090 S2      
327GND              C438  -2          A18X+048382Y+153606X0198Y0197R090 S2      
327GND              C436  -2          A18X+055184Y+152420X0198Y0197R270 S2      
327GND              C439  -2          A18X+054784Y+152420X0198Y0197R270 S2      
327GND              C472  -2          A18X+046020Y+153606X0198Y0197R090 S2      
327GND              C480  -2          A18X+045075Y+153606X0198Y0197R090 S2      
327GND              C484  -2          A18X+047438Y+153606X0198Y0197R090 S2      
327GND              C489  -2          A18X+047910Y+153606X0198Y0197R090 S2      
327GND              C499  -2          A18X+050745Y+153606X0198Y0197R090 S2      
327GND              C483  -2          A18X+050272Y+153606X0198Y0197R090 S2      
327GND              C507  -2          A18X+123225Y+156906X0198Y0197R090 S2      
327GND              C510  -2          A18X+122752Y+156906X0198Y0197R090 S2      
327GND              C506  -2          A18X+129554Y+155720X0198Y0197R270 S2      
327GND              C511  -2          A18X+129154Y+155720X0198Y0197R270 S2      
327GND              C557  -2          A18X+120390Y+156906X0198Y0197R090 S2      
327GND              C561  -2          A18X+119445Y+156906X0198Y0197R090 S2      
327GND              C572  -2          A18X+124642Y+156906X0198Y0197R090 S2      
327GND              C569  -2          A18X+121808Y+156906X0198Y0197R090 S2      
327GND              C574  -2          A18X+122280Y+156906X0198Y0197R090 S2      
327GND              C584  -2          A18X+125115Y+156906X0198Y0197R090 S2      
327GND              C594  -2          A18X+135559Y+156906X0198Y0197R090 S2      
327GND              C595  -2          A18X+136031Y+156906X0198Y0197R090 S2      
327GND              C591  -2          A18X+141961Y+155720X0198Y0197R270 S2      
327GND              C596  -2          A18X+142361Y+155720X0198Y0197R270 S2      
327GND              C626  -2          A18X+133669Y+156906X0198Y0197R090 S2      
327GND              C638  -2          A18X+133196Y+156906X0198Y0197R090 S2      
327GND              C646  -2          A18X+135086Y+156906X0198Y0197R090 S2      
327GND              C651  -2          A18X+134614Y+156906X0198Y0197R090 S2      
327GND              C661  -2          A18X+139338Y+156906X0198Y0197R090 S2      
327GND              C645  -2          A18X+132251Y+156906X0198Y0197R090 S2      
327GND              C670  -2          A18X+161976Y+156906X0198Y0197R090 S2      
327GND              C671  -2          A18X+162448Y+156906X0198Y0197R090 S2      
327GND              C796  -2          A18X+160086Y+156906X0198Y0197R090 S2      
327GND              C803  -2          A18X+158669Y+156906X0198Y0197R090 S2      
327GND              C967  -2          A18X+159614Y+156906X0198Y0197R090 S2      
327GND              C986  -2          A18X+165756Y+156906X0198Y0197R090 S2      
327GND              C971  -2          A18X+161504Y+156906X0198Y0197R090 S2      
327GND              C976  -2          A18X+161031Y+156906X0198Y0197R090 S2      
327GND              C995  -2          A18X+149642Y+156906X0198Y0197R090 S2      
327GND              C996  -2          A18X+149170Y+156906X0198Y0197R090 S2      
327GND              C994  -2          A18X+155972Y+155720X0198Y0197R270 S2      
327GND              C997  -2          A18X+155572Y+155720X0198Y0197R270 S2      
327GND              C1023 -2          A18X+151532Y+156906X0198Y0197R090 S2      
327GND              C1034 -2          A18X+151060Y+156906X0198Y0197R090 S2      
327GND              C1037 -2          A18X+145863Y+156906X0198Y0197R090 S2      
327GND              C1038 -2          A18X+148225Y+156906X0198Y0197R090 S2      
327GND              C1044 -2          A18X+148697Y+156906X0198Y0197R090 S2      
327GND              C1056 -2          A18X+146808Y+156906X0198Y0197R090 S2      
327GND              R6502 -2          A18X+124922Y+078740X0198Y0197     S2      
327GND              R6503 -2          A18X+026300Y+077541X0198Y0197     S2      
327GND              R8033 -2          A18X+074208Y+056400X0198Y0197R180 S2      
327GND              R4490 -2          A01X+109892Y+164250X0198Y0197R180 S1      
327GND              R4492 -2          A01X+111600Y+166858X0198Y0197R090 S1      
327GND              R6501 -2          A01X+043950Y+048642X0198Y0197R270 S1      
327GND              R480  -2          A01X+066858Y+052950X0198Y0197     S1      
327GND              R8099 -2          A01X+087742Y+032600X0198Y0197R180 S1      
327GND              R8001 -2   M      A18X+038264Y+167005X0198Y0197     S2      
327GND              R8093 -2          A01X+162900Y+039608X0198Y0197R090 S1      
327GND              R8096 -2          A01X+030892Y+026300X0198Y0197R180 S1      
327GND              R8115 -2   M      A01X+052250Y+042942X0198Y0197R270 S1      
327GND              R585  -2          A18X+043592Y+162600X0198Y0197     S2      
327GND              R593  -2          A01X+039403Y+159902X0198Y0197R180 S1      
327GND              R594  -2          A01X+039403Y+160302X0198Y0197R180 S1      
327GND              R579  -2          A01X+040892Y+164100X0198Y0197R180 S1      
327GND              PR6561-2          A01X+178587Y+158583X0198Y0197     S1      
327GND              PR6553-2          A01X+175205Y+158590X0198Y0197     S1      
327GND              PR6614-2          A01X+176296Y+164789X0198Y0197R270 S1      
327GND              PR6611-2          A01X+175296Y+164479X0198Y0197R270 S1      
327GND              PR6609-2          A01X+174796Y+164479X0198Y0197R270 S1      
327GND              PR6610-2   M      A18X+175046Y+164639X0198Y0197R090 S2      
327GND              PR6613-2   M      A01X+175796Y+164789X0198Y0197R270 S1      
327GND              PR6612-2   M      A18X+175546Y+164639X0198Y0197R090 S2      
327GND              R6801 -1          A18X+172685Y+165446X0198Y0197R180 S2      
327GND              PR6814-2          A18X+177104Y+166146X0198Y0197R180 S2      
327GND              PR883 -2          A18X+172689Y+165896X0198Y0197     S2      
327GND              PR6810-2          A18X+172689Y+166796X0198Y0197     S2      
327GND              PR6819-2          A18X+172689Y+166346X0198Y0197     S2      
327GND              PR6502-2   M      A01X+094148Y+115350X0198Y0197R180 S1      
327GND              PR6500-1          A18X+094775Y+114395X0198Y0197     S2      
327GND              PR6507-2   M      A01X+094446Y+114465X0198Y0197R090 S1      
327GND              PR6522-2   M      A01X+089446Y+115350X0198Y0197R180 S1      
327GND              PR6520-1          A18X+090072Y+114395X0198Y0197     S2      
327GND              PR6526-2   M      A01X+089744Y+114465X0198Y0197R090 S1      
327GND              PR6628-2          A01X+009859Y+155280X0198Y0197     S1      
327GND              PR6622-2          A01X+006477Y+155287X0198Y0197     S1      
327GND              R6800 -1          A18X+008224Y+162990X0198Y0197     S2      
327GND              PR6811-2          A18X+008221Y+161640X0198Y0197R180 S2      
327GND              PR6820-2          A18X+008221Y+162090X0198Y0197R180 S2      
327GND              PR6802-2          A18X+008221Y+162540X0198Y0197R180 S2      
327GND              PR6540-2   M      A18X+005863Y+163797X0198Y0197R270 S2      
327GND              PR6539-2          A01X+006113Y+163957X0198Y0197R090 S1      
327GND              PR6542-2   M      A18X+005363Y+163797X0198Y0197R270 S2      
327GND              PR6541-2          A01X+005613Y+163957X0198Y0197R090 S1      
327GND              PR6543-2   M      A01X+005113Y+163647X0198Y0197R090 S1      
327GND              PR6544-2          A01X+004613Y+163647X0198Y0197R090 S1      
327GND              PR6821-2          A18X+005371Y+161270X0198Y0197R180 S2      
327GND              PR6533-1          A01X+003806Y+162290X0198Y0197     S1      
327GND              PR6815-2          A18X+003806Y+162320X0198Y0197     S2      
327GND              PR6813-2          A18X+003806Y+160340X0198Y0197     S2      
327GND              PR6548-2          A18X+003873Y+161052X0198Y0197R090 S2      
327GND              R9003 -2          A01X+142372Y+162337X0198Y0197R180 S1      
327GND              R9015 -2          A01X+142372Y+160990X0198Y0197R180 S1      
327GND              R6744 -2          A01X+069952Y+036333X0198Y0197R270 S1      
327GND              R6745 -2          A01X+069337Y+036333X0198Y0197R270 S1      
327GND              R6786 -2          A01X+172689Y+167696X0198Y0197R180 S1      
317GND              VIA   -    MD0100PA00X+093851Y+113784X0200Y         S0      
327GND              C365  -2          A18X+097745Y+130750X0120Y0150     S2      
317GND              VIA   -    MD0100PA00X+097500Y+130750X0200Y         S0      
327GND              U22   -12         A18X+096246Y+134024X0120Y0630R270 S2      
317GND              VIA   -    MD0100PA00X+096750Y+134024X0200Y         S0      
327GND              U6020 -12         A18X+087209Y+134024X0120Y0630R270 S2      
317GND              VIA   -    MD0100PA00X+087700Y+134024X0200Y         S0      
327GND              Q9000 -4          A01X+143163Y+164047X0170Y0200R180 S1      
317GND              VIA   -    MD0100PA00X+143333Y+164329X0200Y         S0      
327GND              Q9002 -4          A01X+142557Y+160166X0170Y0200R270 S1      
317GND              VIA   -    MD0100PA00X+142291Y+160166X0200Y         S0      
327GND              Q9002 -1          A01X+143305Y+159654X0170Y0200R270 S1      
317GND              VIA   -    M      A01X+143558Y+159654X0200Y         S2      
017GND              VIA   -    M      A18X+143558Y+159654X0260Y         S2      
017GND                    -    MD0100PA00X+143558Y+159654                       
327GND              Q137  -1          A18X+169789Y+171848X0170Y0200R090 S2      
317GND              VIA   -    MD0100PA00X+169517Y+171761X0200Y         S0      
327GND              Q137  -4          A18X+170537Y+172359X0170Y0200R090 S2      
317GND              VIA   -    MD0100PA00X+170278Y+172359X0200Y         S0      
317GND              VIA   -    MD0100PA00X+043940Y+161515X0200Y         S0      
317GND              VIA   -    MD0100PA00X+043928Y+160870X0200Y         S0      
317GND              VIA   -    MD0100PA00X+040385Y+161535X0200Y         S0      
317GND              VIA   -    MD0100PA00X+040342Y+160622X0200Y         S0      
327GND              C7    -2          A18X+168938Y+172674X0198Y0197R270 S2      
317GND              VIA   -    MD0100PA00X+168938Y+172919X0200Y         S0      
327GND              R4163 -2          A18X+168538Y+171659X0198Y0197R090 S2      
327GND              R846  -2          A18X+094045Y+130500X0120Y0150R180 S2      
327GND              R847  -2          A18X+094045Y+130150X0120Y0150R180 S2      
317GND              VIA   -    MD0100PA00X+093800Y+130450X0200Y         S0      
317GND              VIA   -    MD0100PA00X+093800Y+130150X0200Y         S0      
327GND              R849  -2          A18X+094045Y+130950X0120Y0150R180 S2      
317GND              VIA   -    MD0100PA00X+093800Y+130950X0200Y         S0      
317GND              VIA   -    MD0100PA00X+165346Y+166842X0200Y         S0      
327GND              C7500 -2          A18X+088745Y+130750X0120Y0150     S2      
317GND              VIA   -    MD0100PA00X+088500Y+130750X0200Y         S0      
327GND              R6773 -2          A18X+092155Y+131000X0120Y0150     S2      
317GND              VIA   -    MD0100PA00X+092400Y+131000X0200Y         S0      
327GND              U16   -4          A01X+165110Y+169640X0350Y0500R180 S1      
317GND              VIA   -    MD0100PA00X+165110Y+170048X0200Y         S0      
327GND              R1085 -2          A01X+165819Y+170424X0120Y0150R180 S1      
317GND              VIA   -    MD0100PA00X+166054Y+170424X0200Y         S0      
317GND              VIA   -    M      A01X+143032Y+162350X0200Y         S2      
017GND              VIA   -    M      A18X+143032Y+162350X0260Y         S2      
017GND                    -    MD0100PA00X+143032Y+162350                       
317GND              VIA   -    M      A01X+142139Y+162171X0200Y         S2      
017GND              VIA   -    M      A18X+142139Y+162171X0260Y         S2      
017GND                    -    MD0100PA00X+142139Y+162171                       
317GND              VIA   -    MD0100PA00X+142123Y+160613X0200Y         S0      
317GND              VIA   -    MD0100PA00X+143008Y+161390X0200Y         S0      
327GND              Q9000 -1          A01X+142651Y+163299X0170Y0200R180 S1      
317GND              VIA   -    MD0100PA00X+142539Y+163550X0200Y         S0      
327GND              Q71   -4          A18X+139494Y+164168X0170Y0200R270 S2      
317GND              VIA   -    MD0100PA00X+139737Y+163995X0200Y         S0      
327GND              Q71   -1          A18X+140242Y+164680X0170Y0200R270 S2      
317GND              VIA   -    MD0100PA00X+140242Y+164953X0200Y         S0      
317GND              VIA   -    MD0100PA00X+041616Y+159445X0200Y         S0      
317GND              VIA   -    MD0100PA00X+041152Y+159965X0200Y         S0      
317GND              VIA   -    MD0100PA00X+042669Y+159800X0200Y         S0      
317GND              VIA   -    MD0100PA00X+172432Y+167696X0200Y         S0      
317GND              VIA   -    MD0100PA00X+168530Y+145123X0200Y    R270 S0      
317GND              VIA   -    MD0100PA00X+170482Y+169424X0200Y    R270 S0      
327GND              R6775 -2          A18X+084495Y+130200X0120Y0150R180 S2      
327GND              R6774 -2          A18X+084495Y+130600X0120Y0150R180 S2      
327GND              R6778 -2          A18X+084495Y+131000X0120Y0150R180 S2      
317GND              VIA   -    MD0100PA00X+084250Y+130200X0200Y         S0      
317GND              VIA   -    MD0100PA00X+084250Y+130600X0200Y         S0      
317GND              VIA   -    MD0100PA00X+084250Y+131000X0200Y         S0      
327GND              PR412 -2          A18X+165400Y+141628X0198Y0197     S2      
327GND              PR3   -2          A18X+165782Y+142694X0198Y0197     S2      
327GND              PR601 -2          A01X+168100Y+143342X0198Y0197R270 S1      
317GND              VIA   -    MD0100PA00X+168359Y+143342X0200Y    R090 S0      
327GND              PC8005-2          A18X+167326Y+141169X0400Y0500R180 S2      
317GND              VIA   -    MD0100PA00X+038780Y+161080X0200Y         S0      
317GND              VIA   -    M      A01X+038780Y+160480X0200Y         S2      
017GND              VIA   -    M      A18X+038780Y+160480X0260Y         S2      
017GND                    -    MD0100PA00X+038780Y+160480                       
317GND              VIA   -    MD0100PA00X+038780Y+160780X0200Y         S0      
317GND              VIA   -    MD0100PA00X+069610Y+036415X0200Y         S0      
317GND              JP6500-3   MD0410PA00X+107286Y+140918X0610Y         S3      
327GND              R6168 -2          A01X+005205Y+168149X0198Y0197R180 S1      
317GND              VIA   -    M      A01X+005205Y+168403X0200Y    R180 S2      
017GND              VIA   -    M      A18X+005205Y+168403X0260Y    R180 S2      
017GND                    -    MD0100PA00X+005205Y+168403                       
317GND              VIA   -    MD0100PA00X+012976Y+158858X0200Y    R180 S0      
317GND              VIA   -    MD0100PA00X+008513Y+162540X0200Y    R270 S0      
317GND              VIA   -    MD0100PA00X+008517Y+162990X0200Y    R270 S0      
317GND              VIA   -    MD0100PA00X+008513Y+162090X0200Y    R270 S0      
317GND              VIA   -    MD0100PA00X+008513Y+161640X0200Y    R270 S0      
317GND              VIA   -    MD0100PA00X+007681Y+159326X0200Y         S0      
317GND              VIA   -    MD0100PA00X+005445Y+164172X0200Y    R180 S0      
317GND              VIA   -    MD0100PA00X+005133Y+164100X0200Y    R270 S0      
317GND              VIA   -    MD0100PA00X+005863Y+164139X0200Y    R270 S0      
327GND              PU6510-TH  M      A01X+005977Y+161540X1440Y1440R090 S1      
317GND              VIA   -    MD0100PA00X+005377Y+160940X0200Y    R090 S0      
317GND              VIA   -    MD0100PA00X+005377Y+162140X0200Y    R090 S0      
317GND              VIA   -    MD0100PA00X+005377Y+161540X0200Y    R090 S0      
317GND              VIA   -    MD0100PA00X+005977Y+160940X0200Y    R090 S0      
317GND              VIA   -    MD0100PA00X+006577Y+160940X0200Y    R090 S0      
317GND              VIA   -    MD0100PA00X+005977Y+162140X0200Y    R090 S0      
317GND              VIA   -    MD0100PA00X+006594Y+162140X0200Y    R090 S0      
317GND              VIA   -    MD0100PA00X+006577Y+161540X0200Y    R090 S0      
317GND              VIA   -    MD0100PA00X+005013Y+159248X0200Y    R090 S0      
317GND              VIA   -    MD0100PA00X+004760Y+162241X0200Y    R270 S0      
327GND              PU6510-31         A01X+005032Y+162249X0070Y0240R090 S1      
327GND              PU6510-32         A01X+005032Y+162092X0070Y0240R090 S1      
317GND              VIA   -    MD0100PA00X+003517Y+161052X0200Y    R270 S0      
317GND              VIA   -    MD0100PA00X+003513Y+160340X0200Y    R270 S0      
317GND              VIA   -    MD0100PA00X+003523Y+162320X0200Y    R270 S0      
317GND              VIA   -    MD0100PA00X+004563Y+159248X0200Y    R090 S0      
317GND              VIA   -    M      A01X+015943Y+168784X0200Y    R090 S2      
017GND              VIA   -    M      A18X+015943Y+168784X0260Y    R090 S2      
017GND                    -    MD0100PA00X+015943Y+168784                       
327GND              R3265 -2          A01X+015943Y+169051X0198Y0197R270 S1      
327GND              R3291 -2          A01X+015293Y+167009X0198Y0197     S1      
317GND              VIA   -    MD0100PA00X+015533Y+167009X0200Y    R180 S0      
317GND              VIA   -    M      A01X+013935Y+169606X0200Y    R180 S2      
017GND              VIA   -    M      A18X+013935Y+169606X0260Y    R180 S2      
017GND                    -    MD0100PA00X+013935Y+169606                       
327GND              R3287 -2          A01X+013935Y+169366X0198Y0197R090 S1      
327GND              C1864 -2          A01X+014693Y+168259X0198Y0197     S1      
317GND              VIA   -    MD0100PA00X+014693Y+168509X0200Y    R180 S0      
317GND              VIA   -    MD0100PA00X+014335Y+169606X0200Y    R180 S0      
327GND              R3285 -2          A01X+014335Y+169366X0198Y0197R090 S1      
317GND              VIA   -    MD0100PA00X+014035Y+164661X0200Y    R180 S0      
327GND              R3290 -2          A01X+014035Y+164901X0198Y0197R270 S1      
327GND              R3288 -2          A01X+014425Y+164901X0198Y0197R270 S1      
317GND              VIA   -    MD0100PA00X+014435Y+164661X0200Y    R180 S0      
327GND              R3293 -2          A01X+014835Y+164901X0198Y0197R270 S1      
317GND              VIA   -    MD0100PA00X+014835Y+164661X0200Y    R180 S0      
317GND              VIA   -    MD0100PA00X+013535Y+169606X0200Y    R180 S0      
327GND              R3267 -2          A01X+013535Y+169366X0198Y0197R090 S1      
317GND              VIA   -    M      A01X+013135Y+169606X0200Y    R180 S2      
017GND              VIA   -    M      A18X+013135Y+169606X0260Y    R180 S2      
017GND                    -    MD0100PA00X+013135Y+169606                       
327GND              R3270 -2          A01X+013135Y+169366X0198Y0197R090 S1      
317GND              VIA   -    MD0100PA00X+012328Y+165859X0200Y    R180 S0      
327GND              C1863 -2          A01X+012328Y+166109X0198Y0197R180 S1      
327GND              C1866 -2          A18X+013325Y+168051X0198Y0197R180 S2      
327GND              C1867 -2          A18X+013468Y+167233X0400Y0500R180 S2      
327GND              U237  -TH  M      A01X+013485Y+167209X0480Y1260R180 S1      
317GND              VIA   -    MD0100PA00X+013605Y+166685X0200Y    R180 S0      
317GND              VIA   -    MD0100PA00X+013355Y+167735X0200Y    R180 S0      
327GND              U237  -7          A01X+013977Y+167445X0070Y0240R090 S1      
327GND              U237  -6          A01X+013977Y+167287X0070Y0240R090 S1      
327GND              U237  -4          A01X+013977Y+166972X0070Y0240R090 S1      
327GND              U237  -28         A01X+013485Y+166323X0070Y0240     S1      
327GND              U237  -22         A01X+012993Y+166972X0070Y0240R270 S1      
327GND              U237  -19         A01X+012993Y+167445X0070Y0240R270 S1      
327GND              U237  -13         A01X+013485Y+168094X0070Y0240R180 S1      
317GND              VIA   -    MD0100PA00X+012435Y+164661X0200Y    R180 S0      
327GND              R3276 -2          A01X+012435Y+164901X0198Y0197R270 S1      
317GND              VIA   -    MD0100PA00X+012835Y+164661X0200Y    R180 S0      
327GND              R3273 -2          A01X+012835Y+164901X0198Y0197R270 S1      
317GND              VIA   -    M      A01X+011535Y+169594X0200Y    R180 S2      
017GND              VIA   -    M      A18X+011535Y+169594X0260Y    R180 S2      
017GND                    -    MD0100PA00X+011535Y+169594                       
327GND              R3279 -2          A01X+011535Y+169354X0198Y0197R090 S1      
317GND              VIA   -    MD0100PA00X+011935Y+169594X0200Y    R180 S0      
327GND              R3281 -2          A01X+011935Y+169354X0198Y0197R090 S1      
317GND              VIA   -    MD0100PA00X+012035Y+164661X0200Y    R180 S0      
327GND              R3272 -2          A01X+012035Y+164901X0198Y0197R270 S1      
317GND              VIA   -    MD0100PA00X+011635Y+164661X0200Y    R180 S0      
327GND              R3268 -2          A01X+011635Y+164901X0198Y0197R270 S1      
317GND              VIA   -    M      A01X+010092Y+167956X0200Y    R090 S2      
017GND              VIA   -    M      A18X+010092Y+167956X0260Y    R090 S2      
017GND                    -    MD0100PA00X+010092Y+167956                       
327GND              R3284 -2          A01X+010391Y+167556X0198Y0197R180 S1      
327GND              R3282 -2   M      A01X+010391Y+167956X0198Y0197R180 S1      
317GND              VIA   -    M      A01X+010044Y+166736X0200Y    R090 S2      
017GND              VIA   -    M      A18X+010044Y+166736X0260Y    R090 S2      
017GND                    -    MD0100PA00X+010044Y+166736                       
327GND              R3278 -2   M      A01X+010391Y+166736X0198Y0197R180 S1      
327GND              R3274 -2          A01X+010391Y+167136X0198Y0197R180 S1      
317GND              VIA   -    MD0100PA00X+008613Y+168736X0200Y    R180 S0      
327GND              R6166 -2          A01X+008613Y+168496X0198Y0197R090 S1      
317GND              VIA   -    MD0100PA00X+008947Y+166713X0200Y    R090 S0      
327GND              C6011 -2          A01X+008702Y+166713X0198Y0197     S1      
317GND              VIA   -    MD0100PA00X+008947Y+166314X0200Y    R090 S0      
327GND              C6012 -2          A01X+008706Y+166314X0198Y0197     S1      
317GND              VIA   -    M      A01X+007813Y+168736X0200Y    R180 S2      
017GND              VIA   -    M      A18X+007813Y+168736X0260Y    R180 S2      
017GND                    -    MD0100PA00X+007813Y+168736                       
327GND              R6164 -2          A01X+007813Y+168496X0198Y0197R090 S1      
317GND              VIA   -    MD0100PA00X+007413Y+168736X0200Y    R180 S0      
327GND              R6160 -2          A01X+007413Y+168496X0198Y0197R090 S1      
317GND              VIA   -    MD0100PA00X+007343Y+164441X0200Y    R090 S0      
327GND              R6176 -2          A01X+007343Y+164681X0198Y0197R270 S1      
317GND              VIA   -    MD0100PA00X+006843Y+164441X0200Y    R090 S0      
327GND              R6180 -2          A01X+006843Y+164681X0198Y0197R270 S1      
317GND              VIA   -    M      A01X+007013Y+168736X0200Y    R180 S2      
017GND              VIA   -    M      A18X+007013Y+168736X0260Y    R180 S2      
017GND                    -    MD0100PA00X+007013Y+168736                       
327GND              R6170 -2          A01X+007013Y+168496X0198Y0197R090 S1      
327GND              C1865 -2          A18X+006444Y+166139X0198Y0197R270 S2      
327GND              U6000 -16         A01X+006643Y+165840X0098Y0236R180 S1      
317GND              VIA   -    MD0100PA00X+006959Y+166988X0200Y    R180 S0      
317GND              VIA   -    MD0100PA00X+006949Y+166183X0200Y    R180 S0      
317GND              VIA   -    MD0100PA00X+006137Y+166993X0200Y    R180 S0      
317GND              VIA   -    MD0100PA00X+006142Y+166170X0200Y    R180 S0      
327GND              U6000 -25  M      A01X+006545Y+166588X1024Y1024R270 S1      
317GND              VIA   -    MD0100PA00X+005365Y+165309X0200Y    R090 S0      
327GND              C6009 -2          A18X+005785Y+165439X0198Y0197     S2      
317GND              VIA   -    MD0100PA00X+005136Y+165022X0200Y    R180 S0      
327GND              C6010 -2          A18X+005493Y+164889X0400Y0500R180 S2      
317GND              VIA   -    MD0100PA00X+005136Y+164772X0200Y    R180 S0      
317GND              VIA   -    MD0100PA00X+005943Y+164441X0200Y    R090 S0      
327GND              R6178 -2          A01X+005943Y+164681X0198Y0197R270 S1      
327GND              R6174 -2          A01X+004435Y+166359X0198Y0197R180 S1      
317GND              VIA   -    M      A01X+004143Y+166859X0200Y    R090 S2      
017GND              VIA   -    M      A18X+004143Y+166859X0260Y    R090 S2      
017GND                    -    MD0100PA00X+004143Y+166859                       
327GND              R6172 -2   M      A01X+004435Y+166859X0198Y0197R180 S1      
317GND              VIA   -    MD0100PA00X+177396Y+168096X0200Y    R090 S0      
317GND              VIA   -    MD0100PA00X+177374Y+167296X0200Y    R090 S0      
317GND              VIA   -    MD0100PA00X+177386Y+166146X0200Y    R090 S0      
317GND              VIA   -    MD0100PA00X+175896Y+169156X0200Y    R270 S0      
317GND              VIA   -    MD0100PA00X+176346Y+169146X0200Y    R270 S0      
317GND              VIA   -    MD0100PA00X+176149Y+166195X0200Y    R090 S0      
327GND              PU6502-32         A01X+175878Y+166344X0070Y0240R270 S1      
327GND              PU6502-31         A01X+175878Y+166187X0070Y0240R270 S1      
317GND              VIA   -    MD0100PA00X+175476Y+164166X0200Y         S0      
327GND              PU6502-TH  M      A01X+174933Y+166896X1440Y1440R270 S1      
317GND              VIA   -    MD0100PA00X+174333Y+167496X0200Y    R270 S0      
317GND              VIA   -    MD0100PA00X+175533Y+167496X0200Y    R270 S0      
317GND              VIA   -    MD0100PA00X+174933Y+167496X0200Y    R270 S0      
317GND              VIA   -    MD0100PA00X+174315Y+166296X0200Y    R270 S0      
317GND              VIA   -    MD0100PA00X+174333Y+166896X0200Y    R270 S0      
317GND              VIA   -    MD0100PA00X+175533Y+166296X0200Y    R270 S0      
317GND              VIA   -    MD0100PA00X+175533Y+166896X0200Y    R270 S0      
317GND              VIA   -    MD0100PA00X+174933Y+166296X0200Y    R270 S0      
317GND              VIA   -    MD0100PA00X+175776Y+164336X0200Y    R090 S0      
317GND              VIA   -    MD0100PA00X+174796Y+164196X0200Y    R090 S0      
317GND              VIA   -    MD0100PA00X+172426Y+168146X0200Y    R270 S0      
317GND              VIA   -    MD0100PA00X+172396Y+166796X0200Y    R090 S0      
317GND              VIA   -    MD0100PA00X+172393Y+165446X0200Y    R090 S0      
317GND              VIA   -    MD0100PA00X+172396Y+166346X0200Y    R090 S0      
317GND              VIA   -    MD0100PA00X+172396Y+165896X0200Y    R090 S0      
317GND              VIA   -    MD0100PA00X+181834Y+153937X0200Y    R090 S0      
317GND              VIA   -    MD0100PA00X+181534Y+153937X0200Y    R090 S0      
317GND              VIA   -    MD0100PA00X+181041Y+153922X0200Y    R090 S0      
317GND              VIA   -    MD0100PA00X+180741Y+153922X0200Y    R090 S0      
327GND              VIA   -           A18X+182889Y+147817X0260Y    R090 S2      
327GND              PC6559-2          A01X+175728Y+160495X0400Y0500     S1      
327GND              PC6558-2          A01X+175728Y+159755X0400Y0500     S1      
327GND              R910  -2          A18X+043556Y+151080X0120Y0150     S2      
317GND              VIA   -    MD0100PA00X+155849Y+156360X0200Y         S0      
317GND              VIA   -    MD0100PA00X+155599Y+156360X0200Y         S0      
317GND              VIA   -    MD0100PA00X+156261Y+156482X0200Y    R090 S0      
317GND              VIA   -    MD0100PA00X+156458Y+156232X0200Y    R090 S0      
317GND              VIA   -    MD0100PA00X+156262Y+156976X0200Y    R090 S0      
317GND              VIA   -    MD0100PA00X+156413Y+157222X0200Y    R090 S0      
327GND              C966  -2   M      A18X+156362Y+157075X0400Y0500R180 S2      
327GND              C802  -2   M      A18X+156359Y+156389X0400Y0500R180 S2      
327GND              C801  -2   M      A18X+155733Y+156365X0400Y0500R270 S2      
327GND              C1022 -2   M      A18X+155059Y+156872X0400Y0500     S2      
327GND              C1025 -2          A18X+155059Y+157558X0400Y0500     S2      
327GND              C990  -2          A18X+155018Y+156045X0400Y0500R090 S2      
317GND              VIA   -    MD0100PA00X+154868Y+155695X0200Y         S0      
317GND              VIA   -    MD0100PA00X+157665Y+157933X0200Y    R270 S0      
327GND              R1048 -2          A01X+157925Y+158379X0120Y0150R090 S1      
327GND              R1062 -2   M      A01X+157605Y+158379X0120Y0150R090 S1      
317GND              VIA   -    M      A01X+158352Y+158557X0200Y    R270 S2      
017GND              VIA   -    M      A18X+158352Y+158557X0260Y    R270 S2      
017GND                    -    MD0100PA00X+158352Y+158557                       
327GND              R1079 -2          A01X+158352Y+158794X0120Y0150R090 S1      
317GND              VIA   -    MD0100PA00X+166213Y+158218X0200Y    R270 S0      
327GND              R1082 -2          A01X+166213Y+158455X0120Y0150R090 S1      
327GND              R1084 -2          A01X+167169Y+158455X0120Y0150R090 S1      
317GND              VIA   -    MD0100PA00X+167025Y+158156X0200Y         S0      
327GND              R1061 -2          A01X+166849Y+158455X0120Y0150R090 S1      
317GND              VIA   -    MD0100PA00X+142793Y+156360X0200Y         S0      
317GND              VIA   -    MD0100PA00X+143043Y+156360X0200Y         S0      
327GND              C1028 -2   M      A18X+142927Y+156365X0400Y0500R270 S2      
317GND              VIA   -    MD0100PA00X+143558Y+156240X0200Y    R090 S0      
317GND              VIA   -    MD0100PA00X+143558Y+156490X0200Y    R090 S0      
327GND              C1033 -2   M      A18X+143553Y+156389X0400Y0500R180 S2      
317GND              VIA   -    MD0100PA00X+143560Y+156961X0200Y    R090 S0      
317GND              VIA   -    MD0100PA00X+143560Y+157211X0200Y    R090 S0      
327GND              C1029 -2   M      A18X+143555Y+157075X0400Y0500R180 S2      
317GND              VIA   -    MD0100PA00X+144554Y+154380X0200Y         S0      
327GND              R1120 -2          A01X+144344Y+154380X0120Y0150R180 S1      
327GND              R1118 -2          A18X+144344Y+154742X0120Y0150     S2      
317GND              VIA   -    MD0100PA00X+144554Y+154742X0200Y         S0      
327GND              R1113 -2          A01X+144344Y+154742X0120Y0150R180 S1      
327GND              R635  -2          A01X+144348Y+155433X0120Y0150R090 S1      
327GND              R1115 -2          A18X+144344Y+155104X0120Y0150     S2      
317GND              VIA   -    MD0100PA00X+144554Y+155104X0200Y         S0      
327GND              R1112 -2   M      A01X+144344Y+155104X0120Y0150R180 S1      
317GND              VIA   -    MD0100PA00X+144603Y+156173X0200Y         S0      
327GND              R636  -2          A01X+144348Y+156173X0120Y0150R270 S1      
327GND              R1091 -2          A01X+145118Y+158379X0120Y0150R090 S1      
317GND              VIA   -    MD0100PA00X+144850Y+157972X0200Y    R270 S0      
327GND              R1104 -2   M      A01X+144798Y+158379X0120Y0150R090 S1      
317GND              VIA   -    M      A01X+145546Y+158557X0200Y    R270 S2      
017GND              VIA   -    M      A18X+145546Y+158557X0260Y    R270 S2      
017GND                    -    MD0100PA00X+145546Y+158557                       
327GND              R1121 -2          A01X+145546Y+158794X0120Y0150R090 S1      
317GND              VIA   -    MD0100PA00X+154813Y+154265X0200Y    R090 S0      
327GND              R1125 -2          A18X+154890Y+154040X0120Y0150     S2      
317GND              VIA   -    MD0100PA00X+153407Y+158218X0200Y    R270 S0      
327GND              R1124 -2          A01X+153407Y+158455X0120Y0150R090 S1      
327GND              R1126 -2          A01X+154363Y+158525X0120Y0150R090 S1      
317GND              VIA   -    MD0100PA00X+154219Y+158156X0200Y         S0      
327GND              R1103 -2          A01X+154043Y+158455X0120Y0150R090 S1      
327GND              R631  -2          A01X+157154Y+155433X0120Y0150R090 S1      
327GND              R1070 -2   M      A01X+157150Y+155104X0120Y0150R180 S1      
317GND              VIA   -    MD0100PA00X+157360Y+155104X0200Y         S0      
327GND              R1074 -2          A18X+157150Y+155104X0120Y0150     S2      
327GND              R1072 -2          A01X+157150Y+154742X0120Y0150R180 S1      
317GND              VIA   -    MD0100PA00X+157360Y+154742X0200Y         S0      
327GND              R1076 -2          A18X+157150Y+154742X0120Y0150     S2      
327GND              R1064 -2          A18X+157150Y+154380X0120Y0150     S2      
317GND              VIA   -    MD0100PA00X+157360Y+154380X0200Y         S0      
327GND              R1078 -2          A01X+157150Y+154380X0120Y0150R180 S1      
317GND              VIA   -    MD0100PA00X+157409Y+156173X0200Y         S0      
327GND              R634  -2          A01X+157154Y+156173X0120Y0150R270 S1      
327GND              C628  -2          A18X+141448Y+156872X0400Y0500     S2      
327GND              C625  -2          A18X+141448Y+157558X0400Y0500     S2      
327GND              C587  -2          A18X+141407Y+156045X0400Y0500R090 S2      
317GND              VIA   -    MD0100PA00X+129432Y+156360X0200Y         S0      
317GND              VIA   -    MD0100PA00X+129182Y+156360X0200Y         S0      
317GND              VIA   -    MD0100PA00X+129947Y+156490X0200Y    R090 S0      
317GND              VIA   -    MD0100PA00X+129947Y+156240X0200Y    R090 S0      
317GND              VIA   -    MD0100PA00X+129949Y+156961X0200Y    R090 S0      
317GND              VIA   -    MD0100PA00X+129949Y+157211X0200Y    R090 S0      
327GND              C633  -2   M      A18X+129944Y+157075X0400Y0500R180 S2      
327GND              C637  -2   M      A18X+129942Y+156389X0400Y0500R180 S2      
327GND              C632  -2   M      A18X+129316Y+156365X0400Y0500R270 S2      
327GND              C560  -2   M      A18X+128642Y+156872X0400Y0500     S2      
327GND              C550  -2          A18X+128642Y+157558X0400Y0500     S2      
327GND              C502  -2          A18X+128600Y+156045X0400Y0500R090 S2      
317GND              VIA   -    MD0100PA00X+128451Y+155695X0200Y         S0      
317GND              VIA   -    M      A01X+131270Y+157960X0200Y    R270 S2      
017GND              VIA   -    M      A18X+131270Y+157960X0260Y    R270 S2      
017GND                    -    MD0100PA00X+131270Y+157960                       
327GND              R1006 -2          A01X+131507Y+158379X0120Y0150R090 S1      
327GND              R1020 -2   M      A01X+131187Y+158379X0120Y0150R090 S1      
317GND              VIA   -    M      A01X+131935Y+158557X0200Y    R270 S2      
017GND              VIA   -    M      A18X+131935Y+158557X0260Y    R270 S2      
017GND                    -    MD0100PA00X+131935Y+158557                       
327GND              R1037 -2          A01X+131935Y+158794X0120Y0150R090 S1      
317GND              VIA   -    MD0100PA00X+139796Y+158218X0200Y    R270 S0      
327GND              R1041 -2          A01X+139796Y+158455X0120Y0150R090 S1      
317GND              VIA   -    MD0100PA00X+141202Y+154265X0200Y    R090 S0      
327GND              R1043 -2          A01X+140752Y+158455X0120Y0150R090 S1      
317GND              VIA   -    MD0100PA00X+140607Y+158156X0200Y         S0      
327GND              R1019 -2          A01X+140432Y+158455X0120Y0150R090 S1      
317GND              VIA   -    MD0100PA00X+118185Y+156173X0200Y         S0      
327GND              R624  -2          A01X+117931Y+156173X0120Y0150R270 S1      
317GND              VIA   -    MD0100PA00X+128396Y+154265X0200Y    R090 S0      
327GND              R6821 -2          A18X+128472Y+154040X0120Y0150     S2      
327GND              R6820 -2          A01X+127945Y+158525X0120Y0150R090 S1      
317GND              VIA   -    MD0100PA00X+127801Y+158156X0200Y         S0      
327GND              R970  -2          A01X+127625Y+158455X0120Y0150R090 S1      
327GND              R629  -2          A01X+130737Y+155433X0120Y0150R090 S1      
327GND              R1028 -2   M      A01X+130732Y+155104X0120Y0150R180 S1      
317GND              VIA   -    MD0100PA00X+130942Y+155104X0200Y         S0      
327GND              R1031 -2          A18X+130732Y+155104X0120Y0150     S2      
327GND              R1029 -2          A01X+130732Y+154742X0120Y0150R180 S1      
317GND              VIA   -    MD0100PA00X+130942Y+154742X0200Y         S0      
327GND              R1033 -2          A18X+130732Y+154742X0120Y0150     S2      
327GND              R1022 -2          A18X+130732Y+154380X0120Y0150     S2      
317GND              VIA   -    MD0100PA00X+130942Y+154380X0200Y         S0      
327GND              R1035 -2          A01X+130732Y+154380X0120Y0150R180 S1      
317GND              VIA   -    MD0100PA00X+130992Y+156173X0200Y         S0      
327GND              R630  -2          A01X+130737Y+156173X0120Y0150R270 S1      
317GND              VIA   -    MD0100PA00X+055062Y+153060X0200Y         S0      
317GND              VIA   -    MD0100PA00X+054812Y+153060X0200Y         S0      
317GND              VIA   -    MD0100PA00X+055472Y+153156X0200Y    R090 S0      
317GND              VIA   -    MD0100PA00X+055664Y+152939X0200Y    R090 S0      
317GND              VIA   -    MD0100PA00X+055620Y+153919X0200Y    R090 S0      
327GND              C405  -2   M      A18X+055574Y+153775X0400Y0500R180 S2      
327GND              C409  -2   M      A18X+055572Y+153089X0400Y0500R180 S2      
327GND              C404  -2   M      A18X+054946Y+153065X0400Y0500R270 S2      
327GND              C466  -2   M      A18X+054262Y+153572X0400Y0500     S2      
327GND              C471  -2          A18X+054262Y+154258X0400Y0500     S2      
327GND              C432  -2          A18X+054230Y+152745X0400Y0500R090 S2      
317GND              VIA   -    MD0100PA00X+054081Y+152395X0200Y         S0      
317GND              VIA   -    MD0100PA00X+056878Y+154633X0200Y    R270 S0      
327GND              R886  -2          A01X+057137Y+155079X0120Y0150R090 S1      
327GND              R867  -2   M      A01X+056817Y+155079X0120Y0150R090 S1      
317GND              VIA   -    MD0100PA00X+057565Y+155257X0200Y    R270 S0      
327GND              R884  -2          A01X+057565Y+155494X0120Y0150R090 S1      
317GND              VIA   -    MD0100PA00X+065400Y+154900X0200Y    R270 S0      
327GND              R6795 -2          A01X+065426Y+155155X0120Y0150R090 S1      
327GND              R6796 -2          A01X+066382Y+155155X0120Y0150R090 S1      
317GND              VIA   -    MD0100PA00X+066237Y+154856X0200Y         S0      
327GND              R866  -2          A01X+066062Y+155155X0120Y0150R090 S1      
317GND              VIA   -    MD0100PA00X+042006Y+153060X0200Y         S0      
317GND              VIA   -    MD0100PA00X+042256Y+153060X0200Y         S0      
327GND              C474  -2   M      A18X+042140Y+153065X0400Y0500R270 S2      
317GND              VIA   -    MD0100PA00X+042770Y+152940X0200Y    R090 S0      
317GND              VIA   -    MD0100PA00X+042770Y+153190X0200Y    R090 S0      
327GND              C475  -2   M      A18X+042765Y+153089X0400Y0500R180 S2      
317GND              VIA   -    MD0100PA00X+042773Y+153661X0200Y    R090 S0      
317GND              VIA   -    MD0100PA00X+042773Y+153911X0200Y    R090 S0      
327GND              C479  -2   M      A18X+042768Y+153775X0400Y0500R180 S2      
317GND              VIA   -    MD0100PA00X+043766Y+151080X0200Y         S0      
327GND              R923  -2          A01X+043556Y+151080X0120Y0150R180 S1      
327GND              R921  -2          A18X+043556Y+151442X0120Y0150     S2      
317GND              VIA   -    MD0100PA00X+043766Y+151442X0200Y         S0      
327GND              R917  -2          A01X+043556Y+151442X0120Y0150R180 S1      
327GND              R919  -2          A18X+043556Y+151804X0120Y0150     S2      
317GND              VIA   -    MD0100PA00X+043766Y+151804X0200Y         S0      
327GND              R916  -2   M      A01X+043556Y+151804X0120Y0150R180 S1      
317GND              VIA   -    MD0100PA00X+043815Y+152873X0200Y         S0      
327GND              R642  -2          A01X+043561Y+152873X0120Y0150R270 S1      
327GND              R926  -2          A01X+044381Y+155079X0120Y0150R090 S1      
317GND              VIA   -    MD0100PA00X+043873Y+154698X0200Y    R270 S0      
327GND              R908  -2   M      A01X+044061Y+155079X0120Y0150R090 S1      
317GND              VIA   -    MD0100PA00X+044759Y+155257X0200Y    R270 S0      
327GND              R875  -2   M      A01X+056362Y+151804X0120Y0150R180 S1      
317GND              VIA   -    MD0100PA00X+056572Y+151804X0200Y         S0      
327GND              R879  -2          A18X+056362Y+151804X0120Y0150     S2      
327GND              R876  -2          A01X+056362Y+151442X0120Y0150R180 S1      
317GND              VIA   -    MD0100PA00X+056572Y+151442X0200Y         S0      
327GND              R881  -2          A18X+056362Y+151442X0120Y0150     S2      
327GND              R869  -2          A18X+056362Y+151080X0120Y0150     S2      
317GND              VIA   -    MD0100PA00X+056572Y+151080X0200Y         S0      
327GND              R883  -2          A01X+056362Y+151080X0120Y0150R180 S1      
317GND              VIA   -    MD0100PA00X+056622Y+152873X0200Y         S0      
327GND              R640  -2          A01X+056367Y+152873X0120Y0150R270 S1      
327GND              C342  -2          A18X+036189Y+153796X0120Y0150R090 S2      
327GND              C220  -2          A18X+027855Y+154258X0400Y0500     S2      
327GND              C113  -2          A18X+027813Y+152745X0400Y0500R090 S2      
327GND              C225  -2   M      A18X+027855Y+153572X0400Y0500     S2      
327GND              C114  -2   M      A18X+027132Y+152745X0400Y0500R090 S2      
327GND              C328  -2          A18X+040661Y+154258X0400Y0500     S2      
327GND              C317  -2          A18X+040661Y+153572X0400Y0500     S2      
327GND              C102  -2          A18X+040619Y+152745X0400Y0500R090 S2      
327GND              C306  -2          A18X+033349Y+152165X0120Y0150R090 S2      
327GND              C313  -2          A18X+033404Y+152865X0120Y0150R270 S2      
327GND              C315  -2          A18X+036656Y+152165X0120Y0150R090 S2      
327GND              C316  -2          A18X+036711Y+152865X0120Y0150R270 S2      
327GND              C203  -2          A18X+035711Y+152165X0120Y0150R090 S2      
327GND              C206  -2          A18X+035766Y+152865X0120Y0150R270 S2      
327GND              R749  -2          A01X+039644Y+155155X0120Y0150R090 S1      
317GND              VIA   -    MD0100PA00X+040470Y+152395X0200Y         S0      
327GND              C217  -2          A18X+035239Y+152165X0120Y0150R090 S2      
327GND              C287  -2          A18X+035294Y+152865X0120Y0150R270 S2      
327GND              C288  -2          A18X+034766Y+152165X0120Y0150R090 S2      
327GND              C202  -2          A18X+034821Y+152865X0120Y0150R270 S2      
327GND              C204  -2          A18X+034349Y+152865X0120Y0150R270 S2      
327GND              C205  -2          A18X+034294Y+152165X0120Y0150R090 S2      
327GND              C300  -2          A18X+036184Y+152165X0120Y0150R090 S2      
327GND              C311  -2          A18X+036239Y+152865X0120Y0150R270 S2      
327GND              C292  -2          A18X+033821Y+152165X0120Y0150R090 S2      
327GND              C290  -2          A18X+033876Y+152865X0120Y0150R270 S2      
327GND              C353  -2          A18X+039020Y+152165X0120Y0150R090 S2      
327GND              C289  -2          A18X+038546Y+152165X0120Y0150R090 S2      
327GND              C291  -2          A18X+038601Y+152865X0120Y0150R270 S2      
327GND              C346  -2          A18X+038073Y+152165X0120Y0150R090 S2      
327GND              C340  -2          A18X+038128Y+152865X0120Y0150R270 S2      
327GND              C344  -2          A18X+037656Y+152865X0120Y0150R270 S2      
327GND              C307  -2          A18X+037601Y+152165X0120Y0150R090 S2      
327GND              C314  -2          A18X+037128Y+152165X0120Y0150R090 S2      
327GND              C350  -2          A18X+037184Y+152865X0120Y0150R270 S2      
327GND              C294  -2          A18X+032876Y+152165X0120Y0150R090 S2      
327GND              C334  -2          A18X+032932Y+152865X0120Y0150R270 S2      
327GND              C337  -2          A18X+032404Y+152165X0120Y0150R090 S2      
327GND              C319  -2          A18X+032459Y+152865X0120Y0150R270 S2      
327GND              C322  -2          A18X+031987Y+152865X0120Y0150R270 S2      
327GND              C326  -2          A18X+031459Y+152165X0120Y0150R090 S2      
327GND              C330  -2          A18X+031932Y+152165X0120Y0150R090 S2      
327GND              C341  -2          A18X+031514Y+152865X0120Y0150R270 S2      
327GND              R6733 -2          A18X+040491Y+150740X0120Y0150     S2      
317GND              VIA   -    MD0100PA00X+040415Y+150965X0200Y    R090 S0      
327GND              R6732 -2          A01X+039964Y+155155X0120Y0150R090 S1      
317GND              VIA   -    MD0100PA00X+039820Y+154856X0200Y         S0      
327GND              R6731 -2          A01X+039008Y+155155X0120Y0150R090 S1      
317GND              VIA   -    MD0100PA00X+039008Y+154918X0200Y    R270 S0      
317GND              VIA   -    MD0080PA00X+038546Y+152145X0160Y         S0      
317GND              VIA   -    MD0080PA00X+039020Y+152145X0160Y         S0      
317GND              VIA   -    MD0080PA00X+037128Y+152145X0160Y         S0      
317GND              VIA   -    MD0080PA00X+036656Y+152145X0160Y         S0      
317GND              VIA   -    MD0080PA00X+038073Y+152145X0160Y         S0      
317GND              VIA   -    MD0080PA00X+037601Y+152145X0160Y         S0      
317GND              VIA   -    MD0080PA00X+035239Y+152145X0160Y         S0      
317GND              VIA   -    MD0080PA00X+035711Y+152145X0160Y         S0      
317GND              VIA   -    MD0080PA00X+036184Y+152145X0160Y         S0      
317GND              VIA   -    MD0080PA00X+033821Y+152145X0160Y         S0      
317GND              VIA   -    MD0080PA00X+034294Y+152145X0160Y         S0      
317GND              VIA   -    MD0080PA00X+034766Y+152145X0160Y         S0      
317GND              VIA   -    MD0080PA00X+032404Y+152145X0160Y         S0      
317GND              VIA   -    MD0080PA00X+032876Y+152145X0160Y         S0      
317GND              VIA   -    MD0080PA00X+033349Y+152145X0160Y         S0      
317GND              VIA   -    MD0080PA00X+031459Y+152145X0160Y         S0      
317GND              VIA   -    MD0080PA00X+031932Y+152145X0160Y         S0      
317GND              VIA   -    MD0080PA00X+038601Y+152885X0160Y         S0      
317GND              VIA   -    MD0080PA00X+038128Y+152885X0160Y         S0      
317GND              VIA   -    MD0080PA00X+037184Y+152885X0160Y         S0      
317GND              VIA   -    MD0080PA00X+036711Y+152885X0160Y         S0      
317GND              VIA   -    MD0080PA00X+037656Y+152885X0160Y         S0      
317GND              VIA   -    MD0080PA00X+035294Y+152885X0160Y         S0      
317GND              VIA   -    MD0080PA00X+035766Y+152885X0160Y         S0      
317GND              VIA   -    MD0080PA00X+036239Y+152885X0160Y         S0      
317GND              VIA   -    MD0080PA00X+033876Y+152885X0160Y         S0      
317GND              VIA   -    MD0080PA00X+034349Y+152885X0160Y         S0      
317GND              VIA   -    MD0080PA00X+034821Y+152885X0160Y         S0      
317GND              VIA   -    MD0080PA00X+032459Y+152885X0160Y         S0      
317GND              VIA   -    MD0080PA00X+032932Y+152885X0160Y         S0      
317GND              VIA   -    MD0080PA00X+033404Y+152885X0160Y         S0      
317GND              VIA   -    MD0080PA00X+031514Y+152885X0160Y         S0      
317GND              VIA   -    MD0080PA00X+031987Y+152885X0160Y         S0      
327GND              U6015 -E27 M      A01X+039119Y+151863X0120Y         S1      
327GND              U6015 -B19        A01X+039324Y+152453X0100Y0130R090 S1      
327GND              U6015 -H19 M      A01X+038914Y+152453X0120Y         S1      
327GND              U6015 -H12        A01X+038914Y+152926X0120Y         S1      
327GND              U6015 -E14 M      A01X+039119Y+152808X0120Y         S1      
327GND              U6015 -J22 M      A01X+038818Y+152220X0120Y         S1      
327GND              U6015 -T22 M      A01X+038346Y+152220X0120Y         S1      
327GND              U6015 -AC22M      A01X+037873Y+152220X0120Y         S1      
327GND              U6015 -BD13M      A01X+036456Y+152811X0120Y         S1      
327GND              U6015 -AU13M      A01X+036928Y+152811X0120Y         S1      
327GND              U6015 -AK13M      A01X+037401Y+152811X0120Y         S1      
327GND              U6015 -AK22M      A01X+037401Y+152220X0120Y         S1      
327GND              U6015 -AU22M      A01X+036928Y+152220X0120Y         S1      
327GND              U6015 -BD22M      A01X+036456Y+152220X0120Y         S1      
327GND              U6015 -CE13M      A01X+035039Y+152811X0120Y         S1      
327GND              U6015 -BV13M      A01X+035511Y+152811X0120Y         S1      
327GND              U6015 -BL13M      A01X+035984Y+152811X0120Y         S1      
327GND              U6015 -BL22M      A01X+035984Y+152220X0120Y         S1      
327GND              U6015 -BV22M      A01X+035511Y+152220X0120Y         S1      
327GND              U6015 -CE22M      A01X+035039Y+152220X0120Y         S1      
327GND              U6015 -CM22M      A01X+034566Y+152220X0120Y         S1      
327GND              U6015 -CW22M      A01X+034094Y+152220X0120Y         S1      
327GND              U6015 -DF22M      A01X+033621Y+152220X0120Y         S1      
327GND              U6015 -DN22M      A01X+033149Y+152220X0120Y         S1      
327GND              U6015 -DY22M      A01X+032676Y+152220X0120Y         S1      
327GND              U6015 -EG22M      A01X+032204Y+152220X0120Y         S1      
327GND              U6015 -EP22M      A01X+031732Y+152220X0120Y         S1      
327GND              U6015 -FF21M      A01X+030956Y+152335X0120Y         S1      
327GND              U6015 -FC19M      A01X+031161Y+152453X0120Y         S1      
327GND              U6015 -FJ19M      A01X+030752Y+152453X0100Y0130R090 S1      
327GND              U6015 -FJ12M      A01X+030752Y+152926X0100Y0130R090 S1      
327GND              R628  -2          A01X+017143Y+152873X0120Y0150R270 S1      
317GND              VIA   -    MD0100PA00X+017398Y+152873X0200Y         S0      
327GND              PC6512-2          A18X+096801Y+124742X0400Y0500R090 S2      
327GND              PC6509-2          A18X+097501Y+124742X0400Y0500R090 S2      
327GND              PC6511-2          A18X+095181Y+124742X0400Y0500R090 S2      
327GND              PC6508-2          A18X+095991Y+124742X0400Y0500R090 S2      
327GND              PC6510-2          A18X+094481Y+124742X0400Y0500R090 S2      
327GND              PC6530-2          A18X+091602Y+124742X0400Y0500R090 S2      
327GND              PC6529-2          A18X+090902Y+124742X0400Y0500R090 S2      
327GND              PC6527-2          A18X+090092Y+124742X0400Y0500R090 S2      
327GND              PC6528-2          A18X+089282Y+124742X0400Y0500R090 S2      
327GND              PC6531-2          A18X+088582Y+124742X0400Y0500R090 S2      
327GND              VIA   -           A18X+078777Y+144127X0260Y    R090 S2      
327GND              VIA   -           A18X+077277Y+144127X0260Y    R090 S2      
327GND              VIA   -           A18X+079277Y+142627X0260Y    R180 S2      
327GND              VIA   -           A18X+079277Y+141127X0260Y    R180 S2      
327GND              PC27  -2          A18X+077191Y+137918X0400Y0500R270 S2      
327GND              PC514_-2          A18X+076510Y+137933X0400Y0500R270 S2      
327GND              PC516_-2          A18X+075698Y+137933X0400Y0500R270 S2      
327GND              PC515_-2          A18X+073231Y+137923X0400Y0500R270 S2      
327GND              PC513_-2          A18X+072420Y+137923X0400Y0500R270 S2      
327GND              PC8000-2          A18X+078367Y+136230X0400Y0500R180 S2      
327GND              PC528 -2          A18X+075274Y+136763X0950Y1110R270 S2      
327GND              PC525 -2          A18X+072027Y+136772X0950Y1110R270 S2      
327GND              PC802 -2          A18X+069227Y+136609X0950Y1110R270 S2      
327GND              PR6000-1          A18X+080117Y+134588X0198Y0197R180 S2      
327GND              PC8001-2          A18X+078367Y+135540X0400Y0500R180 S2      
327GND              VIA   -           A18X+076646Y+136078X0260Y    R090 S2      
327GND              PC523_-2          A18X+076646Y+135036X0400Y0500R090 S2      
327GND              VIA   -           A18X+073527Y+136141X0260Y    R090 S2      
327GND              PC527_-2          A18X+073527Y+135099X0400Y0500R090 S2      
327GND              PC526_-2          A18X+070612Y+135099X0400Y0500R090 S2      
327GND              VIA   -           A18X+067855Y+136141X0260Y    R090 S2      
327GND              PC529_-2          A18X+067855Y+135099X0400Y0500R090 S2      
327GND              VIA   -           A18X+066500Y+134910X0260Y    R090 S2      
327GND              VIA   -           A18X+080542Y+132126X0260Y    R180 S2      
327GND              VIA   -           A18X+066500Y+132910X0260Y    R090 S2      
327GND              PC130 -2          A18X+080328Y+130676X0400Y0500R090 S2      
327GND              PC134 -2          A18X+079528Y+130676X0400Y0500R090 S2      
327GND              PC129 -2          A18X+078728Y+130676X0400Y0500R090 S2      
327GND              PC135 -2          A18X+077928Y+130676X0400Y0500R090 S2      
327GND              VIA   -           A18X+075255Y+129725X0260Y         S2      
327GND              VIA   -           A18X+068078Y+129751X0260Y         S2      
327GND              PC123 -2          A01X+080497Y+135798X0400Y0500R180 S1      
327GND              PC119 -2          A01X+078367Y+136230X0400Y0500     S1      
327GND              PC120 -2          A01X+078367Y+135540X0400Y0500     S1      
327GND              PU55  -11_1       A01X+078614Y+134224X0315Y1240R180 S1      
327GND              PC118 -2          A01X+077945Y+133733X0198Y0197R090 S1      
327GND              PC136 -2          A01X+080767Y+130479X0198Y0197R090 S1      
327GND              PU6500-6          A01X+095264Y+114709X0070Y0320R090 S1      
327GND              PU6500-2          A01X+095264Y+115339X0070Y0320R090 S1      
327GND              PU6501-6          A01X+090562Y+114709X0070Y0320R090 S1      
327GND              PU6501-2          A01X+090562Y+115339X0070Y0320R090 S1      
327GND              PC6000-2          A01X+081099Y+136419X0198Y0197     S1      
327GND              C348  -2          A01X+080785Y+135199X0198Y0197     S1      
327GND              PR452 -2   M      A01X+080744Y+133633X0198Y0197     S1      
327GND              PC127 -2   M      A01X+080744Y+134076X0198Y0197     S1      
327GND              PR454 -2   M      A01X+080446Y+134518X0198Y0197R270 S1      
327GND              PU55  -6          A01X+079628Y+134274X0070Y0320R270 S1      
327GND              PU55  -2          A01X+079628Y+133644X0070Y0320R270 S1      
327GND              PC126 -2   M      A01X+079542Y+132866X0198Y0197     S1      
317GND              VIA   -    MD0100PA00X+098956Y+110041X0200Y    R270 S0      
317GND              VIA   -    MD0100PA00X+098956Y+109701X0200Y    R270 S0      
317GND              VIA   -    MD0100PA00X+098956Y+108411X0200Y    R270 S0      
317GND              VIA   -    MD0100PA00X+098956Y+108751X0200Y    R270 S0      
317GND              VIA   -    MD0100PA00X+096690Y+115277X0200Y    R180 S0      
317GND              VIA   -    MD0100PA00X+096990Y+114977X0200Y    R180 S0      
317GND              VIA   -    MD0100PA00X+096690Y+114977X0200Y    R180 S0      
317GND              VIA   -    MD0100PA00X+096990Y+114337X0200Y    R180 S0      
317GND              VIA   -    MD0100PA00X+096990Y+113997X0200Y    R180 S0      
317GND              VIA   -    MD0100PA00X+096690Y+114337X0200Y    R180 S0      
317GND              VIA   -    MD0100PA00X+096690Y+113997X0200Y    R180 S0      
317GND              VIA   -    MD0100PA00X+096990Y+114657X0200Y    R180 S0      
317GND              VIA   -    MD0100PA00X+096690Y+114657X0200Y    R180 S0      
317GND              VIA   -    MD0100PA00X+098636Y+110041X0200Y    R270 S0      
317GND              VIA   -    MD0100PA00X+098316Y+110041X0200Y    R270 S0      
317GND              VIA   -    MD0100PA00X+098316Y+109701X0200Y    R270 S0      
317GND              VIA   -    MD0100PA00X+098636Y+109701X0200Y    R270 S0      
317GND              VIA   -    MD0100PA00X+098636Y+108411X0200Y    R270 S0      
317GND              VIA   -    MD0100PA00X+098316Y+108411X0200Y    R270 S0      
317GND              VIA   -    MD0100PA00X+098316Y+108751X0200Y    R270 S0      
317GND              VIA   -    MD0100PA00X+098636Y+108751X0200Y    R270 S0      
317GND              VIA   -    MD0100PA00X+095350Y+115857X0200Y    R180 S0      
317GND              VIA   -    MD0100PA00X+094775Y+114655X0200Y    R270 S0      
317GND              VIA   -    MD0100PA00X+094482Y+115612X0200Y    R270 S0      
317GND              VIA   -    MD0100PA00X+097715Y+105268X0200Y    R090 S0      
317GND              VIA   -    MD0100PA00X+091988Y+115277X0200Y    R180 S0      
317GND              VIA   -    MD0100PA00X+092288Y+114977X0200Y    R180 S0      
317GND              VIA   -    MD0100PA00X+092288Y+114337X0200Y    R180 S0      
317GND              VIA   -    MD0100PA00X+092288Y+113997X0200Y    R180 S0      
317GND              VIA   -    MD0100PA00X+092288Y+114657X0200Y    R180 S0      
317GND              VIA   -    MD0100PA00X+091988Y+114977X0200Y    R180 S0      
317GND              VIA   -    MD0100PA00X+091688Y+113897X0200Y    R180 S0      
317GND              VIA   -    MD0100PA00X+091988Y+114337X0200Y    R180 S0      
317GND              VIA   -    MD0100PA00X+091988Y+113997X0200Y    R180 S0      
317GND              VIA   -    MD0100PA00X+091988Y+114657X0200Y    R180 S0      
317GND              VIA   -    MD0100PA00X+088906Y+105313X0200Y    R270 S0      
317GND              VIA   -    MD0100PA00X+090647Y+115857X0200Y    R180 S0      
317GND              VIA   -    MD0100PA00X+090072Y+114655X0200Y         S0      
317GND              VIA   -    MD0100PA00X+089775Y+115612X0200Y    R270 S0      
317GND              VIA   -    MD0100PA00X+089165Y+113784X0200Y         S0      
317GND              VIA   -    MD0100PA00X+089800Y+110974X0200Y    R180 S0      
317GND              VIA   -    MD0100PA00X+089800Y+111234X0200Y    R180 S0      
317GND              VIA   -    MD0100PA00X+088122Y+109756X0200Y    R270 S0      
317GND              VIA   -    MD0100PA00X+088122Y+110096X0200Y    R270 S0      
317GND              VIA   -    MD0100PA00X+088122Y+108806X0200Y    R270 S0      
317GND              VIA   -    MD0100PA00X+088122Y+108466X0200Y    R270 S0      
317GND              VIA   -    MD0100PA00X+087462Y+109756X0200Y    R270 S0      
317GND              VIA   -    MD0100PA00X+087782Y+109756X0200Y    R270 S0      
317GND              VIA   -    MD0100PA00X+087782Y+110096X0200Y    R270 S0      
317GND              VIA   -    MD0100PA00X+087462Y+110096X0200Y    R270 S0      
317GND              VIA   -    MD0100PA00X+087462Y+108806X0200Y    R270 S0      
317GND              VIA   -    MD0100PA00X+087782Y+108806X0200Y    R270 S0      
317GND              VIA   -    MD0100PA00X+087782Y+108466X0200Y    R270 S0      
317GND              VIA   -    MD0100PA00X+087462Y+108466X0200Y    R270 S0      
317GND              VIA   -    MD0100PA00X+092011Y+124592X0200Y         S0      
317GND              VIA   -    MD0100PA00X+092011Y+124892X0200Y         S0      
317GND              VIA   -    MD0100PA00X+092011Y+125774X0200Y         S0      
317GND              VIA   -    MD0100PA00X+092011Y+125474X0200Y         S0      
317GND              VIA   -    MD0100PA00X+092011Y+125174X0200Y         S0      
317GND              VIA   -    MD0100PA00X+090501Y+124592X0200Y         S0      
317GND              VIA   -    MD0100PA00X+090501Y+124892X0200Y         S0      
317GND              VIA   -    MD0100PA00X+091071Y+125174X0200Y         S0      
317GND              VIA   -    MD0100PA00X+091071Y+125774X0200Y         S0      
317GND              VIA   -    MD0100PA00X+091071Y+125474X0200Y         S0      
317GND              VIA   -    MD0100PA00X+089691Y+124892X0200Y         S0      
317GND              VIA   -    MD0100PA00X+089691Y+124592X0200Y         S0      
317GND              VIA   -    MD0100PA00X+089611Y+125174X0200Y         S0      
317GND              VIA   -    MD0100PA00X+089611Y+125474X0200Y         S0      
317GND              VIA   -    MD0100PA00X+089611Y+125774X0200Y         S0      
317GND              VIA   -    MD0100PA00X+088194Y+125186X0200Y         S0      
317GND              VIA   -    MD0100PA00X+088181Y+124592X0200Y         S0      
317GND              VIA   -    MD0100PA00X+088181Y+124892X0200Y         S0      
317GND              VIA   -    MD0100PA00X+088671Y+125174X0200Y         S0      
317GND              VIA   -    MD0100PA00X+088671Y+125474X0200Y         S0      
317GND              VIA   -    MD0100PA00X+088671Y+125774X0200Y         S0      
317GND              VIA   -    MD0100PA00X+081099Y+136168X0200Y    R090 S0      
317GND              VIA   -    MD0100PA00X+081025Y+135199X0200Y    R180 S0      
317GND              VIA   -    MD0100PA00X+080847Y+135924X0200Y    R270 S0      
317GND              VIA   -    MD0100PA00X+080847Y+135674X0200Y    R270 S0      
317GND              VIA   -    MD0100PA00X+080117Y+134328X0200Y    R090 S0      
317GND              VIA   -    MD0100PA00X+080410Y+133384X0200Y    R090 S0      
317GND              VIA   -    MD0100PA00X+080760Y+130719X0200Y    R180 S0      
317GND              VIA   -    MD0100PA00X+080453Y+131026X0200Y    R180 S0      
317GND              VIA   -    MD0100PA00X+080203Y+131026X0200Y    R180 S0      
317GND              VIA   -    MD0100PA00X+078501Y+135086X0200Y    R090 S0      
317GND              VIA   -    MD0100PA00X+079542Y+133126X0200Y    R090 S0      
317GND              VIA   -    MD0100PA00X+078853Y+131026X0200Y    R180 S0      
317GND              VIA   -    MD0100PA00X+079653Y+131026X0200Y    R180 S0      
317GND              VIA   -    MD0100PA00X+079403Y+131026X0200Y    R180 S0      
317GND              VIA   -    MD0100PA00X+078603Y+131026X0200Y    R180 S0      
317GND              VIA   -    MD0100PA00X+078000Y+136050X0200Y    R090 S0      
317GND              VIA   -    MD0100PA00X+078000Y+136350X0200Y    R090 S0      
317GND              VIA   -    MD0100PA00X+078201Y+134986X0200Y    R090 S0      
317GND              VIA   -    MD0100PA00X+078201Y+134646X0200Y    R090 S0      
317GND              VIA   -    MD0100PA00X+077901Y+134986X0200Y    R090 S0      
317GND              VIA   -    MD0100PA00X+077901Y+134646X0200Y    R090 S0      
317GND              VIA   -    MD0100PA00X+078000Y+135350X0200Y    R090 S0      
317GND              VIA   -    MD0100PA00X+078201Y+134326X0200Y    R090 S0      
317GND              VIA   -    MD0100PA00X+078201Y+133706X0200Y    R090 S0      
317GND              VIA   -    MD0100PA00X+078201Y+134006X0200Y    R090 S0      
317GND              VIA   -    MD0100PA00X+077901Y+134006X0200Y    R090 S0      
317GND              VIA   -    MD0100PA00X+077901Y+134326X0200Y    R090 S0      
317GND              VIA   -    MD0100PA00X+078053Y+131026X0200Y    R180 S0      
317GND              VIA   -    MD0100PA00X+077803Y+131026X0200Y    R180 S0      
317GND              H12   -1   MD1470PA00X+098386Y+114528X2440Y         S3      
327GND              R711  -2          A01X+027158Y+155225X0120Y0150R090 S1      
327GND              R6720 -2          A01X+026838Y+155155X0120Y0150R090 S1      
317GND              VIA   -    MD0100PA00X+027014Y+154856X0200Y         S0      
317GND              VIA   -    MD0100PA00X+027664Y+152395X0200Y         S0      
327GND              C280  -2          A18X+026214Y+152165X0120Y0150R090 S2      
327GND              C198  -2          A18X+023905Y+152865X0120Y0150R270 S2      
327GND              C130  -2          A18X+022960Y+152865X0120Y0150R270 S2      
317GND              VIA   -    MD0100PA00X+029279Y+152156X0200Y    R090 S0      
317GND              VIA   -    MD0100PA00X+022132Y+155080X0180Y         S0      
317GND              VIA   -    MD0100PA00X+022605Y+155090X0180Y         S0      
317GND              VIA   -    MD0100PA00X+021660Y+155070X0180Y         S0      
327GND              R6715 -2   M      A01X+028620Y+152385X0120Y0150R270 S1      
317GND              VIA   -    MD0100PA00X+028480Y+152675X0200Y    R090 S0      
327GND              U6014 -E30        A01X+026313Y+151626X0120Y         S1      
317GND              VIA   -    MD0100PA00X+030204Y+152873X0200Y         S0      
327GND              R626  -2          A01X+029950Y+152873X0120Y0150R270 S1      
317GND              VIA   -    MD0100PA00X+030461Y+154633X0200Y    R270 S0      
327GND              R792  -2          A01X+031148Y+155494X0120Y0150R090 S1      
317GND              VIA   -    MD0100PA00X+031148Y+155257X0200Y    R270 S0      
327GND              R756  -2          A18X+029945Y+151080X0120Y0150     S2      
327GND              R787  -2          A18X+029945Y+151442X0120Y0150     S2      
327GND              R785  -2          A18X+029945Y+151804X0120Y0150     S2      
317GND              VIA   -    MD0100PA00X+030155Y+151080X0200Y         S0      
327GND              R791  -2          A01X+029945Y+151080X0120Y0150R180 S1      
317GND              VIA   -    MD0100PA00X+030155Y+151442X0200Y         S0      
327GND              R783  -2          A01X+029945Y+151442X0120Y0150R180 S1      
317GND              VIA   -    MD0100PA00X+030155Y+151804X0200Y         S0      
327GND              R782  -2   M      A01X+029945Y+151804X0120Y0150R180 S1      
317GND              VIA   -    MD0100PA00X+029159Y+153190X0200Y    R090 S0      
317GND              VIA   -    MD0100PA00X+029159Y+152940X0200Y    R090 S0      
327GND              C324  -2   M      A18X+029154Y+153089X0400Y0500R180 S2      
317GND              VIA   -    MD0100PA00X+029162Y+153911X0200Y    R090 S0      
317GND              VIA   -    MD0100PA00X+029162Y+153661X0200Y    R090 S0      
327GND              C320  -2   M      A18X+029157Y+153775X0400Y0500R180 S2      
317GND              VIA   -    MD0100PA00X+028645Y+153060X0200Y         S0      
317GND              VIA   -    MD0100PA00X+028395Y+153060X0200Y         S0      
327GND              C323  -2   M      A18X+028529Y+153065X0400Y0500R270 S2      
327GND              U6015 -AC32M      A01X+037873Y+151424X0150Y         S1      
327GND              U6015 -AC4 M      A01X+037873Y+153606X0150Y         S1      
327GND              U6015 -AD2 M      A01X+037853Y+153843X0120Y         S1      
327GND              U6015 -AD34M      A01X+037853Y+151150X0120Y         S1      
327GND              U6015 -AE1 M      A01X+037734Y+154048X0100Y0130     S1      
327GND              U6015 -AK32M      A01X+037401Y+151424X0150Y         S1      
327GND              U6015 -AK4 M      A01X+037401Y+153606X0150Y         S1      
327GND              U6015 -AL2 M      A01X+037380Y+153843X0120Y         S1      
327GND              U6015 -AL34M      A01X+037380Y+151150X0120Y         S1      
327GND              U6015 -AM1 M      A01X+037262Y+154048X0100Y0130     S1      
327GND              U6015 -AU32M      A01X+036928Y+151424X0150Y         S1      
327GND              U6015 -AU4 M      A01X+036928Y+153606X0150Y         S1      
327GND              U6015 -AV2 M      A01X+036908Y+153843X0120Y         S1      
327GND              U6015 -AV34M      A01X+036908Y+151150X0120Y         S1      
327GND              U6015 -AW1 M      A01X+036790Y+154048X0100Y0130     S1      
327GND              U6015 -BD32M      A01X+036456Y+151424X0150Y         S1      
327GND              U6015 -BD4 M      A01X+036456Y+153606X0150Y         S1      
327GND              U6015 -BE2 M      A01X+036435Y+153843X0120Y         S1      
327GND              U6015 -BE34M      A01X+036435Y+151150X0120Y         S1      
327GND              U6015 -BF1 M      A01X+036317Y+154048X0100Y0130     S1      
327GND              U6015 -BL32M      A01X+035984Y+151424X0150Y         S1      
327GND              U6015 -BL4 M      A01X+035984Y+153606X0150Y         S1      
327GND              U6015 -BM2 M      A01X+035963Y+153843X0120Y         S1      
327GND              U6015 -BM34M      A01X+035963Y+151150X0120Y         S1      
327GND              U6015 -BN1 M      A01X+035845Y+154048X0100Y0130     S1      
327GND              U6015 -BV32M      A01X+035511Y+151424X0150Y         S1      
327GND              U6015 -BV4 M      A01X+035511Y+153606X0150Y         S1      
327GND              U6015 -BW2 M      A01X+035490Y+153843X0120Y         S1      
327GND              U6015 -BW34M      A01X+035490Y+151150X0120Y         S1      
327GND              U6015 -BY1 M      A01X+035372Y+154048X0100Y0130     S1      
327GND              U6015 -CE32M      A01X+035039Y+151424X0150Y         S1      
327GND              U6015 -CE4 M      A01X+035039Y+153606X0150Y         S1      
327GND              U6015 -CF2 M      A01X+035018Y+153843X0120Y         S1      
327GND              U6015 -CF34M      A01X+035018Y+151150X0120Y         S1      
327GND              U6015 -CG1 M      A01X+034900Y+154048X0100Y0130     S1      
327GND              U6015 -CM32M      A01X+034566Y+151424X0150Y         S1      
327GND              U6015 -CM4 M      A01X+034566Y+153606X0150Y         S1      
327GND              U6015 -CN2 M      A01X+034546Y+153843X0120Y         S1      
327GND              U6015 -CN34M      A01X+034546Y+151150X0120Y         S1      
327GND              U6015 -CP1 M      A01X+034428Y+154048X0100Y0130     S1      
327GND              U6015 -CW32M      A01X+034094Y+151424X0150Y         S1      
327GND              U6015 -CW4 M      A01X+034094Y+153606X0150Y         S1      
327GND              U6015 -CY2 M      A01X+034073Y+153843X0120Y         S1      
327GND              U6015 -CY34M      A01X+034073Y+151150X0120Y         S1      
327GND              U6015 -DA1 M      A01X+033955Y+154048X0100Y0130     S1      
327GND              U6015 -DF32M      A01X+033621Y+151424X0150Y         S1      
327GND              U6015 -DF4 M      A01X+033621Y+153606X0150Y         S1      
327GND              U6015 -DG2 M      A01X+033601Y+153843X0120Y         S1      
327GND              U6015 -DG34M      A01X+033601Y+151150X0120Y         S1      
327GND              U6015 -DH1 M      A01X+033483Y+154048X0100Y0130     S1      
327GND              U6015 -DN32M      A01X+033149Y+151424X0150Y         S1      
327GND              U6015 -DN4 M      A01X+033149Y+153606X0150Y         S1      
327GND              U6015 -DP2 M      A01X+033128Y+153843X0120Y         S1      
327GND              U6015 -DP34M      A01X+033128Y+151150X0120Y         S1      
327GND              U6015 -DR1 M      A01X+033010Y+154048X0100Y0130     S1      
327GND              U6015 -DY32M      A01X+032676Y+151424X0150Y         S1      
327GND              U6015 -DY4 M      A01X+032676Y+153606X0150Y         S1      
327GND              U6015 -EA2 M      A01X+032656Y+153843X0120Y         S1      
327GND              U6015 -EA34M      A01X+032656Y+151150X0120Y         S1      
327GND              U6015 -EB1 M      A01X+032538Y+154048X0100Y0130     S1      
327GND              U6015 -EG32M      A01X+032204Y+151424X0150Y         S1      
327GND              U6015 -EG4 M      A01X+032204Y+153606X0150Y         S1      
327GND              U6015 -EH2 M      A01X+032183Y+153843X0120Y         S1      
327GND              U6015 -EH34M      A01X+032183Y+151150X0120Y         S1      
327GND              U6015 -EJ1 M      A01X+032065Y+154048X0100Y0130     S1      
327GND              U6015 -EP32M      A01X+031732Y+151424X0150Y         S1      
327GND              U6015 -EP4 M      A01X+031732Y+153606X0150Y         S1      
327GND              U6015 -ER2 M      A01X+031711Y+153843X0120Y         S1      
327GND              U6015 -ER34M      A01X+031711Y+151150X0120Y         S1      
327GND              U6015 -ET1 M      A01X+031593Y+154048X0100Y0130     S1      
327GND              U6015 -FA32M      A01X+031259Y+151424X0150Y         S1      
327GND              U6015 -FB2 M      A01X+031238Y+153843X0120Y         S1      
327GND              U6015 -FB34M      A01X+031238Y+151150X0120Y         S1      
327GND              U6015 -FC23M      A01X+031161Y+152217X0120Y         S1      
327GND              U6015 -FC25M      A01X+031161Y+151981X0120Y         S1      
327GND              U6015 -FC28M      A01X+031161Y+151744X0120Y         S1      
327GND              U6015 -FC3 M      A01X+031161Y+153634X0120Y         S1      
327GND              U6015 -FC6 M      A01X+031161Y+153398X0120Y         S1      
327GND              U6015 -FC9 M      A01X+031161Y+153162X0120Y         S1      
327GND              U6015 -FD1 M      A01X+031120Y+154048X0100Y0130     S1      
327GND              U6015 -H31 M      A01X+038914Y+151508X0120Y         S1      
327GND              U6015 -J4  M      A01X+038818Y+153606X0150Y         S1      
327GND              U6015 -K2  M      A01X+038798Y+153843X0120Y         S1      
327GND              U6015 -K34 M      A01X+038798Y+151150X0120Y         S1      
327GND              U6015 -L1  M      A01X+038679Y+154048X0100Y0130     S1      
327GND              U6015 -L35 M      A01X+038679Y+150946X0100Y0130     S1      
327GND              U6015 -T32 M      A01X+038346Y+151424X0150Y         S1      
327GND              U6015 -T4  M      A01X+038346Y+153606X0150Y         S1      
327GND              U6015 -U2  M      A01X+038325Y+153843X0120Y         S1      
327GND              U6015 -U34 M      A01X+038325Y+151150X0120Y         S1      
327GND              U6015 -V1  M      A01X+038207Y+154048X0100Y0130     S1      
327GND              C6087 -2          A01X+169510Y+169642X0198Y0197     S1      
317GND              VIA   -    M      A01X+169510Y+169895X0200Y    R090 S2      
017GND              VIA   -    M      A18X+169510Y+169895X0260Y    R090 S2      
017GND                    -    MD0100PA00X+169510Y+169895                       
327GND              C6086 -2          A01X+168473Y+169643X0198Y0197R180 S1      
317GND              VIA   -    M      A01X+168473Y+169895X0200Y    R090 S2      
017GND              VIA   -    M      A18X+168473Y+169895X0260Y    R090 S2      
017GND                    -    MD0100PA00X+168473Y+169895                       
327GND              C9226 -2          A18X+156784Y+057087X0198Y0197R090 S2      
317GND              VIA   -    MD0100PA00X+155189Y+060694X0200Y         S0      
327GND              U324  -S          A18X+155189Y+061030X0320Y0360R270 S2      
317GND              VIA   -    MD0100PA00X+158416Y+055897X0193Y    R270 S0      
317GND              VIA   -    MD0100PA00X+158944Y+055546X0200Y         S0      
317GND              VIA   -    MD0100PA00X+159196Y+055546X0200Y         S0      
317GND              VIA   -    MD0100PA00X+159504Y+055546X0200Y         S0      
317GND              VIA   -    MD0100PA00X+159756Y+055546X0200Y         S0      
317GND              VIA   -    MD0100PA00X+156568Y+056842X0193Y    R270 S0      
317GND              VIA   -    MD0100PA00X+156138Y+057226X0193Y    R270 S0      
317GND              VIA   -    MD0100PA00X+157068Y+056842X0193Y    R270 S0      
317GND              VIA   -    MD0100PA00X+156818Y+056842X0193Y    R270 S0      
327GND              C1227 -2          A01X+156134Y+057462X0198Y0197R270 S1      
327GND              C1331 -2          A01X+156718Y+057189X0400Y0500R090 S1      
327GND              C57   -2          A01X+159040Y+055899X0400Y0500R090 S1      
327GND              C1042 -2          A01X+158408Y+056153X0198Y0197R270 S1      
327GND              C1170 -2          A01X+159750Y+055899X0400Y0500R090 S1      
327GND              Q50   -1          A01X+159041Y+053123X0170Y0200R270 S1      
317GND              VIA   -    MD0100PA00X+159321Y+053123X0200Y    R180 S0      
327GND              Q50   -4          A01X+158293Y+053634X0170Y0200R270 S1      
317GND              VIA   -    MD0100PA00X+157975Y+053634X0200Y    R180 S0      
317GND              VIA   -    MD0100PA00X+167752Y+060945X0200Y    R180 S0      
317GND              VIA   -    MD0100PA00X+167152Y+060945X0200Y    R180 S0      
317GND              VIA   -    MD0100PA00X+167752Y+059996X0200Y    R180 S0      
327GND              PC1845-2          A01X+167302Y+060470X0630Y1190R090 S1      
317GND              VIA   -    M      A01X+167452Y+060945X0200Y    R180 S2      
017GND              VIA   -    M      A18X+167452Y+060945X0260Y    R180 S2      
017GND                    -    MD0100PA00X+167452Y+060945                       
317GND              VIA   -    MD0100PA00X+167152Y+059996X0200Y    R180 S0      
317GND              VIA   -    M      A01X+167452Y+059996X0200Y    R180 S2      
017GND              VIA   -    M      A18X+167452Y+059996X0260Y    R180 S2      
017GND                    -    MD0100PA00X+167452Y+059996                       
317GND              VIA   -    M      A01X+166852Y+060945X0200Y    R180 S2      
017GND              VIA   -    M      A18X+166852Y+060945X0260Y    R180 S2      
017GND                    -    MD0100PA00X+166852Y+060945                       
317GND              VIA   -    M      A01X+166852Y+059996X0200Y    R180 S2      
017GND              VIA   -    M      A18X+166852Y+059996X0260Y    R180 S2      
017GND                    -    MD0100PA00X+166852Y+059996                       
327GND              PC1850-2          A01X+163314Y+052623X0400Y0500R180 S1      
327GND              PC1849-2          A01X+163314Y+053313X0400Y0500R180 S1      
327GND              PC1898-2          A01X+163314Y+054003X0400Y0500R180 S1      
327GND              PC1848-2          A01X+163833Y+055821X0198Y0197R270 S1      
317GND              VIA   -    MD0100PA00X+163580Y+055836X0200Y    R270 S0      
317GND              VIA   -    MD0100PA00X+163880Y+055536X0200Y    R270 S0      
317GND              VIA   -    MD0100PA00X+163580Y+055536X0200Y    R270 S0      
317GND              VIA   -    MD0100PA00X+163580Y+054896X0200Y    R270 S0      
317GND              VIA   -    MD0100PA00X+163580Y+055216X0200Y    R270 S0      
317GND              VIA   -    MD0100PA00X+163880Y+055216X0200Y    R270 S0      
317GND              VIA   -    MD0100PA00X+163880Y+054896X0200Y    R270 S0      
317GND              VIA   -    MD0100PA00X+163880Y+054556X0200Y    R270 S0      
317GND              VIA   -    MD0100PA00X+163580Y+054556X0200Y    R270 S0      
317GND              VIA   -    MD0100PA00X+163280Y+054456X0200Y    R270 S0      
317GND              VIA   -    MD0100PA00X+163678Y+054260X0200Y    R270 S0      
317GND              VIA   -    MD0100PA00X+163693Y+053869X0200Y    R270 S0      
317GND              VIA   -    MD0100PA00X+163693Y+053519X0200Y    R270 S0      
317GND              VIA   -    MD0100PA00X+163693Y+053169X0200Y    R270 S0      
317GND              VIA   -    MD0100PA00X+163987Y+054244X0200Y    R270 S0      
317GND              VIA   -    MD0100PA00X+163693Y+052819X0200Y    R270 S0      
317GND              VIA   -    MD0100PA00X+163693Y+052469X0200Y    R270 S0      
317GND              VIA   -    MD0100PA00X+163189Y+052148X0200Y    R270 S0      
327GND              PC1846-2   M      A01X+162239Y+056680X0198Y0197R180 S1      
317GND              VIA   -    M      A01X+162239Y+056417X0200Y    R270 S2      
017GND              VIA   -    M      A18X+162239Y+056417X0260Y    R270 S2      
017GND                    -    MD0100PA00X+162239Y+056417                       
327GND              PC1648-2          A01X+161888Y+053074X0198Y0197     S1      
317GND              VIA   -    MD0100PA00X+161888Y+053339X0200Y    R270 S0      
327GND              PC1853-2   M      A01X+161037Y+055466X0198Y0197R180 S1      
327GND              PR8091-2   M      A01X+161336Y+055025X0198Y0197R090 S1      
327GND              PR8089-2   M      A01X+161044Y+055909X0198Y0197R180 S1      
317GND              VIA   -    MD0100PA00X+160654Y+055330X0200Y    R270 S0      
327GND              PR3337-2   M      A18X+160737Y+055673X0198Y0197     S2      
317GND              VIA   -    M      A01X+160737Y+056133X0200Y    R270 S2      
017GND              VIA   -    M      A18X+160737Y+056133X0260Y    R270 S2      
017GND                    -    MD0100PA00X+160737Y+056133                       
317GND              VIA   -    MD0100PA00X+040167Y+167792X0200Y         S0      
327GND              Q8000 -4          A18X+040167Y+167534X0170Y0200R090 S2      
317GND              VIA   -    MD0100PA00X+040900Y+166702X0200Y         S0      
327GND              U255  -2          A01X+040900Y+166974X0170Y0240R180 S1      
327GND              Q8000 -1          A18X+039419Y+167022X0170Y0200R090 S2      
317GND              VIA   -    MD0100PA00X+063521Y+172154X0200Y         S0      
327GND              C1707 -2          A01X+063779Y+172154X0198Y0197R090 S1      
327GND              C1973 -2          A01X+065198Y+171714X0198Y0197     S1      
317GND              VIA   -    MD0100PA00X+065453Y+171823X0200Y         S0      
327GND              R3463 -2          A01X+065198Y+172214X0198Y0197     S1      
327GND              R2831 -2          A01X+065198Y+173300X0198Y0197     S1      
317GND              VIA   -    MD0100PA00X+065451Y+172800X0200Y         S0      
327GND              C1773 -2          A01X+065198Y+172800X0198Y0197     S1      
327GND              C185  -2          A18X+023382Y+153796X0120Y0150R090 S2      
327GND              R709  -2          A18X+027685Y+150740X0120Y0150     S2      
317GND              VIA   -    MD0100PA00X+027608Y+150965X0200Y    R090 S0      
327GND              U6014 -EP22M      A01X+018925Y+152220X0120Y         S1      
327GND              U6014 -EG22M      A01X+019398Y+152220X0120Y         S1      
327GND              U6014 -DY22M      A01X+019870Y+152220X0120Y         S1      
327GND              U6014 -DN22M      A01X+020343Y+152220X0120Y         S1      
327GND              U6014 -DF22M      A01X+020815Y+152220X0120Y         S1      
327GND              U6014 -CW22M      A01X+021288Y+152220X0120Y         S1      
327GND              U6014 -CM22M      A01X+021760Y+152220X0120Y         S1      
327GND              U6014 -CE22M      A01X+022232Y+152220X0120Y         S1      
327GND              U6014 -BV22M      A01X+022705Y+152220X0120Y         S1      
327GND              U6014 -BL22M      A01X+023177Y+152220X0120Y         S1      
327GND              U6014 -BD22M      A01X+023650Y+152220X0120Y         S1      
327GND              U6014 -AU22M      A01X+024122Y+152220X0120Y         S1      
327GND              U6014 -AK22M      A01X+024595Y+152220X0120Y         S1      
327GND              U6014 -AC22M      A01X+025067Y+152220X0120Y         S1      
327GND              U6014 -T22 M      A01X+025540Y+152220X0120Y         S1      
327GND              U6014 -T13 M      A01X+025540Y+152811X0120Y         S1      
327GND              U6014 -AC13M      A01X+025067Y+152811X0120Y         S1      
327GND              U6014 -AK13M      A01X+024595Y+152811X0120Y         S1      
327GND              U6014 -AU13M      A01X+024122Y+152811X0120Y         S1      
327GND              U6014 -BD13M      A01X+023650Y+152811X0120Y         S1      
327GND              U6014 -BL13M      A01X+023177Y+152811X0120Y         S1      
317GND              VIA   -    MD0080PA00X+022960Y+152885X0160Y         S0      
327GND              U6014 -BV13M      A01X+022705Y+152811X0120Y         S1      
327GND              U6014 -CE13M      A01X+022232Y+152811X0120Y         S1      
327GND              U6014 -CM13M      A01X+021760Y+152811X0120Y         S1      
327GND              U6014 -CW13M      A01X+021288Y+152811X0120Y         S1      
327GND              U6014 -DF13M      A01X+020815Y+152811X0120Y         S1      
327GND              U6014 -DN13M      A01X+020343Y+152811X0120Y         S1      
327GND              U6014 -DY13M      A01X+019870Y+152811X0120Y         S1      
327GND              U6014 -EG13M      A01X+019398Y+152811X0120Y         S1      
327GND              U6014 -EP13M      A01X+018925Y+152811X0120Y         S1      
317GND              VIA   -    MD0080PA00X+026214Y+152145X0160Y         S0      
317GND              VIA   -    MD0080PA00X+024795Y+152145X0160Y         S0      
317GND              VIA   -    MD0080PA00X+025267Y+152145X0160Y         S0      
317GND              VIA   -    MD0080PA00X+025740Y+152145X0160Y         S0      
317GND              VIA   -    MD0080PA00X+023377Y+152145X0160Y         S0      
317GND              VIA   -    MD0080PA00X+023850Y+152145X0160Y         S0      
317GND              VIA   -    MD0080PA00X+024322Y+152145X0160Y         S0      
317GND              VIA   -    MD0080PA00X+022432Y+152145X0160Y         S0      
317GND              VIA   -    MD0080PA00X+021960Y+152145X0160Y         S0      
317GND              VIA   -    MD0080PA00X+021488Y+152145X0160Y         S0      
317GND              VIA   -    MD0080PA00X+021015Y+152145X0160Y         S0      
317GND              VIA   -    MD0080PA00X+020543Y+152145X0160Y         S0      
317GND              VIA   -    MD0080PA00X+020070Y+152145X0160Y         S0      
317GND              VIA   -    MD0080PA00X+019598Y+152145X0160Y         S0      
317GND              VIA   -    MD0080PA00X+019125Y+152145X0160Y         S0      
317GND              VIA   -    MD0080PA00X+018653Y+152145X0160Y         S0      
317GND              VIA   -    MD0080PA00X+024850Y+152885X0160Y         S0      
327GND              C228  -2          A18X+024850Y+152865X0120Y0150R270 S2      
317GND              VIA   -    MD0080PA00X+025322Y+152885X0160Y         S0      
327GND              C192  -2          A18X+025322Y+152865X0120Y0150R270 S2      
317GND              VIA   -    MD0080PA00X+025795Y+152885X0160Y         S0      
327GND              C253  -2          A18X+025795Y+152865X0120Y0150R270 S2      
317GND              VIA   -    MD0080PA00X+023432Y+152885X0160Y         S0      
327GND              C137  -2          A18X+023432Y+152865X0120Y0150R270 S2      
317GND              VIA   -    MD0080PA00X+023905Y+152885X0160Y         S0      
317GND              VIA   -    MD0080PA00X+024377Y+152885X0160Y         S0      
327GND              C283  -2          A18X+024377Y+152865X0120Y0150R270 S2      
317GND              VIA   -    MD0080PA00X+022488Y+152885X0160Y         S0      
327GND              C129  -2          A18X+022488Y+152865X0120Y0150R270 S2      
317GND              VIA   -    MD0080PA00X+022015Y+152885X0160Y         S0      
327GND              C126  -2          A18X+022015Y+152865X0120Y0150R270 S2      
317GND              VIA   -    MD0080PA00X+021543Y+152885X0160Y         S0      
327GND              C123  -2          A18X+021543Y+152865X0120Y0150R270 S2      
317GND              VIA   -    MD0080PA00X+021070Y+152885X0160Y         S0      
327GND              C189  -2          A18X+021070Y+152865X0120Y0150R270 S2      
317GND              VIA   -    MD0080PA00X+020598Y+152885X0160Y         S0      
327GND              C191  -2          A18X+020598Y+152865X0120Y0150R270 S2      
317GND              VIA   -    MD0080PA00X+020125Y+152885X0160Y         S0      
327GND              C260  -2          A18X+020125Y+152865X0120Y0150R270 S2      
317GND              VIA   -    MD0080PA00X+019653Y+152885X0160Y         S0      
327GND              C184  -2          A18X+019653Y+152865X0120Y0150R270 S2      
317GND              VIA   -    MD0080PA00X+019180Y+152885X0160Y         S0      
327GND              C141  -2          A18X+019180Y+152865X0120Y0150R270 S2      
317GND              VIA   -    MD0080PA00X+018708Y+152885X0160Y         S0      
327GND              C282  -2          A18X+018708Y+152865X0120Y0150R270 S2      
327GND              C135  -2          A18X+018653Y+152165X0120Y0150R090 S2      
327GND              C243  -2          A18X+019125Y+152165X0120Y0150R090 S2      
327GND              C138  -2          A18X+019598Y+152165X0120Y0150R090 S2      
327GND              C265  -2          A18X+020070Y+152165X0120Y0150R090 S2      
327GND              C201  -2          A18X+020543Y+152165X0120Y0150R090 S2      
327GND              C139  -2          A18X+021015Y+152165X0120Y0150R090 S2      
327GND              C134  -2          A18X+021488Y+152165X0120Y0150R090 S2      
327GND              C133  -2          A18X+021960Y+152165X0120Y0150R090 S2      
327GND              C131  -2          A18X+022432Y+152165X0120Y0150R090 S2      
327GND              C188  -2          A18X+025740Y+152165X0120Y0150R090 S2      
327GND              C285  -2          A18X+025267Y+152165X0120Y0150R090 S2      
327GND              C222  -2          A18X+024795Y+152165X0120Y0150R090 S2      
327GND              C190  -2          A18X+024322Y+152165X0120Y0150R090 S2      
327GND              C187  -2          A18X+023850Y+152165X0120Y0150R090 S2      
327GND              C266  -2          A18X+023377Y+152165X0120Y0150R090 S2      
317GND              VIA   -    MD0100PA00X+030726Y+164115X0200Y    R090 S0      
317GND              VIA   -    MD0100PA00X+029732Y+165117X0200Y    R090 S0      
317GND              VIA   -    MD0100PA00X+029732Y+165977X0200Y    R270 S0      
317GND              VIA   -    MD0100PA00X+030726Y+164975X0200Y    R270 S0      
317GND              VIA   -    MD0100PA00X+020380Y+164683X0200Y    R090 S0      
317GND              VIA   -    MD0100PA00X+020797Y+165313X0200Y    R090 S0      
317GND              VIA   -    MD0100PA00X+016311Y+150798X0200Y    R270 S0      
327GND              VIA   -           A18X+025302Y+060757X0260Y    R270 S2      
327GND              PC65  -2          A18X+023443Y+060560X0400Y0500     S2      
327GND              VIA   -           A18X+028586Y+059697X0260Y    R180 S2      
327GND              VIA   -           A18X+025302Y+058757X0260Y    R270 S2      
327GND              PC87  -2          A18X+023442Y+059756X0400Y0500     S2      
327GND              PC84  -2          A18X+023442Y+058946X0400Y0500     S2      
327GND              PR403 -2          A18X+023221Y+058395X0198Y0197R180 S2      
327GND              VIA   -           A18X+020102Y+057147X0260Y    R090 S2      
327GND              VIA   -           A18X+025302Y+056757X0260Y    R180 S2      
327GND              VIA   -           A18X+023302Y+056757X0260Y    R180 S2      
327GND              PC114 -2          A18X+132744Y+061441X0400Y0500     S2      
327GND              PC288 -2          A18X+132938Y+059124X0400Y0500R270 S2      
327GND              PR439 -2          A18X+130782Y+059344X0198Y0197R090 S2      
327GND              PC285 -2          A18X+131323Y+059126X0400Y0500R270 S2      
327GND              PC260 -2          A18X+132133Y+059126X0400Y0500R270 S2      
327GND              PR418 -1          A01X+129491Y+059287X0198Y0197R180 S1      
327GND              PC215 -2          A01X+129889Y+059348X0198Y0197R270 S1      
317GND              VIA   -    MD0100PA00X+130870Y+058780X0200Y    R090 S0      
317GND              VIA   -    MD0100PA00X+132130Y+064000X0200Y    R270 S0      
317GND              VIA   -    MD0100PA00X+132130Y+064300X0200Y    R270 S0      
317GND              VIA   -    MD0100PA00X+132130Y+064600X0200Y    R270 S0      
317GND              VIA   -    MD0100PA00X+132130Y+064900X0200Y    R270 S0      
317GND              VIA   -    MD0100PA00X+131830Y+064600X0200Y    R270 S0      
317GND              VIA   -    MD0100PA00X+131830Y+064300X0200Y    R270 S0      
317GND              VIA   -    MD0100PA00X+131830Y+064000X0200Y    R270 S0      
327GND              R3455 -2          A01X+019892Y+170700X0198Y0197R180 S1      
317GND              VIA   -    MD0100PA00X+019955Y+170460X0200Y         S0      
327GND              PC115 -2          A01X+131350Y+064216X0630Y1190R180 S1      
327GND              PC8003-2          A01X+031796Y+060586X0400Y0500R270 S1      
327GND              PC21  -2          A01X+023221Y+057113X0198Y0197     S1      
327GND              PR399 -1          A01X+023282Y+056715X0198Y0197R270 S1      
317GND              VIA   -    MD0100PA00X+023347Y+060964X0200Y         S0      
317GND              VIA   -    MD0100PA00X+023667Y+060964X0200Y         S0      
317GND              VIA   -    MD0100PA00X+023666Y+060160X0200Y         S0      
317GND              VIA   -    MD0100PA00X+023346Y+060160X0200Y         S0      
327GND              R82   -2          A18X+075115Y+027740X0198Y0197     S2      
317GND              VIA   -    MD0100PA00X+075456Y+028398X0200Y         S0      
317GND              VIA   -    MD0100PA00X+023473Y+058403X0200Y    R180 S0      
317GND              VIA   -    MD0100PA00X+042076Y+163050X0200Y         S0      
317GND              VIA   -    MD0100PA00X+041736Y+163050X0200Y         S0      
327GND              U6014 -E27 M      A01X+026313Y+151863X0120Y         S1      
327GND              U6014 -E33 M      A01X+026313Y+151390X0120Y         S1      
327GND              U6014 -H31 M      A01X+026108Y+151508X0120Y         S1      
327GND              U6014 -K34 M      A01X+025991Y+151150X0120Y         S1      
327GND              U6014 -L35 M      A01X+025873Y+150946X0100Y0130     S1      
327GND              U6014 -AC32M      A01X+025067Y+151424X0150Y         S1      
327GND              U6014 -AC4 M      A01X+025067Y+153606X0150Y         S1      
327GND              U6014 -AD2 M      A01X+025046Y+153843X0120Y         S1      
327GND              U6014 -AD34M      A01X+025046Y+151150X0120Y         S1      
327GND              U6014 -AE1 M      A01X+024928Y+154048X0100Y0130     S1      
327GND              U6014 -AK32M      A01X+024595Y+151424X0150Y         S1      
327GND              U6014 -AK4 M      A01X+024595Y+153606X0150Y         S1      
327GND              U6014 -AL2 M      A01X+024574Y+153843X0120Y         S1      
327GND              U6014 -AL34M      A01X+024574Y+151150X0120Y         S1      
327GND              U6014 -AM1 M      A01X+024456Y+154048X0100Y0130     S1      
327GND              U6014 -AU32M      A01X+024122Y+151424X0150Y         S1      
327GND              U6014 -AV2 M      A01X+024102Y+153843X0120Y         S1      
327GND              U6014 -AW1 M      A01X+023984Y+154048X0100Y0130     S1      
327GND              U6014 -AU4 M      A01X+024122Y+153606X0150Y         S1      
327GND              U6014 -AV34M      A01X+024102Y+151150X0120Y         S1      
327GND              U6014 -BD32M      A01X+023650Y+151424X0150Y         S1      
317GND              VIA   -    MD0080PA00X+024327Y+153606X0160Y    R180 S0      
327GND              U6014 -BD4 M      A01X+023650Y+153606X0150Y         S1      
327GND              U6014 -BE2 M      A01X+023629Y+153843X0120Y         S1      
327GND              U6014 -BE34M      A01X+023629Y+151150X0120Y         S1      
327GND              U6014 -BF1 M      A01X+023511Y+154048X0100Y0130     S1      
327GND              U6014 -BL32M      A01X+023177Y+151424X0150Y         S1      
317GND              VIA   -    MD0080PA00X+023382Y+153606X0160Y    R180 S0      
327GND              U6014 -BL4 M      A01X+023177Y+153606X0150Y         S1      
327GND              U6014 -BM2 M      A01X+023157Y+153843X0120Y         S1      
327GND              U6014 -BM34M      A01X+023157Y+151150X0120Y         S1      
327GND              U6014 -BN1 M      A01X+023039Y+154048X0100Y0130     S1      
327GND              U6014 -BV32M      A01X+022705Y+151424X0150Y         S1      
317GND              VIA   -    MD0080PA00X+022910Y+153606X0160Y    R180 S0      
327GND              U6014 -BV4 M      A01X+022705Y+153606X0150Y         S1      
327GND              U6014 -BW2 M      A01X+022684Y+153843X0120Y         S1      
327GND              U6014 -BW34M      A01X+022684Y+151150X0120Y         S1      
327GND              U6014 -BY1 M      A01X+022566Y+154048X0100Y0130     S1      
327GND              U6014 -CE32M      A01X+022232Y+151424X0150Y         S1      
327GND              U6014 -CE4 M      A01X+022232Y+153606X0150Y         S1      
327GND              U6014 -CF2 M      A01X+022212Y+153843X0120Y         S1      
327GND              U6014 -CF34M      A01X+022212Y+151150X0120Y         S1      
327GND              U6014 -CG1 M      A01X+022094Y+154048X0100Y0130     S1      
327GND              U6014 -CM32M      A01X+021760Y+151424X0150Y         S1      
327GND              U6014 -CM4 M      A01X+021760Y+153606X0150Y         S1      
327GND              U6014 -CN2 M      A01X+021739Y+153843X0120Y         S1      
327GND              U6014 -CN34M      A01X+021739Y+151150X0120Y         S1      
327GND              U6014 -CP1 M      A01X+021621Y+154048X0100Y0130     S1      
317GND              VIA   -    MD0080PA00X+021965Y+153606X0160Y    R180 S0      
327GND              U6014 -CW32M      A01X+021288Y+151424X0150Y         S1      
327GND              U6014 -CW4 M      A01X+021288Y+153606X0150Y         S1      
327GND              U6014 -CY2 M      A01X+021267Y+153843X0120Y         S1      
327GND              U6014 -CY34M      A01X+021267Y+151150X0120Y         S1      
327GND              U6014 -DA1 M      A01X+021149Y+154048X0100Y0130     S1      
327GND              U6014 -DF32M      A01X+020815Y+151424X0150Y         S1      
317GND              VIA   -    MD0080PA00X+021020Y+153606X0160Y    R180 S0      
327GND              U6014 -DF4 M      A01X+020815Y+153606X0150Y         S1      
327GND              U6014 -DG2 M      A01X+020794Y+153843X0120Y         S1      
327GND              U6014 -DG34M      A01X+020794Y+151150X0120Y         S1      
327GND              U6014 -DH1 M      A01X+020676Y+154048X0100Y0130     S1      
327GND              U6014 -DN32M      A01X+020343Y+151424X0150Y         S1      
317GND              VIA   -    MD0080PA00X+020548Y+153606X0160Y    R180 S0      
327GND              U6014 -DN4 M      A01X+020343Y+153606X0150Y         S1      
327GND              U6014 -DP2 M      A01X+020322Y+153843X0120Y         S1      
327GND              U6014 -DP34M      A01X+020322Y+151150X0120Y         S1      
327GND              U6014 -DR1 M      A01X+020204Y+154048X0100Y0130     S1      
327GND              U6014 -DY32M      A01X+019870Y+151424X0150Y         S1      
327GND              U6014 -DY4 M      A01X+019870Y+153606X0150Y         S1      
327GND              U6014 -EA2 M      A01X+019850Y+153843X0120Y         S1      
327GND              U6014 -EA34M      A01X+019850Y+151150X0120Y         S1      
327GND              U6014 -EB1 M      A01X+019732Y+154048X0100Y0130     S1      
327GND              U6014 -EG32M      A01X+019398Y+151424X0150Y         S1      
327GND              U6014 -EH2 M      A01X+019377Y+153843X0120Y         S1      
327GND              U6014 -EJ1 M      A01X+019259Y+154048X0100Y0130     S1      
327GND              U6014 -EG4 M      A01X+019398Y+153606X0150Y         S1      
327GND              U6014 -EH34M      A01X+019377Y+151150X0120Y         S1      
327GND              U6014 -EP32M      A01X+018925Y+151424X0150Y         S1      
327GND              U6014 -EP4 M      A01X+018925Y+153606X0150Y         S1      
327GND              U6014 -ER2 M      A01X+018905Y+153843X0120Y         S1      
327GND              U6014 -ET1 M      A01X+018787Y+154048X0100Y0130     S1      
327GND              U6014 -ER34M      A01X+018905Y+151150X0120Y         S1      
327GND              U6014 -FA15M      A01X+018453Y+152788X0150Y         S1      
327GND              U6014 -FA32M      A01X+018453Y+151424X0150Y         S1      
327GND              U6014 -FB2 M      A01X+018432Y+153843X0120Y         S1      
327GND              U6014 -FB34M      A01X+018432Y+151150X0120Y         S1      
327GND              U6014 -FC19M      A01X+018355Y+152453X0120Y         S1      
327GND              U6014 -FC23M      A01X+018355Y+152217X0120Y         S1      
327GND              U6014 -FC25M      A01X+018355Y+151981X0120Y         S1      
327GND              U6014 -FC28M      A01X+018355Y+151744X0120Y         S1      
327GND              U6014 -FC3 M      A01X+018355Y+153634X0120Y         S1      
327GND              U6014 -FC6 M      A01X+018355Y+153398X0120Y         S1      
327GND              U6014 -FD1 M      A01X+018314Y+154048X0100Y0130     S1      
327GND              U6014 -FF21M      A01X+018150Y+152335X0120Y         S1      
327GND              U6014 -FJ19M      A01X+017946Y+152453X0100Y0130R090 S1      
327GND              U6014 -J4  M      A01X+026012Y+153606X0150Y         S1      
327GND              U6014 -K2  M      A01X+025991Y+153843X0120Y         S1      
327GND              U6014 -L1  M      A01X+025873Y+154048X0100Y0130     S1      
327GND              U6014 -T32 M      A01X+025540Y+151424X0150Y         S1      
317GND              VIA   -    MD0080PA00X+025300Y+151424X0160Y    R180 S0      
327GND              U6014 -T4  M      A01X+025540Y+153606X0150Y         S1      
327GND              U6014 -U2  M      A01X+025519Y+153843X0120Y         S1      
327GND              U6014 -U34 M      A01X+025519Y+151150X0120Y         S1      
327GND              U6014 -V1  M      A01X+025401Y+154048X0100Y0130     S1      
317GND              VIA   -    MD0080PA00X+025272Y+153606X0160Y    R180 S0      
317GND              VIA   -    MD0100PA00X+111783Y+147309X0180Y         S0      
317GND              VIA   -    MD0100PA00X+111795Y+146796X0180Y         S0      
327GND              R4544 -2          A18X+040800Y+163908X0198Y0197R270 S2      
317GND              VIA   -    MD0100PA00X+040608Y+164100X0200Y         S0      
317GND              VIA   -    MD0100PA00X+040062Y+162977X0200Y         S0      
317GND              VIA   -    MD0100PA00X+041544Y+163638X0200Y         S0      
317GND              VIA   -    MD0100PA00X+041696Y+163412X0200Y         S0      
317GND              VIA   -    MD0100PA00X+044878Y+161977X0200Y         S0      
317GND              VIA   -    MD0100PA00X+044878Y+161717X0200Y         S0      
317GND              VIA   -    MD0100PA00X+044878Y+162227X0200Y         S0      
327GND              Q148  -1          A18X+043256Y+163026X0170Y0200R180 S2      
317GND              VIA   -    MD0100PA00X+043256Y+162750X0200Y         S0      
327GND              C1804 -2          A18X+042800Y+164342X0198Y0197R090 S2      
317GND              VIA   -    MD0100PA00X+042800Y+164050X0200Y         S0      
327GND              Q74   -1          A18X+041744Y+164674X0170Y0200     S2      
317GND              VIA   -    MD0100PA00X+041744Y+164395X0200Y         S0      
327GND              R3462 -2          A01X+041392Y+165350X0198Y0197R180 S1      
317GND              VIA   -    MD0100PA00X+041150Y+165350X0200Y         S0      
327GND              C1963 -2          A01X+041700Y+166808X0198Y0197R090 S1      
317GND              VIA   -    M      A01X+042000Y+166808X0200Y         S2      
017GND              VIA   -    M      A18X+042000Y+166808X0260Y         S2      
017GND                    -    MD0100PA00X+042000Y+166808                       
327GND              R3460 -2          A01X+041700Y+168058X0198Y0197R090 S1      
317GND              VIA   -    M      A01X+041700Y+168350X0200Y         S2      
017GND              VIA   -    M      A18X+041700Y+168350X0260Y         S2      
017GND                    -    MD0100PA00X+041700Y+168350                       
327GND              R3489 -2          A01X+040500Y+168058X0198Y0197R090 S1      
317GND              VIA   -    M      A01X+040500Y+168350X0200Y         S2      
017GND              VIA   -    M      A18X+040500Y+168350X0260Y         S2      
017GND                    -    MD0100PA00X+040500Y+168350                       
327GND              Q103  -1          A01X+047556Y+165074X0170Y0200     S1      
317GND              VIA   -    MD0100PA00X+018739Y+162180X0180Y         S0      
317GND              VIA   -    MD0100PA00X+020440Y+162180X0180Y         S0      
317GND              VIA   -    MD0100PA00X+019945Y+162180X0180Y         S0      
317GND              VIA   -    MD0100PA00X+019234Y+162180X0180Y         S0      
317GND              VIA   -    MD0100PA00X+020440Y+162679X0180Y         S0      
317GND              VIA   -    MD0100PA00X+019945Y+162679X0180Y         S0      
317GND              VIA   -    MD0100PA00X+019234Y+162679X0180Y         S0      
317GND              VIA   -    MD0100PA00X+021646Y+162180X0180Y         S0      
317GND              VIA   -    MD0100PA00X+021151Y+162180X0180Y         S0      
317GND              VIA   -    MD0100PA00X+021646Y+162679X0180Y         S0      
317GND              VIA   -    MD0100PA00X+021151Y+162679X0180Y         S0      
317GND              VIA   -    MD0100PA00X+022852Y+162180X0180Y         S0      
317GND              VIA   -    MD0100PA00X+022357Y+162180X0180Y         S0      
317GND              VIA   -    MD0100PA00X+022852Y+162679X0180Y         S0      
317GND              VIA   -    MD0100PA00X+022357Y+162679X0180Y         S0      
317GND              VIA   -    MD0100PA00X+024769Y+162180X0180Y         S0      
317GND              VIA   -    MD0100PA00X+024058Y+162180X0180Y         S0      
317GND              VIA   -    MD0100PA00X+023563Y+162180X0180Y         S0      
317GND              VIA   -    MD0100PA00X+024769Y+162679X0180Y         S0      
317GND              VIA   -    MD0100PA00X+024058Y+162679X0180Y         S0      
317GND              VIA   -    MD0100PA00X+023563Y+162679X0180Y         S0      
317GND              VIA   -    MD0100PA00X+026470Y+162180X0180Y         S0      
317GND              VIA   -    MD0100PA00X+025975Y+162180X0180Y         S0      
317GND              VIA   -    MD0100PA00X+025264Y+162180X0180Y         S0      
317GND              VIA   -    MD0100PA00X+026470Y+162679X0180Y         S0      
317GND              VIA   -    MD0100PA00X+025975Y+162679X0180Y         S0      
317GND              VIA   -    MD0100PA00X+025264Y+162679X0180Y         S0      
317GND              VIA   -    MD0100PA00X+027676Y+162180X0180Y         S0      
317GND              VIA   -    MD0100PA00X+027181Y+162180X0180Y         S0      
317GND              VIA   -    MD0100PA00X+027676Y+162679X0180Y         S0      
317GND              VIA   -    MD0100PA00X+027181Y+162679X0180Y         S0      
317GND              VIA   -    MD0100PA00X+028882Y+162180X0180Y         S0      
317GND              VIA   -    MD0100PA00X+028387Y+162180X0180Y         S0      
317GND              VIA   -    MD0100PA00X+028882Y+162679X0180Y         S0      
317GND              VIA   -    MD0100PA00X+028387Y+162679X0180Y         S0      
317GND              VIA   -    MD0100PA00X+030088Y+162180X0180Y         S0      
317GND              VIA   -    MD0100PA00X+029593Y+162180X0180Y         S0      
317GND              VIA   -    MD0100PA00X+030799Y+162180X0180Y         S0      
317GND              VIA   -    MD0100PA00X+030088Y+162679X0180Y         S0      
317GND              VIA   -    MD0100PA00X+029593Y+162679X0180Y         S0      
317GND              VIA   -    MD0100PA00X+030799Y+162679X0180Y         S0      
317GND              VIA   -    MD0100PA00X+031294Y+162180X0180Y         S0      
317GND              VIA   -    MD0100PA00X+032005Y+162180X0180Y         S0      
317GND              VIA   -    MD0100PA00X+031294Y+162679X0180Y         S0      
317GND              VIA   -    MD0100PA00X+032005Y+162679X0180Y         S0      
317GND              VIA   -    MD0100PA00X+032500Y+162180X0180Y         S0      
317GND              VIA   -    MD0100PA00X+033706Y+162180X0180Y         S0      
317GND              VIA   -    MD0100PA00X+033211Y+162180X0180Y         S0      
317GND              VIA   -    MD0100PA00X+032500Y+162679X0180Y         S0      
317GND              VIA   -    MD0100PA00X+033706Y+162679X0180Y         S0      
317GND              VIA   -    MD0100PA00X+033211Y+162679X0180Y         S0      
317GND              VIA   -    MD0100PA00X+034912Y+162180X0180Y         S0      
317GND              VIA   -    MD0100PA00X+034417Y+162180X0180Y         S0      
317GND              VIA   -    MD0100PA00X+034912Y+162679X0180Y         S0      
317GND              VIA   -    MD0100PA00X+034417Y+162679X0180Y         S0      
317GND              VIA   -    MD0100PA00X+036118Y+162180X0180Y         S0      
317GND              VIA   -    MD0100PA00X+035623Y+162180X0180Y         S0      
317GND              VIA   -    MD0100PA00X+036829Y+162180X0180Y         S0      
317GND              VIA   -    MD0100PA00X+036118Y+162679X0180Y         S0      
317GND              VIA   -    MD0100PA00X+035623Y+162679X0180Y         S0      
317GND              VIA   -    MD0100PA00X+036829Y+162679X0180Y         S0      
317GND              VIA   -    MD0100PA00X+037324Y+162180X0180Y         S0      
317GND              VIA   -    MD0100PA00X+037324Y+162679X0180Y         S0      
327GND              R3502 -2          A18X+046100Y+164708X0198Y0197R270 S2      
327GND              C1802 -2          A01X+046100Y+164708X0198Y0197R090 S1      
317GND              VIA   -    MD0100PA00X+046100Y+165000X0200Y         S0      
327GND              Q75   -4          A01X+044976Y+163756X0170Y0200R270 S1      
317GND              VIA   -    MD0100PA00X+045250Y+163756X0200Y         S0      
327GND              Q75   -1          A01X+045724Y+163244X0170Y0200R270 S1      
317GND              VIA   -    MD0100PA00X+045724Y+162950X0200Y         S0      
317GND              VIA   -    MD0100PA00X+045652Y+162679X0180Y         S0      
317GND              VIA   -    MD0100PA00X+045156Y+162679X0180Y         S0      
317GND              VIA   -    MD0100PA00X+045156Y+162180X0180Y         S0      
317GND              VIA   -    MD0100PA00X+045652Y+162180X0180Y         S0      
327GND              Q103  -4          A01X+047044Y+164326X0170Y0200     S1      
317GND              VIA   -    M      A01X+046835Y+164535X0200Y         S2      
017GND              VIA   -    M      A18X+046835Y+164535X0260Y         S2      
017GND                    -    MD0100PA00X+046835Y+164535                       
327GND              R3431 -2   M      A01X+047558Y+165550X0198Y0197     S1      
317GND              VIA   -    MD0100PA00X+047850Y+165550X0200Y         S0      
327GND              C1975 -2          A01X+046492Y+165550X0198Y0197R180 S1      
317GND              VIA   -    MD0100PA00X+046250Y+165550X0200Y         S0      
327GND              R3457 -2          A01X+046808Y+167600X0198Y0197     S1      
327GND              R3454 -2          A01X+047242Y+167600X0198Y0197R180 S1      
317GND              VIA   -    MD0100PA00X+047050Y+167408X0200Y         S0      
327GND              C1958 -2          A01X+047308Y+168000X0198Y0197     S1      
317GND              VIA   -    M      A01X+047600Y+168000X0200Y         S2      
017GND              VIA   -    M      A18X+047600Y+168000X0260Y         S2      
017GND                    -    MD0100PA00X+047600Y+168000                       
327GND              R3449 -2          A01X+047558Y+170100X0198Y0197     S1      
317GND              VIA   -    M      A01X+047850Y+170100X0200Y         S2      
017GND              VIA   -    M      A18X+047850Y+170100X0260Y         S2      
017GND                    -    MD0100PA00X+047850Y+170100                       
327GND              R3452 -2          A01X+046542Y+170100X0198Y0197R180 S1      
317GND              VIA   -    MD0100PA00X+046250Y+170100X0200Y         S0      
317GND              VIA   -    MD0100PA00X+046473Y+173052X0200Y         S0      
327GND              R3495 -2          A01X+047558Y+171450X0198Y0197     S1      
317GND              VIA   -    M      A01X+047850Y+171450X0200Y         S2      
017GND              VIA   -    M      A18X+047850Y+171450X0260Y         S2      
017GND                    -    MD0100PA00X+047850Y+171450                       
317GND              VIA   -    MD0100PA00X+033022Y+145550X0200Y         S0      
317GND              VIA   -    MD0100PA00X+033500Y+145550X0200Y         S0      
317GND              VIA   -    MD0100PA00X+033022Y+145030X0200Y         S0      
317GND              VIA   -    MD0100PA00X+033500Y+145030X0200Y         S0      
317GND              VIA   -    MD0100PA00X+032831Y+145290X0200Y         S0      
317GND              VIA   -    MD0100PA00X+033691Y+145290X0200Y    R180 S0      
317GND              VIA   -    MD0100PA00X+020694Y+145550X0200Y         S0      
317GND              VIA   -    MD0100PA00X+020216Y+145550X0200Y         S0      
317GND              VIA   -    MD0100PA00X+020885Y+145290X0200Y    R180 S0      
317GND              VIA   -    MD0100PA00X+020025Y+145290X0200Y         S0      
317GND              VIA   -    MD0100PA00X+020694Y+145030X0200Y         S0      
317GND              VIA   -    MD0100PA00X+020216Y+145030X0200Y         S0      
317GND              VIA   -    MD0100PA00X+047111Y+145550X0200Y         S0      
317GND              VIA   -    MD0100PA00X+046633Y+145550X0200Y         S0      
317GND              VIA   -    MD0100PA00X+047302Y+145290X0200Y    R180 S0      
317GND              VIA   -    MD0100PA00X+046442Y+145290X0200Y         S0      
317GND              VIA   -    MD0100PA00X+047111Y+145030X0200Y         S0      
317GND              VIA   -    MD0100PA00X+046633Y+145030X0200Y         S0      
317GND              VIA   -    MD0100PA00X+059918Y+145550X0200Y         S0      
317GND              VIA   -    MD0100PA00X+059440Y+145550X0200Y         S0      
317GND              VIA   -    MD0100PA00X+060109Y+145290X0200Y    R180 S0      
317GND              VIA   -    MD0100PA00X+059249Y+145290X0200Y         S0      
317GND              VIA   -    MD0100PA00X+059918Y+145030X0200Y         S0      
317GND              VIA   -    MD0100PA00X+059440Y+145030X0200Y         S0      
317GND              VIA   -    MD0100PA00X+121481Y+148850X0200Y         S0      
317GND              VIA   -    MD0100PA00X+121003Y+148850X0200Y         S0      
317GND              VIA   -    MD0100PA00X+121672Y+148590X0200Y    R180 S0      
317GND              VIA   -    MD0100PA00X+120812Y+148590X0200Y         S0      
317GND              VIA   -    MD0100PA00X+121481Y+148330X0200Y         S0      
317GND              VIA   -    MD0100PA00X+121003Y+148330X0200Y         S0      
317GND              VIA   -    MD0100PA00X+134288Y+148850X0200Y         S0      
317GND              VIA   -    MD0100PA00X+133810Y+148850X0200Y         S0      
317GND              VIA   -    MD0100PA00X+134479Y+148590X0200Y    R180 S0      
317GND              VIA   -    MD0100PA00X+133619Y+148590X0200Y         S0      
317GND              VIA   -    MD0100PA00X+134288Y+148330X0200Y         S0      
317GND              VIA   -    MD0100PA00X+133810Y+148330X0200Y         S0      
317GND              VIA   -    MD0100PA00X+147899Y+148850X0200Y         S0      
317GND              VIA   -    MD0100PA00X+147421Y+148850X0200Y         S0      
317GND              VIA   -    MD0100PA00X+148090Y+148590X0200Y    R180 S0      
317GND              VIA   -    MD0100PA00X+147230Y+148590X0200Y         S0      
317GND              VIA   -    MD0100PA00X+147899Y+148330X0200Y         S0      
317GND              VIA   -    MD0100PA00X+147421Y+148330X0200Y         S0      
317GND              VIA   -    MD0100PA00X+160705Y+148850X0200Y         S0      
317GND              VIA   -    MD0100PA00X+160227Y+148850X0200Y         S0      
317GND              VIA   -    MD0100PA00X+160896Y+148590X0200Y    R180 S0      
317GND              VIA   -    MD0100PA00X+160036Y+148590X0200Y         S0      
317GND              VIA   -    MD0100PA00X+160705Y+148330X0200Y         S0      
317GND              VIA   -    MD0100PA00X+160227Y+148330X0200Y         S0      
317GND              VIA   -    MD0100PA00X+029118Y+150799X0200Y    R270 S0      
317GND              VIA   -    MD0100PA00X+029378Y+147950X0200Y    R270 S0      
317GND              VIA   -    MD0100PA00X+029378Y+148428X0200Y    R270 S0      
317GND              VIA   -    MD0100PA00X+029378Y+150130X0200Y    R270 S0      
317GND              VIA   -    MD0100PA00X+029378Y+150608X0200Y    R270 S0      
317GND              VIA   -    MD0100PA00X+028858Y+147950X0200Y    R270 S0      
317GND              VIA   -    MD0100PA00X+028858Y+148428X0200Y    R270 S0      
317GND              VIA   -    MD0100PA00X+028858Y+150130X0200Y    R270 S0      
317GND              VIA   -    MD0100PA00X+028858Y+150608X0200Y    R270 S0      
317GND              VIA   -    MD0100PA00X+029118Y+147759X0200Y    R090 S0      
317GND              VIA   -    MD0100PA00X+029118Y+148619X0200Y    R270 S0      
317GND              VIA   -    MD0100PA00X+029118Y+149949X0200Y    R090 S0      
317GND              VIA   -    MD0100PA00X+032160Y+147490X0200Y         S0      
317GND              VIA   -    MD0100PA00X+031682Y+147490X0200Y         S0      
317GND              VIA   -    MD0100PA00X+034362Y+147490X0200Y         S0      
317GND              VIA   -    MD0100PA00X+034840Y+147490X0200Y         S0      
317GND              VIA   -    MD0100PA00X+037042Y+147490X0200Y         S0      
317GND              VIA   -    MD0100PA00X+037520Y+147490X0200Y         S0      
317GND              VIA   -    MD0100PA00X+032160Y+146970X0200Y         S0      
317GND              VIA   -    MD0100PA00X+031682Y+146970X0200Y         S0      
317GND              VIA   -    MD0100PA00X+034362Y+146970X0200Y         S0      
317GND              VIA   -    MD0100PA00X+034840Y+146970X0200Y         S0      
317GND              VIA   -    MD0100PA00X+037042Y+146970X0200Y         S0      
317GND              VIA   -    MD0100PA00X+037520Y+146970X0200Y         S0      
317GND              VIA   -    MD0100PA00X+029672Y+146520X0200Y         S0      
317GND              VIA   -    MD0100PA00X+030150Y+146520X0200Y         S0      
317GND              VIA   -    MD0100PA00X+032830Y+146520X0200Y         S0      
317GND              VIA   -    MD0100PA00X+032352Y+146520X0200Y         S0      
317GND              VIA   -    MD0100PA00X+035510Y+146520X0200Y         S0      
317GND              VIA   -    MD0100PA00X+035032Y+146520X0200Y         S0      
317GND              VIA   -    MD0100PA00X+038190Y+146520X0200Y         S0      
317GND              VIA   -    MD0100PA00X+037712Y+146520X0200Y         S0      
317GND              VIA   -    MD0100PA00X+029672Y+146000X0200Y         S0      
317GND              VIA   -    MD0100PA00X+030150Y+146000X0200Y         S0      
317GND              VIA   -    MD0100PA00X+032830Y+146000X0200Y         S0      
317GND              VIA   -    MD0100PA00X+032352Y+146000X0200Y         S0      
317GND              VIA   -    MD0100PA00X+035510Y+146000X0200Y         S0      
317GND              VIA   -    MD0100PA00X+035032Y+146000X0200Y         S0      
317GND              VIA   -    MD0100PA00X+038190Y+146000X0200Y         S0      
317GND              VIA   -    MD0100PA00X+037712Y+146000X0200Y         S0      
317GND              VIA   -    MD0100PA00X+030820Y+145550X0200Y         S0      
317GND              VIA   -    MD0100PA00X+030342Y+145550X0200Y         S0      
317GND              VIA   -    MD0100PA00X+035702Y+145550X0200Y         S0      
317GND              VIA   -    MD0100PA00X+036180Y+145550X0200Y         S0      
317GND              VIA   -    MD0100PA00X+038860Y+145550X0200Y         S0      
317GND              VIA   -    MD0100PA00X+038382Y+145550X0200Y         S0      
317GND              VIA   -    MD0100PA00X+040200Y+145550X0200Y         S0      
317GND              VIA   -    MD0100PA00X+039722Y+145550X0200Y         S0      
317GND              VIA   -    MD0100PA00X+030820Y+145030X0200Y         S0      
317GND              VIA   -    MD0100PA00X+030342Y+145030X0200Y         S0      
317GND              VIA   -    MD0100PA00X+035702Y+145030X0200Y         S0      
317GND              VIA   -    MD0100PA00X+036180Y+145030X0200Y         S0      
317GND              VIA   -    MD0100PA00X+038860Y+145030X0200Y         S0      
317GND              VIA   -    MD0100PA00X+038382Y+145030X0200Y         S0      
317GND              VIA   -    MD0100PA00X+040200Y+145030X0200Y         S0      
317GND              VIA   -    MD0100PA00X+039722Y+145030X0200Y         S0      
317GND              VIA   -    MD0100PA00X+029481Y+146260X0200Y         S0      
317GND              VIA   -    MD0100PA00X+030151Y+145290X0200Y         S0      
317GND              VIA   -    MD0100PA00X+031011Y+145290X0200Y    R180 S0      
317GND              VIA   -    MD0100PA00X+030341Y+146260X0200Y    R180 S0      
317GND              VIA   -    MD0100PA00X+032161Y+146260X0200Y         S0      
317GND              VIA   -    MD0100PA00X+033021Y+146260X0200Y    R180 S0      
317GND              VIA   -    MD0100PA00X+031491Y+147230X0200Y         S0      
317GND              VIA   -    MD0100PA00X+032831Y+147230X0200Y         S0      
317GND              VIA   -    MD0100PA00X+032351Y+147230X0200Y    R180 S0      
317GND              VIA   -    MD0100PA00X+034171Y+147230X0200Y         S0      
317GND              VIA   -    MD0100PA00X+035031Y+147230X0200Y    R180 S0      
317GND              VIA   -    MD0100PA00X+036851Y+147230X0200Y         S0      
317GND              VIA   -    MD0100PA00X+034841Y+146260X0200Y         S0      
317GND              VIA   -    MD0100PA00X+035701Y+146260X0200Y    R180 S0      
317GND              VIA   -    MD0100PA00X+037521Y+146260X0200Y         S0      
317GND              VIA   -    MD0100PA00X+035511Y+145290X0200Y         S0      
317GND              VIA   -    MD0100PA00X+036371Y+145290X0200Y    R180 S0      
317GND              VIA   -    MD0100PA00X+038191Y+145290X0200Y         S0      
317GND              VIA   -    MD0100PA00X+039531Y+145290X0200Y         S0      
317GND              VIA   -    MD0100PA00X+039051Y+145290X0200Y    R180 S0      
317GND              VIA   -    MD0100PA00X+038381Y+146260X0200Y    R180 S0      
317GND              VIA   -    MD0100PA00X+040391Y+145290X0200Y    R180 S0      
317GND              VIA   -    MD0100PA00X+037711Y+147230X0200Y    R180 S0      
317GND              VIA   -    MD0100PA00X+040608Y+149339X0200Y    R090 S0      
317GND              VIA   -    MD0100PA00X+040608Y+148477X0200Y    R090 S0      
317GND              VIA   -    MD0100PA00X+040608Y+147999X0200Y    R090 S0      
317GND              VIA   -    MD0100PA00X+040608Y+149817X0200Y    R090 S0      
317GND              VIA   -    MD0100PA00X+041128Y+149339X0200Y    R090 S0      
317GND              VIA   -    MD0100PA00X+041128Y+148477X0200Y    R090 S0      
317GND              VIA   -    MD0100PA00X+041128Y+147999X0200Y    R090 S0      
317GND              VIA   -    MD0100PA00X+041128Y+149817X0200Y    R090 S0      
317GND              VIA   -    MD0100PA00X+040868Y+149148X0200Y    R090 S0      
317GND              VIA   -    MD0100PA00X+040868Y+148668X0200Y    R270 S0      
317GND              VIA   -    MD0100PA00X+040868Y+150008X0200Y    R270 S0      
317GND              VIA   -    MD0100PA00X+040868Y+147808X0200Y    R090 S0      
317GND              VIA   -    MD0100PA00X+042729Y+150799X0200Y    R270 S0      
317GND              VIA   -    MD0100PA00X+042989Y+147950X0200Y    R270 S0      
317GND              VIA   -    MD0100PA00X+042989Y+148428X0200Y    R270 S0      
317GND              VIA   -    MD0100PA00X+042989Y+150130X0200Y    R270 S0      
317GND              VIA   -    MD0100PA00X+042989Y+150608X0200Y    R270 S0      
317GND              VIA   -    MD0100PA00X+042469Y+147950X0200Y    R270 S0      
317GND              VIA   -    MD0100PA00X+042469Y+148428X0200Y    R270 S0      
317GND              VIA   -    MD0100PA00X+042469Y+150130X0200Y    R270 S0      
317GND              VIA   -    MD0100PA00X+042469Y+150608X0200Y    R270 S0      
317GND              VIA   -    MD0100PA00X+042729Y+147759X0200Y    R090 S0      
317GND              VIA   -    MD0100PA00X+042729Y+148619X0200Y    R270 S0      
317GND              VIA   -    MD0100PA00X+042729Y+149949X0200Y    R090 S0      
317GND              VIA   -    MD0100PA00X+045771Y+147490X0200Y         S0      
317GND              VIA   -    MD0100PA00X+045293Y+147490X0200Y         S0      
317GND              VIA   -    MD0100PA00X+047973Y+147490X0200Y         S0      
317GND              VIA   -    MD0100PA00X+048451Y+147490X0200Y         S0      
317GND              VIA   -    MD0100PA00X+050653Y+147490X0200Y         S0      
317GND              VIA   -    MD0100PA00X+051131Y+147490X0200Y         S0      
317GND              VIA   -    MD0100PA00X+045771Y+146970X0200Y         S0      
317GND              VIA   -    MD0100PA00X+045293Y+146970X0200Y         S0      
317GND              VIA   -    MD0100PA00X+047973Y+146970X0200Y         S0      
317GND              VIA   -    MD0100PA00X+048451Y+146970X0200Y         S0      
317GND              VIA   -    MD0100PA00X+050653Y+146970X0200Y         S0      
317GND              VIA   -    MD0100PA00X+051131Y+146970X0200Y         S0      
317GND              VIA   -    MD0100PA00X+043283Y+146520X0200Y         S0      
317GND              VIA   -    MD0100PA00X+043761Y+146520X0200Y         S0      
317GND              VIA   -    MD0100PA00X+046441Y+146520X0200Y         S0      
317GND              VIA   -    MD0100PA00X+045963Y+146520X0200Y         S0      
317GND              VIA   -    MD0100PA00X+049121Y+146520X0200Y         S0      
317GND              VIA   -    MD0100PA00X+048643Y+146520X0200Y         S0      
317GND              VIA   -    MD0100PA00X+051801Y+146520X0200Y         S0      
317GND              VIA   -    MD0100PA00X+051323Y+146520X0200Y         S0      
317GND              VIA   -    MD0100PA00X+043283Y+146000X0200Y         S0      
317GND              VIA   -    MD0100PA00X+043761Y+146000X0200Y         S0      
317GND              VIA   -    MD0100PA00X+046441Y+146000X0200Y         S0      
317GND              VIA   -    MD0100PA00X+045963Y+146000X0200Y         S0      
317GND              VIA   -    MD0100PA00X+049121Y+146000X0200Y         S0      
317GND              VIA   -    MD0100PA00X+048643Y+146000X0200Y         S0      
317GND              VIA   -    MD0100PA00X+051801Y+146000X0200Y         S0      
317GND              VIA   -    MD0100PA00X+051323Y+146000X0200Y         S0      
317GND              VIA   -    MD0100PA00X+044431Y+145550X0200Y         S0      
317GND              VIA   -    MD0100PA00X+043953Y+145550X0200Y         S0      
317GND              VIA   -    MD0100PA00X+049313Y+145550X0200Y         S0      
317GND              VIA   -    MD0100PA00X+049791Y+145550X0200Y         S0      
317GND              VIA   -    MD0100PA00X+052471Y+145550X0200Y         S0      
317GND              VIA   -    MD0100PA00X+051993Y+145550X0200Y         S0      
317GND              VIA   -    MD0100PA00X+053811Y+145550X0200Y         S0      
317GND              VIA   -    MD0100PA00X+053333Y+145550X0200Y         S0      
317GND              VIA   -    MD0100PA00X+044431Y+145030X0200Y         S0      
317GND              VIA   -    MD0100PA00X+043953Y+145030X0200Y         S0      
317GND              VIA   -    MD0100PA00X+049313Y+145030X0200Y         S0      
317GND              VIA   -    MD0100PA00X+049791Y+145030X0200Y         S0      
317GND              VIA   -    MD0100PA00X+052471Y+145030X0200Y         S0      
317GND              VIA   -    MD0100PA00X+051993Y+145030X0200Y         S0      
317GND              VIA   -    MD0100PA00X+053811Y+145030X0200Y         S0      
317GND              VIA   -    MD0100PA00X+053333Y+145030X0200Y         S0      
317GND              VIA   -    MD0100PA00X+043092Y+146260X0200Y         S0      
317GND              VIA   -    MD0100PA00X+043762Y+145290X0200Y         S0      
317GND              VIA   -    MD0100PA00X+044622Y+145290X0200Y    R180 S0      
317GND              VIA   -    MD0100PA00X+043952Y+146260X0200Y    R180 S0      
317GND              VIA   -    MD0100PA00X+045772Y+146260X0200Y         S0      
317GND              VIA   -    MD0100PA00X+046632Y+146260X0200Y    R180 S0      
317GND              VIA   -    MD0100PA00X+045102Y+147230X0200Y         S0      
317GND              VIA   -    MD0100PA00X+045962Y+147230X0200Y    R180 S0      
317GND              VIA   -    MD0100PA00X+047782Y+147230X0200Y         S0      
317GND              VIA   -    MD0100PA00X+048642Y+147230X0200Y    R180 S0      
317GND              VIA   -    MD0100PA00X+050462Y+147230X0200Y         S0      
317GND              VIA   -    MD0100PA00X+048452Y+146260X0200Y         S0      
317GND              VIA   -    MD0100PA00X+049312Y+146260X0200Y    R180 S0      
317GND              VIA   -    MD0100PA00X+051132Y+146260X0200Y         S0      
317GND              VIA   -    MD0100PA00X+049122Y+145290X0200Y         S0      
317GND              VIA   -    MD0100PA00X+049982Y+145290X0200Y    R180 S0      
317GND              VIA   -    MD0100PA00X+051802Y+145290X0200Y         S0      
317GND              VIA   -    MD0100PA00X+053142Y+145290X0200Y         S0      
317GND              VIA   -    MD0100PA00X+052662Y+145290X0200Y    R180 S0      
317GND              VIA   -    MD0100PA00X+051992Y+146260X0200Y    R180 S0      
317GND              VIA   -    MD0100PA00X+054002Y+145290X0200Y    R180 S0      
317GND              VIA   -    MD0100PA00X+051322Y+147230X0200Y    R180 S0      
317GND              VIA   -    MD0100PA00X+054219Y+149339X0200Y    R090 S0      
317GND              VIA   -    MD0100PA00X+054219Y+148477X0200Y    R090 S0      
317GND              VIA   -    MD0100PA00X+054219Y+147999X0200Y    R090 S0      
317GND              VIA   -    MD0100PA00X+054219Y+149817X0200Y    R090 S0      
317GND              VIA   -    MD0100PA00X+054739Y+149339X0200Y    R090 S0      
317GND              VIA   -    MD0100PA00X+054739Y+148477X0200Y    R090 S0      
317GND              VIA   -    MD0100PA00X+054739Y+147999X0200Y    R090 S0      
317GND              VIA   -    MD0100PA00X+054739Y+149817X0200Y    R090 S0      
317GND              VIA   -    MD0100PA00X+053769Y+150487X0200Y    R090 S0      
317GND              VIA   -    MD0100PA00X+054479Y+148668X0200Y    R270 S0      
317GND              VIA   -    MD0100PA00X+054479Y+150008X0200Y    R270 S0      
317GND              VIA   -    MD0100PA00X+054479Y+147808X0200Y    R090 S0      
317GND              VIA   -    MD0100PA00X+055535Y+150799X0200Y    R270 S0      
317GND              VIA   -    MD0100PA00X+055795Y+147950X0200Y    R270 S0      
317GND              VIA   -    MD0100PA00X+055795Y+148428X0200Y    R270 S0      
317GND              VIA   -    MD0100PA00X+055795Y+150130X0200Y    R270 S0      
317GND              VIA   -    MD0100PA00X+055795Y+150608X0200Y    R270 S0      
317GND              VIA   -    MD0100PA00X+055275Y+147950X0200Y    R270 S0      
317GND              VIA   -    MD0100PA00X+055275Y+148428X0200Y    R270 S0      
317GND              VIA   -    MD0100PA00X+055275Y+150130X0200Y    R270 S0      
317GND              VIA   -    MD0100PA00X+055275Y+150608X0200Y    R270 S0      
317GND              VIA   -    MD0100PA00X+055535Y+147759X0200Y    R090 S0      
317GND              VIA   -    MD0100PA00X+055535Y+148619X0200Y    R270 S0      
317GND              VIA   -    MD0100PA00X+055535Y+149949X0200Y    R090 S0      
317GND              VIA   -    MD0100PA00X+058578Y+147490X0200Y         S0      
317GND              VIA   -    MD0100PA00X+058100Y+147490X0200Y         S0      
317GND              VIA   -    MD0100PA00X+060780Y+147490X0200Y         S0      
317GND              VIA   -    MD0100PA00X+061258Y+147490X0200Y         S0      
317GND              VIA   -    MD0100PA00X+063460Y+147490X0200Y         S0      
317GND              VIA   -    MD0100PA00X+063938Y+147490X0200Y         S0      
317GND              VIA   -    MD0100PA00X+058578Y+146970X0200Y         S0      
317GND              VIA   -    MD0100PA00X+058100Y+146970X0200Y         S0      
317GND              VIA   -    MD0100PA00X+060780Y+146970X0200Y         S0      
317GND              VIA   -    MD0100PA00X+061258Y+146970X0200Y         S0      
317GND              VIA   -    MD0100PA00X+063460Y+146970X0200Y         S0      
317GND              VIA   -    MD0100PA00X+063938Y+146970X0200Y         S0      
317GND              VIA   -    MD0100PA00X+056090Y+146520X0200Y         S0      
317GND              VIA   -    MD0100PA00X+056568Y+146520X0200Y         S0      
317GND              VIA   -    MD0100PA00X+059248Y+146520X0200Y         S0      
317GND              VIA   -    MD0100PA00X+058770Y+146520X0200Y         S0      
317GND              VIA   -    MD0100PA00X+061928Y+146520X0200Y         S0      
317GND              VIA   -    MD0100PA00X+061450Y+146520X0200Y         S0      
317GND              VIA   -    MD0100PA00X+064608Y+146520X0200Y         S0      
317GND              VIA   -    MD0100PA00X+064130Y+146520X0200Y         S0      
317GND              VIA   -    MD0100PA00X+056090Y+146000X0200Y         S0      
317GND              VIA   -    MD0100PA00X+056568Y+146000X0200Y         S0      
317GND              VIA   -    MD0100PA00X+059248Y+146000X0200Y         S0      
317GND              VIA   -    MD0100PA00X+058770Y+146000X0200Y         S0      
317GND              VIA   -    MD0100PA00X+061928Y+146000X0200Y         S0      
317GND              VIA   -    MD0100PA00X+061450Y+146000X0200Y         S0      
317GND              VIA   -    MD0100PA00X+064608Y+146000X0200Y         S0      
317GND              VIA   -    MD0100PA00X+064130Y+146000X0200Y         S0      
317GND              VIA   -    MD0100PA00X+057238Y+145550X0200Y         S0      
317GND              VIA   -    MD0100PA00X+056760Y+145550X0200Y         S0      
317GND              VIA   -    MD0100PA00X+062120Y+145550X0200Y         S0      
317GND              VIA   -    MD0100PA00X+062598Y+145550X0200Y         S0      
317GND              VIA   -    MD0100PA00X+065278Y+145550X0200Y         S0      
317GND              VIA   -    MD0100PA00X+064800Y+145550X0200Y         S0      
317GND              VIA   -    MD0100PA00X+066618Y+145550X0200Y         S0      
317GND              VIA   -    MD0100PA00X+066140Y+145550X0200Y         S0      
317GND              VIA   -    MD0100PA00X+057238Y+145030X0200Y         S0      
317GND              VIA   -    MD0100PA00X+056760Y+145030X0200Y         S0      
317GND              VIA   -    MD0100PA00X+062120Y+145030X0200Y         S0      
317GND              VIA   -    MD0100PA00X+062598Y+145030X0200Y         S0      
317GND              VIA   -    MD0100PA00X+065278Y+145030X0200Y         S0      
317GND              VIA   -    MD0100PA00X+064800Y+145030X0200Y         S0      
317GND              VIA   -    MD0100PA00X+066618Y+145030X0200Y         S0      
317GND              VIA   -    MD0100PA00X+066140Y+145030X0200Y         S0      
317GND              VIA   -    MD0100PA00X+055899Y+146260X0200Y         S0      
317GND              VIA   -    MD0100PA00X+056569Y+145290X0200Y         S0      
317GND              VIA   -    MD0100PA00X+057429Y+145290X0200Y    R180 S0      
317GND              VIA   -    MD0100PA00X+056759Y+146260X0200Y    R180 S0      
317GND              VIA   -    MD0100PA00X+058579Y+146260X0200Y         S0      
317GND              VIA   -    MD0100PA00X+059439Y+146260X0200Y    R180 S0      
317GND              VIA   -    MD0100PA00X+057909Y+147230X0200Y         S0      
317GND              VIA   -    MD0100PA00X+058769Y+147230X0200Y    R180 S0      
317GND              VIA   -    MD0100PA00X+060589Y+147230X0200Y         S0      
317GND              VIA   -    MD0100PA00X+061449Y+147230X0200Y    R180 S0      
317GND              VIA   -    MD0100PA00X+063269Y+147230X0200Y         S0      
317GND              VIA   -    MD0100PA00X+061259Y+146260X0200Y         S0      
317GND              VIA   -    MD0100PA00X+062119Y+146260X0200Y    R180 S0      
317GND              VIA   -    MD0100PA00X+063939Y+146260X0200Y         S0      
317GND              VIA   -    MD0100PA00X+061929Y+145290X0200Y         S0      
317GND              VIA   -    MD0100PA00X+062789Y+145290X0200Y    R180 S0      
317GND              VIA   -    MD0100PA00X+064609Y+145290X0200Y         S0      
317GND              VIA   -    MD0100PA00X+065949Y+145290X0200Y         S0      
317GND              VIA   -    MD0100PA00X+065469Y+145290X0200Y    R180 S0      
317GND              VIA   -    MD0100PA00X+064799Y+146260X0200Y    R180 S0      
317GND              VIA   -    MD0100PA00X+066809Y+145290X0200Y    R180 S0      
317GND              VIA   -    MD0100PA00X+064129Y+147230X0200Y    R180 S0      
317GND              VIA   -    MD0100PA00X+067026Y+149339X0200Y    R090 S0      
317GND              VIA   -    MD0100PA00X+067026Y+148477X0200Y    R090 S0      
317GND              VIA   -    MD0100PA00X+067026Y+147999X0200Y    R090 S0      
317GND              VIA   -    MD0100PA00X+067026Y+149817X0200Y    R090 S0      
317GND              VIA   -    MD0100PA00X+067546Y+149339X0200Y    R090 S0      
317GND              VIA   -    MD0100PA00X+067546Y+148477X0200Y    R090 S0      
317GND              VIA   -    MD0100PA00X+067511Y+147960X0200Y    R090 S0      
317GND              VIA   -    MD0100PA00X+067546Y+149817X0200Y    R090 S0      
317GND              VIA   -    MD0100PA00X+066576Y+150487X0200Y    R090 S0      
317GND              VIA   -    MD0100PA00X+067286Y+149148X0200Y    R090 S0      
317GND              VIA   -    MD0100PA00X+067286Y+148668X0200Y    R270 S0      
317GND              VIA   -    MD0100PA00X+067286Y+150008X0200Y    R270 S0      
317GND              VIA   -    MD0100PA00X+067286Y+147808X0200Y    R090 S0      
317GND              VIA   -    MD0100PA00X+117099Y+154099X0200Y    R270 S0      
317GND              VIA   -    MD0100PA00X+117359Y+151250X0200Y    R270 S0      
317GND              VIA   -    MD0100PA00X+117359Y+151728X0200Y    R270 S0      
317GND              VIA   -    MD0100PA00X+117359Y+153908X0200Y    R270 S0      
317GND              VIA   -    MD0100PA00X+116839Y+151250X0200Y    R270 S0      
317GND              VIA   -    MD0100PA00X+116839Y+151728X0200Y    R270 S0      
317GND              VIA   -    MD0100PA00X+116839Y+153430X0200Y    R270 S0      
317GND              VIA   -    MD0100PA00X+116839Y+153908X0200Y    R270 S0      
317GND              VIA   -    MD0100PA00X+117099Y+151059X0200Y    R090 S0      
317GND              VIA   -    MD0100PA00X+117099Y+151919X0200Y    R270 S0      
317GND              VIA   -    MD0100PA00X+117099Y+153249X0200Y    R090 S0      
317GND              VIA   -    MD0100PA00X+120141Y+150790X0200Y         S0      
317GND              VIA   -    MD0100PA00X+119663Y+150790X0200Y         S0      
317GND              VIA   -    MD0100PA00X+122343Y+150790X0200Y         S0      
317GND              VIA   -    MD0100PA00X+125023Y+150790X0200Y         S0      
317GND              VIA   -    MD0100PA00X+125501Y+150790X0200Y         S0      
317GND              VIA   -    MD0100PA00X+120141Y+150270X0200Y         S0      
317GND              VIA   -    MD0100PA00X+119663Y+150270X0200Y         S0      
317GND              VIA   -    MD0100PA00X+122343Y+150270X0200Y         S0      
317GND              VIA   -    MD0100PA00X+122821Y+150270X0200Y         S0      
317GND              VIA   -    MD0100PA00X+125023Y+150270X0200Y         S0      
317GND              VIA   -    MD0100PA00X+125501Y+150270X0200Y         S0      
317GND              VIA   -    MD0100PA00X+117653Y+149820X0200Y         S0      
317GND              VIA   -    MD0100PA00X+118131Y+149820X0200Y         S0      
317GND              VIA   -    MD0100PA00X+120811Y+149820X0200Y         S0      
317GND              VIA   -    MD0100PA00X+120333Y+149820X0200Y         S0      
317GND              VIA   -    MD0100PA00X+123491Y+149820X0200Y         S0      
317GND              VIA   -    MD0100PA00X+123013Y+149820X0200Y         S0      
317GND              VIA   -    MD0100PA00X+126171Y+149820X0200Y         S0      
317GND              VIA   -    MD0100PA00X+125693Y+149820X0200Y         S0      
317GND              VIA   -    MD0100PA00X+117653Y+149300X0200Y         S0      
317GND              VIA   -    MD0100PA00X+118131Y+149300X0200Y         S0      
317GND              VIA   -    MD0100PA00X+120811Y+149300X0200Y         S0      
317GND              VIA   -    MD0100PA00X+120333Y+149300X0200Y         S0      
317GND              VIA   -    MD0100PA00X+123491Y+149300X0200Y         S0      
317GND              VIA   -    MD0100PA00X+123013Y+149300X0200Y         S0      
317GND              VIA   -    MD0100PA00X+126171Y+149300X0200Y         S0      
317GND              VIA   -    MD0100PA00X+125693Y+149300X0200Y         S0      
317GND              VIA   -    MD0100PA00X+118801Y+148850X0200Y         S0      
317GND              VIA   -    MD0100PA00X+118323Y+148850X0200Y         S0      
317GND              VIA   -    MD0100PA00X+123683Y+148850X0200Y         S0      
317GND              VIA   -    MD0100PA00X+124161Y+148850X0200Y         S0      
317GND              VIA   -    MD0100PA00X+126841Y+148850X0200Y         S0      
317GND              VIA   -    MD0100PA00X+126363Y+148850X0200Y         S0      
317GND              VIA   -    MD0100PA00X+128181Y+148850X0200Y         S0      
317GND              VIA   -    MD0100PA00X+127703Y+148850X0200Y         S0      
317GND              VIA   -    MD0100PA00X+118801Y+148330X0200Y         S0      
317GND              VIA   -    MD0100PA00X+118323Y+148330X0200Y         S0      
317GND              VIA   -    MD0100PA00X+123683Y+148330X0200Y         S0      
317GND              VIA   -    MD0100PA00X+124161Y+148330X0200Y         S0      
317GND              VIA   -    MD0100PA00X+126841Y+148330X0200Y         S0      
317GND              VIA   -    MD0100PA00X+126363Y+148330X0200Y         S0      
317GND              VIA   -    MD0100PA00X+128181Y+148330X0200Y         S0      
317GND              VIA   -    MD0100PA00X+127703Y+148330X0200Y         S0      
317GND              VIA   -    MD0100PA00X+117462Y+149560X0200Y         S0      
317GND              VIA   -    MD0100PA00X+118132Y+148590X0200Y         S0      
317GND              VIA   -    MD0100PA00X+118992Y+148590X0200Y    R180 S0      
317GND              VIA   -    MD0100PA00X+118322Y+149560X0200Y    R180 S0      
317GND              VIA   -    MD0100PA00X+120142Y+149560X0200Y         S0      
317GND              VIA   -    MD0100PA00X+121002Y+149560X0200Y    R180 S0      
317GND              VIA   -    MD0100PA00X+119472Y+150530X0200Y         S0      
317GND              VIA   -    MD0100PA00X+120332Y+150530X0200Y    R180 S0      
317GND              VIA   -    MD0100PA00X+122152Y+150530X0200Y         S0      
317GND              VIA   -    MD0100PA00X+123012Y+150530X0200Y    R180 S0      
317GND              VIA   -    MD0100PA00X+124832Y+150530X0200Y         S0      
317GND              VIA   -    MD0100PA00X+122822Y+149560X0200Y         S0      
317GND              VIA   -    MD0100PA00X+123682Y+149560X0200Y    R180 S0      
317GND              VIA   -    MD0100PA00X+125502Y+149560X0200Y         S0      
317GND              VIA   -    MD0100PA00X+123492Y+148590X0200Y         S0      
317GND              VIA   -    MD0100PA00X+124352Y+148590X0200Y    R180 S0      
317GND              VIA   -    MD0100PA00X+126172Y+148590X0200Y         S0      
317GND              VIA   -    MD0100PA00X+127512Y+148590X0200Y         S0      
317GND              VIA   -    MD0100PA00X+127032Y+148590X0200Y    R180 S0      
317GND              VIA   -    MD0100PA00X+126362Y+149560X0200Y    R180 S0      
317GND              VIA   -    MD0100PA00X+128372Y+148590X0200Y    R180 S0      
317GND              VIA   -    MD0100PA00X+125692Y+150530X0200Y    R180 S0      
317GND              VIA   -    MD0100PA00X+128589Y+152639X0200Y    R090 S0      
317GND              VIA   -    MD0100PA00X+128589Y+151777X0200Y    R090 S0      
317GND              VIA   -    MD0100PA00X+128589Y+151299X0200Y    R090 S0      
317GND              VIA   -    MD0100PA00X+128589Y+153117X0200Y    R090 S0      
317GND              VIA   -    MD0100PA00X+129109Y+152639X0200Y    R090 S0      
317GND              VIA   -    MD0100PA00X+129109Y+151777X0200Y    R090 S0      
317GND              VIA   -    MD0100PA00X+129109Y+151299X0200Y    R090 S0      
317GND              VIA   -    MD0100PA00X+129109Y+153117X0200Y    R090 S0      
317GND              VIA   -    MD0100PA00X+128849Y+152448X0200Y    R090 S0      
317GND              VIA   -    MD0100PA00X+128849Y+151968X0200Y    R270 S0      
317GND              VIA   -    MD0100PA00X+128849Y+153308X0200Y    R270 S0      
317GND              VIA   -    MD0100PA00X+128849Y+151108X0200Y    R090 S0      
317GND              VIA   -    MD0100PA00X+129905Y+154099X0200Y    R270 S0      
317GND              VIA   -    MD0100PA00X+130165Y+151250X0200Y    R270 S0      
317GND              VIA   -    MD0100PA00X+130165Y+151728X0200Y    R270 S0      
317GND              VIA   -    MD0100PA00X+130165Y+153430X0200Y    R270 S0      
317GND              VIA   -    MD0100PA00X+130165Y+153908X0200Y    R270 S0      
317GND              VIA   -    MD0100PA00X+129645Y+151250X0200Y    R270 S0      
317GND              VIA   -    MD0100PA00X+129645Y+151728X0200Y    R270 S0      
317GND              VIA   -    MD0100PA00X+129645Y+153430X0200Y    R270 S0      
317GND              VIA   -    MD0100PA00X+129645Y+153908X0200Y    R270 S0      
317GND              VIA   -    MD0100PA00X+129905Y+151059X0200Y    R090 S0      
317GND              VIA   -    MD0100PA00X+129905Y+151919X0200Y    R270 S0      
317GND              VIA   -    MD0100PA00X+129905Y+153249X0200Y    R090 S0      
317GND              VIA   -    MD0100PA00X+132948Y+150790X0200Y         S0      
317GND              VIA   -    MD0100PA00X+132470Y+150790X0200Y         S0      
317GND              VIA   -    MD0100PA00X+135150Y+150790X0200Y         S0      
317GND              VIA   -    MD0100PA00X+135628Y+150790X0200Y         S0      
317GND              VIA   -    MD0100PA00X+137830Y+150790X0200Y         S0      
317GND              VIA   -    MD0100PA00X+138308Y+150790X0200Y         S0      
317GND              VIA   -    MD0100PA00X+132948Y+150270X0200Y         S0      
317GND              VIA   -    MD0100PA00X+132470Y+150270X0200Y         S0      
317GND              VIA   -    MD0100PA00X+135150Y+150270X0200Y         S0      
317GND              VIA   -    MD0100PA00X+135628Y+150270X0200Y         S0      
317GND              VIA   -    MD0100PA00X+137830Y+150270X0200Y         S0      
317GND              VIA   -    MD0100PA00X+138308Y+150270X0200Y         S0      
317GND              VIA   -    MD0100PA00X+130460Y+149820X0200Y         S0      
317GND              VIA   -    MD0100PA00X+130938Y+149820X0200Y         S0      
317GND              VIA   -    MD0100PA00X+133618Y+149820X0200Y         S0      
317GND              VIA   -    MD0100PA00X+133140Y+149820X0200Y         S0      
317GND              VIA   -    MD0100PA00X+136298Y+149820X0200Y         S0      
317GND              VIA   -    MD0100PA00X+135820Y+149820X0200Y         S0      
317GND              VIA   -    MD0100PA00X+138978Y+149820X0200Y         S0      
317GND              VIA   -    MD0100PA00X+138500Y+149820X0200Y         S0      
317GND              VIA   -    MD0100PA00X+130460Y+149300X0200Y         S0      
317GND              VIA   -    MD0100PA00X+130938Y+149300X0200Y         S0      
317GND              VIA   -    MD0100PA00X+133618Y+149300X0200Y         S0      
317GND              VIA   -    MD0100PA00X+133140Y+149300X0200Y         S0      
317GND              VIA   -    MD0100PA00X+136298Y+149300X0200Y         S0      
317GND              VIA   -    MD0100PA00X+135820Y+149300X0200Y         S0      
317GND              VIA   -    MD0100PA00X+138978Y+149300X0200Y         S0      
317GND              VIA   -    MD0100PA00X+138500Y+149300X0200Y         S0      
317GND              VIA   -    MD0100PA00X+131608Y+148850X0200Y         S0      
317GND              VIA   -    MD0100PA00X+131130Y+148850X0200Y         S0      
317GND              VIA   -    MD0100PA00X+136490Y+148850X0200Y         S0      
317GND              VIA   -    MD0100PA00X+136968Y+148850X0200Y         S0      
317GND              VIA   -    MD0100PA00X+139648Y+148850X0200Y         S0      
317GND              VIA   -    MD0100PA00X+139170Y+148850X0200Y         S0      
317GND              VIA   -    MD0100PA00X+140988Y+148850X0200Y         S0      
317GND              VIA   -    MD0100PA00X+140510Y+148850X0200Y         S0      
317GND              VIA   -    MD0100PA00X+131608Y+148330X0200Y         S0      
317GND              VIA   -    MD0100PA00X+131130Y+148330X0200Y         S0      
317GND              VIA   -    MD0100PA00X+136490Y+148330X0200Y         S0      
317GND              VIA   -    MD0100PA00X+136968Y+148330X0200Y         S0      
317GND              VIA   -    MD0100PA00X+139648Y+148330X0200Y         S0      
317GND              VIA   -    MD0100PA00X+139170Y+148330X0200Y         S0      
317GND              VIA   -    MD0100PA00X+140988Y+148330X0200Y         S0      
317GND              VIA   -    MD0100PA00X+140510Y+148330X0200Y         S0      
317GND              VIA   -    MD0100PA00X+130269Y+149560X0200Y         S0      
317GND              VIA   -    MD0100PA00X+130939Y+148590X0200Y         S0      
317GND              VIA   -    MD0100PA00X+131799Y+148590X0200Y    R180 S0      
317GND              VIA   -    MD0100PA00X+131129Y+149560X0200Y    R180 S0      
317GND              VIA   -    MD0100PA00X+132949Y+149560X0200Y         S0      
317GND              VIA   -    MD0100PA00X+133809Y+149560X0200Y    R180 S0      
317GND              VIA   -    MD0100PA00X+132279Y+150530X0200Y         S0      
317GND              VIA   -    MD0100PA00X+133139Y+150530X0200Y    R180 S0      
317GND              VIA   -    MD0100PA00X+134959Y+150530X0200Y         S0      
317GND              VIA   -    MD0100PA00X+135819Y+150530X0200Y    R180 S0      
317GND              VIA   -    MD0100PA00X+137639Y+150530X0200Y         S0      
317GND              VIA   -    MD0100PA00X+135629Y+149560X0200Y         S0      
317GND              VIA   -    MD0100PA00X+136489Y+149560X0200Y    R180 S0      
317GND              VIA   -    MD0100PA00X+138309Y+149560X0200Y         S0      
317GND              VIA   -    MD0100PA00X+136299Y+148590X0200Y         S0      
317GND              VIA   -    MD0100PA00X+137159Y+148590X0200Y    R180 S0      
317GND              VIA   -    MD0100PA00X+138979Y+148590X0200Y         S0      
317GND              VIA   -    MD0100PA00X+140319Y+148590X0200Y         S0      
317GND              VIA   -    MD0100PA00X+139839Y+148590X0200Y    R180 S0      
317GND              VIA   -    MD0100PA00X+139169Y+149560X0200Y    R180 S0      
317GND              VIA   -    MD0100PA00X+141179Y+148590X0200Y    R180 S0      
317GND              VIA   -    MD0100PA00X+138499Y+150530X0200Y    R180 S0      
317GND              VIA   -    MD0100PA00X+141396Y+152639X0200Y    R090 S0      
317GND              VIA   -    MD0100PA00X+141396Y+151777X0200Y    R090 S0      
317GND              VIA   -    MD0100PA00X+141396Y+151299X0200Y    R090 S0      
317GND              VIA   -    MD0100PA00X+141396Y+153117X0200Y    R090 S0      
317GND              VIA   -    MD0100PA00X+141916Y+152639X0200Y    R090 S0      
317GND              VIA   -    MD0100PA00X+141916Y+151777X0200Y    R090 S0      
317GND              VIA   -    MD0100PA00X+141916Y+151299X0200Y    R090 S0      
317GND              VIA   -    MD0100PA00X+141916Y+153117X0200Y    R090 S0      
317GND              VIA   -    MD0100PA00X+141656Y+152448X0200Y    R090 S0      
317GND              VIA   -    MD0100PA00X+141656Y+151968X0200Y    R270 S0      
317GND              VIA   -    MD0100PA00X+141656Y+153308X0200Y    R270 S0      
317GND              VIA   -    MD0100PA00X+141656Y+151108X0200Y    R090 S0      
317GND              VIA   -    MD0100PA00X+143516Y+154099X0200Y    R270 S0      
317GND              VIA   -    MD0100PA00X+143776Y+151250X0200Y    R270 S0      
317GND              VIA   -    MD0100PA00X+143776Y+151728X0200Y    R270 S0      
317GND              VIA   -    MD0100PA00X+143776Y+153430X0200Y    R270 S0      
317GND              VIA   -    MD0100PA00X+143776Y+153908X0200Y    R270 S0      
317GND              VIA   -    MD0100PA00X+143256Y+151250X0200Y    R270 S0      
317GND              VIA   -    MD0100PA00X+143256Y+151728X0200Y    R270 S0      
317GND              VIA   -    MD0100PA00X+143256Y+153430X0200Y    R270 S0      
317GND              VIA   -    MD0100PA00X+143256Y+153908X0200Y    R270 S0      
317GND              VIA   -    MD0100PA00X+143516Y+151059X0200Y    R090 S0      
317GND              VIA   -    MD0100PA00X+143516Y+151919X0200Y    R270 S0      
317GND              VIA   -    MD0100PA00X+143516Y+153249X0200Y    R090 S0      
317GND              VIA   -    MD0100PA00X+146559Y+150790X0200Y         S0      
317GND              VIA   -    MD0100PA00X+146081Y+150790X0200Y         S0      
317GND              VIA   -    MD0100PA00X+148761Y+150790X0200Y         S0      
317GND              VIA   -    MD0100PA00X+149239Y+150790X0200Y         S0      
317GND              VIA   -    MD0100PA00X+151441Y+150790X0200Y         S0      
317GND              VIA   -    MD0100PA00X+151919Y+150790X0200Y         S0      
317GND              VIA   -    MD0100PA00X+146559Y+150270X0200Y         S0      
317GND              VIA   -    MD0100PA00X+146081Y+150270X0200Y         S0      
317GND              VIA   -    MD0100PA00X+148761Y+150270X0200Y         S0      
317GND              VIA   -    MD0100PA00X+149239Y+150270X0200Y         S0      
317GND              VIA   -    MD0100PA00X+151441Y+150270X0200Y         S0      
317GND              VIA   -    MD0100PA00X+152781Y+150270X0200Y         S0      
317GND              VIA   -    MD0100PA00X+151919Y+150270X0200Y         S0      
317GND              VIA   -    MD0100PA00X+144071Y+149820X0200Y         S0      
317GND              VIA   -    MD0100PA00X+144549Y+149820X0200Y         S0      
317GND              VIA   -    MD0100PA00X+147229Y+149820X0200Y         S0      
317GND              VIA   -    MD0100PA00X+146751Y+149820X0200Y         S0      
317GND              VIA   -    MD0100PA00X+149909Y+149820X0200Y         S0      
317GND              VIA   -    MD0100PA00X+149431Y+149820X0200Y         S0      
317GND              VIA   -    MD0100PA00X+152589Y+149820X0200Y         S0      
317GND              VIA   -    MD0100PA00X+152111Y+149820X0200Y         S0      
317GND              VIA   -    MD0100PA00X+144071Y+149300X0200Y         S0      
317GND              VIA   -    MD0100PA00X+144549Y+149300X0200Y         S0      
317GND              VIA   -    MD0100PA00X+147229Y+149300X0200Y         S0      
317GND              VIA   -    MD0100PA00X+146751Y+149300X0200Y         S0      
317GND              VIA   -    MD0100PA00X+149909Y+149300X0200Y         S0      
317GND              VIA   -    MD0100PA00X+149431Y+149300X0200Y         S0      
317GND              VIA   -    MD0100PA00X+152589Y+149300X0200Y         S0      
317GND              VIA   -    MD0100PA00X+152111Y+149300X0200Y         S0      
317GND              VIA   -    MD0100PA00X+145219Y+148850X0200Y         S0      
317GND              VIA   -    MD0100PA00X+144741Y+148850X0200Y         S0      
317GND              VIA   -    MD0100PA00X+150101Y+148850X0200Y         S0      
317GND              VIA   -    MD0100PA00X+150579Y+148850X0200Y         S0      
317GND              VIA   -    MD0100PA00X+153259Y+148850X0200Y         S0      
317GND              VIA   -    MD0100PA00X+152781Y+148850X0200Y         S0      
317GND              VIA   -    MD0100PA00X+154599Y+148850X0200Y         S0      
317GND              VIA   -    MD0100PA00X+154121Y+148850X0200Y         S0      
317GND              VIA   -    MD0100PA00X+145219Y+148330X0200Y         S0      
317GND              VIA   -    MD0100PA00X+144741Y+148330X0200Y         S0      
317GND              VIA   -    MD0100PA00X+150101Y+148330X0200Y         S0      
317GND              VIA   -    MD0100PA00X+150579Y+148330X0200Y         S0      
317GND              VIA   -    MD0100PA00X+153259Y+148330X0200Y         S0      
317GND              VIA   -    MD0100PA00X+152781Y+148330X0200Y         S0      
317GND              VIA   -    MD0100PA00X+154599Y+148330X0200Y         S0      
317GND              VIA   -    MD0100PA00X+154121Y+148330X0200Y         S0      
317GND              VIA   -    MD0100PA00X+143880Y+149560X0200Y         S0      
317GND              VIA   -    MD0100PA00X+144550Y+148590X0200Y         S0      
317GND              VIA   -    MD0100PA00X+145410Y+148590X0200Y    R180 S0      
317GND              VIA   -    MD0100PA00X+144740Y+149560X0200Y    R180 S0      
317GND              VIA   -    MD0100PA00X+146560Y+149560X0200Y         S0      
317GND              VIA   -    MD0100PA00X+147420Y+149560X0200Y    R180 S0      
317GND              VIA   -    MD0100PA00X+145890Y+150530X0200Y         S0      
317GND              VIA   -    MD0100PA00X+146750Y+150530X0200Y    R180 S0      
317GND              VIA   -    MD0100PA00X+148570Y+150530X0200Y         S0      
317GND              VIA   -    MD0100PA00X+149430Y+150530X0200Y    R180 S0      
317GND              VIA   -    MD0100PA00X+151250Y+150530X0200Y         S0      
317GND              VIA   -    MD0100PA00X+149240Y+149560X0200Y         S0      
317GND              VIA   -    MD0100PA00X+150100Y+149560X0200Y    R180 S0      
317GND              VIA   -    MD0100PA00X+151920Y+149560X0200Y         S0      
317GND              VIA   -    MD0100PA00X+149910Y+148590X0200Y         S0      
317GND              VIA   -    MD0100PA00X+150770Y+148590X0200Y    R180 S0      
317GND              VIA   -    MD0100PA00X+152590Y+148590X0200Y         S0      
317GND              VIA   -    MD0100PA00X+153930Y+148590X0200Y         S0      
317GND              VIA   -    MD0100PA00X+153450Y+148590X0200Y    R180 S0      
317GND              VIA   -    MD0100PA00X+152780Y+149560X0200Y    R180 S0      
317GND              VIA   -    MD0100PA00X+154790Y+148590X0200Y    R180 S0      
317GND              VIA   -    MD0100PA00X+152590Y+150530X0200Y         S0      
317GND              VIA   -    MD0100PA00X+152110Y+150530X0200Y    R180 S0      
317GND              VIA   -    MD0100PA00X+155007Y+152639X0200Y    R090 S0      
317GND              VIA   -    MD0100PA00X+155007Y+151777X0200Y    R090 S0      
317GND              VIA   -    MD0100PA00X+155007Y+151299X0200Y    R090 S0      
317GND              VIA   -    MD0100PA00X+155007Y+153117X0200Y    R090 S0      
317GND              VIA   -    MD0100PA00X+155527Y+152639X0200Y    R090 S0      
317GND              VIA   -    MD0100PA00X+155527Y+151777X0200Y    R090 S0      
317GND              VIA   -    MD0100PA00X+155527Y+151299X0200Y    R090 S0      
317GND              VIA   -    MD0100PA00X+155527Y+153117X0200Y    R090 S0      
317GND              VIA   -    MD0100PA00X+155267Y+152448X0200Y    R090 S0      
317GND              VIA   -    MD0100PA00X+155267Y+151968X0200Y    R270 S0      
317GND              VIA   -    MD0100PA00X+155267Y+153308X0200Y    R270 S0      
317GND              VIA   -    MD0100PA00X+155267Y+151108X0200Y    R090 S0      
317GND              VIA   -    MD0100PA00X+156322Y+154099X0200Y    R270 S0      
317GND              VIA   -    MD0100PA00X+156582Y+151250X0200Y    R270 S0      
317GND              VIA   -    MD0100PA00X+156582Y+151728X0200Y    R270 S0      
317GND              VIA   -    MD0100PA00X+156582Y+153430X0200Y    R270 S0      
317GND              VIA   -    MD0100PA00X+156582Y+153908X0200Y    R270 S0      
317GND              VIA   -    MD0100PA00X+156062Y+151250X0200Y    R270 S0      
317GND              VIA   -    MD0100PA00X+156062Y+151728X0200Y    R270 S0      
317GND              VIA   -    MD0100PA00X+156062Y+153430X0200Y    R270 S0      
317GND              VIA   -    MD0100PA00X+156062Y+153908X0200Y    R270 S0      
317GND              VIA   -    MD0100PA00X+156322Y+151059X0200Y    R090 S0      
317GND              VIA   -    MD0100PA00X+156322Y+151919X0200Y    R270 S0      
317GND              VIA   -    MD0100PA00X+156322Y+153249X0200Y    R090 S0      
317GND              VIA   -    MD0100PA00X+159365Y+150790X0200Y         S0      
317GND              VIA   -    MD0100PA00X+158887Y+150790X0200Y         S0      
317GND              VIA   -    MD0100PA00X+161567Y+150790X0200Y         S0      
317GND              VIA   -    MD0100PA00X+162045Y+150790X0200Y         S0      
317GND              VIA   -    MD0100PA00X+164247Y+150790X0200Y         S0      
317GND              VIA   -    MD0100PA00X+164725Y+150790X0200Y         S0      
317GND              VIA   -    MD0100PA00X+159365Y+150270X0200Y         S0      
317GND              VIA   -    MD0100PA00X+158887Y+150270X0200Y         S0      
317GND              VIA   -    MD0100PA00X+161567Y+150270X0200Y         S0      
317GND              VIA   -    MD0100PA00X+162045Y+150270X0200Y         S0      
317GND              VIA   -    MD0100PA00X+164247Y+150270X0200Y         S0      
317GND              VIA   -    MD0100PA00X+164725Y+150270X0200Y         S0      
317GND              VIA   -    MD0100PA00X+156877Y+149820X0200Y         S0      
317GND              VIA   -    MD0100PA00X+157355Y+149820X0200Y         S0      
317GND              VIA   -    MD0100PA00X+160035Y+149820X0200Y         S0      
317GND              VIA   -    MD0100PA00X+159557Y+149820X0200Y         S0      
317GND              VIA   -    MD0100PA00X+162715Y+149820X0200Y         S0      
317GND              VIA   -    MD0100PA00X+162237Y+149820X0200Y         S0      
317GND              VIA   -    MD0100PA00X+165395Y+149820X0200Y         S0      
317GND              VIA   -    MD0100PA00X+164917Y+149820X0200Y         S0      
317GND              VIA   -    MD0100PA00X+156877Y+149300X0200Y         S0      
317GND              VIA   -    MD0100PA00X+157355Y+149300X0200Y         S0      
317GND              VIA   -    MD0100PA00X+160035Y+149300X0200Y         S0      
317GND              VIA   -    MD0100PA00X+159557Y+149300X0200Y         S0      
317GND              VIA   -    MD0100PA00X+162715Y+149300X0200Y         S0      
317GND              VIA   -    MD0100PA00X+162237Y+149300X0200Y         S0      
317GND              VIA   -    MD0100PA00X+165395Y+149300X0200Y         S0      
317GND              VIA   -    MD0100PA00X+164917Y+149300X0200Y         S0      
317GND              VIA   -    MD0100PA00X+158025Y+148850X0200Y         S0      
317GND              VIA   -    MD0100PA00X+157547Y+148850X0200Y         S0      
317GND              VIA   -    MD0100PA00X+162907Y+148850X0200Y         S0      
317GND              VIA   -    MD0100PA00X+163385Y+148850X0200Y         S0      
317GND              VIA   -    MD0100PA00X+166065Y+148850X0200Y         S0      
317GND              VIA   -    MD0100PA00X+165587Y+148850X0200Y         S0      
317GND              VIA   -    MD0100PA00X+167405Y+148850X0200Y         S0      
317GND              VIA   -    MD0100PA00X+166927Y+148850X0200Y         S0      
317GND              VIA   -    MD0100PA00X+158025Y+148330X0200Y         S0      
317GND              VIA   -    MD0100PA00X+157547Y+148330X0200Y         S0      
317GND              VIA   -    MD0100PA00X+162907Y+148330X0200Y         S0      
317GND              VIA   -    MD0100PA00X+163385Y+148330X0200Y         S0      
317GND              VIA   -    MD0100PA00X+166065Y+148330X0200Y         S0      
317GND              VIA   -    MD0100PA00X+165587Y+148330X0200Y         S0      
317GND              VIA   -    MD0100PA00X+167405Y+148330X0200Y         S0      
317GND              VIA   -    MD0100PA00X+166927Y+148330X0200Y         S0      
317GND              VIA   -    MD0100PA00X+156686Y+149560X0200Y         S0      
317GND              VIA   -    MD0100PA00X+157356Y+148590X0200Y         S0      
317GND              VIA   -    MD0100PA00X+158216Y+148590X0200Y    R180 S0      
317GND              VIA   -    MD0100PA00X+157546Y+149560X0200Y    R180 S0      
317GND              VIA   -    MD0100PA00X+159366Y+149560X0200Y         S0      
317GND              VIA   -    MD0100PA00X+160226Y+149560X0200Y    R180 S0      
317GND              VIA   -    MD0100PA00X+158696Y+150530X0200Y         S0      
317GND              VIA   -    MD0100PA00X+159556Y+150530X0200Y    R180 S0      
317GND              VIA   -    MD0100PA00X+161376Y+150530X0200Y         S0      
317GND              VIA   -    MD0100PA00X+162236Y+150530X0200Y    R180 S0      
317GND              VIA   -    MD0100PA00X+164056Y+150530X0200Y         S0      
317GND              VIA   -    MD0100PA00X+162046Y+149560X0200Y         S0      
317GND              VIA   -    MD0100PA00X+162906Y+149560X0200Y    R180 S0      
317GND              VIA   -    MD0100PA00X+164726Y+149560X0200Y         S0      
317GND              VIA   -    MD0100PA00X+162716Y+148590X0200Y         S0      
317GND              VIA   -    MD0100PA00X+163576Y+148590X0200Y    R180 S0      
317GND              VIA   -    MD0100PA00X+165396Y+148590X0200Y         S0      
317GND              VIA   -    MD0100PA00X+166736Y+148590X0200Y         S0      
317GND              VIA   -    MD0100PA00X+166256Y+148590X0200Y    R180 S0      
317GND              VIA   -    MD0100PA00X+165586Y+149560X0200Y    R180 S0      
317GND              VIA   -    MD0100PA00X+167596Y+148590X0200Y    R180 S0      
317GND              VIA   -    MD0100PA00X+164916Y+150530X0200Y    R180 S0      
317GND              VIA   -    MD0100PA00X+167813Y+152639X0200Y    R090 S0      
317GND              VIA   -    MD0100PA00X+167813Y+151777X0200Y    R090 S0      
317GND              VIA   -    MD0100PA00X+167813Y+151299X0200Y    R090 S0      
317GND              VIA   -    MD0100PA00X+167813Y+153117X0200Y    R090 S0      
317GND              VIA   -    MD0100PA00X+168333Y+152639X0200Y    R090 S0      
317GND              VIA   -    MD0100PA00X+168333Y+151777X0200Y    R090 S0      
317GND              VIA   -    MD0100PA00X+168276Y+151217X0200Y    R090 S0      
317GND              VIA   -    MD0100PA00X+168333Y+153117X0200Y    R090 S0      
317GND              VIA   -    MD0100PA00X+167363Y+153787X0200Y    R090 S0      
317GND              VIA   -    MD0100PA00X+167363Y+153309X0200Y    R090 S0      
317GND              VIA   -    MD0100PA00X+168073Y+152448X0200Y    R090 S0      
317GND              VIA   -    MD0100PA00X+168073Y+151968X0200Y    R270 S0      
317GND              VIA   -    MD0100PA00X+168073Y+153308X0200Y    R270 S0      
317GND              VIA   -    MD0100PA00X+168043Y+151120X0200Y    R090 S0      
327GND              C1979 -2          A01X+046850Y+171142X0198Y0197R270 S1      
317GND              VIA   -    MD0100PA00X+046850Y+170850X0200Y         S0      
327GND              Q1    -1          A01X+063950Y+051260X0170Y0200R090 S1      
327GND              Q1    -4          A01X+064698Y+050748X0170Y0200R090 S1      
317GND              VIA   -    MD0100PA00X+037990Y+167005X0200Y         S0      
317GND              VIA   -    MD0100PA00X+092392Y+084399X0190Y         S0      
317GND              VIA   -    MD0100PA00X+065184Y+156775X0200Y         S0      
317GND              VIA   -    MD0100PA00X+015032Y+023354X0200Y         S0      
327GND              Q128  -1          A18X+065227Y+163306X0170Y0200     S2      
317GND              VIA   -    MD0100PA00X+065227Y+163037X0200Y         S0      
327GND              Q128  -4          A18X+065739Y+162558X0170Y0200     S2      
317GND              VIA   -    MD0100PA00X+065739Y+162814X0200Y         S0      
327GND              C12   -2          A18X+066054Y+164152X0198Y0197R180 S2      
317GND              VIA   -    MD0100PA00X+066054Y+163817X0200Y         S0      
327GND              R4120 -2          A18X+065039Y+164552X0198Y0197     S2      
317GND              VIA   -    MD0100PA00X+065090Y+164812X0200Y         S0      
327GND              R2926 -2          A18X+070932Y+162736X0198Y0197R270 S2      
317GND              VIA   -    MD0100PA00X+070668Y+162736X0200Y         S0      
317GND              VIA   -    MD0100PA00X+042344Y+161241X0200Y         S0      
317GND              VIA   -    MD0100PA00X+041320Y+161270X0200Y         S0      
317GND              VIA   -    MD0100PA00X+042338Y+160768X0200Y         S0      
317GND              VIA   -    MD0100PA00X+041829Y+160750X0200Y         S0      
317GND              VIA   -    MD0100PA00X+041310Y+160760X0200Y         S0      
317GND              VIA   -    MD0100PA00X+042335Y+161786X0200Y         S0      
317GND              VIA   -    MD0100PA00X+041850Y+161800X0200Y         S0      
317GND              VIA   -    MD0100PA00X+041310Y+161790X0200Y         S0      
327GND              U10   -33  M      A01X+041829Y+161272X1240Y1240R270 S1      
327GND              R2927 -2          A18X+070932Y+163471X0198Y0197R090 S2      
317GND              VIA   -    MD0100PA00X+017536Y+145550X0200Y         S0      
317GND              VIA   -    MD0100PA00X+018014Y+145550X0200Y         S0      
317GND              VIA   -    MD0100PA00X+017536Y+145030X0200Y         S0      
317GND              VIA   -    MD0100PA00X+018014Y+145030X0200Y         S0      
317GND              VIA   -    MD0100PA00X+019546Y+146520X0200Y         S0      
317GND              VIA   -    MD0100PA00X+020024Y+146520X0200Y         S0      
317GND              VIA   -    MD0100PA00X+019546Y+146000X0200Y         S0      
317GND              VIA   -    MD0100PA00X+020024Y+146000X0200Y         S0      
317GND              VIA   -    MD0100PA00X+018876Y+147490X0200Y         S0      
317GND              VIA   -    MD0100PA00X+019354Y+147490X0200Y         S0      
317GND              VIA   -    MD0100PA00X+018876Y+146970X0200Y         S0      
317GND              VIA   -    MD0100PA00X+019354Y+146970X0200Y         S0      
317GND              VIA   -    MD0100PA00X+022226Y+146520X0200Y         S0      
317GND              VIA   -    MD0100PA00X+022704Y+146520X0200Y         S0      
317GND              VIA   -    MD0100PA00X+022226Y+146000X0200Y         S0      
317GND              VIA   -    MD0100PA00X+022704Y+146000X0200Y         S0      
317GND              VIA   -    MD0100PA00X+021556Y+147490X0200Y         S0      
317GND              VIA   -    MD0100PA00X+022034Y+147490X0200Y         S0      
317GND              VIA   -    MD0100PA00X+021556Y+146970X0200Y         S0      
317GND              VIA   -    MD0100PA00X+022034Y+146970X0200Y         S0      
317GND              VIA   -    MD0100PA00X+022896Y+145550X0200Y         S0      
317GND              VIA   -    MD0100PA00X+023374Y+145550X0200Y         S0      
317GND              VIA   -    MD0100PA00X+022896Y+145030X0200Y         S0      
317GND              VIA   -    MD0100PA00X+023374Y+145030X0200Y         S0      
317GND              VIA   -    MD0100PA00X+024236Y+147490X0200Y         S0      
317GND              VIA   -    MD0100PA00X+024714Y+147490X0200Y         S0      
317GND              VIA   -    MD0100PA00X+024236Y+146970X0200Y         S0      
317GND              VIA   -    MD0100PA00X+024714Y+146970X0200Y         S0      
317GND              VIA   -    MD0100PA00X+024906Y+146520X0200Y         S0      
317GND              VIA   -    MD0100PA00X+025384Y+146520X0200Y         S0      
317GND              VIA   -    MD0100PA00X+024906Y+146000X0200Y         S0      
317GND              VIA   -    MD0100PA00X+025384Y+146000X0200Y         S0      
317GND              VIA   -    MD0100PA00X+025576Y+145550X0200Y         S0      
317GND              VIA   -    MD0100PA00X+026054Y+145550X0200Y         S0      
317GND              VIA   -    MD0100PA00X+025576Y+145030X0200Y         S0      
317GND              VIA   -    MD0100PA00X+026054Y+145030X0200Y         S0      
317GND              VIA   -    MD0100PA00X+026916Y+145550X0200Y         S0      
317GND              VIA   -    MD0100PA00X+027394Y+145550X0200Y         S0      
317GND              VIA   -    MD0100PA00X+026916Y+145030X0200Y         S0      
317GND              VIA   -    MD0100PA00X+027394Y+145030X0200Y         S0      
317GND              VIA   -    MD0100PA00X+027802Y+147999X0200Y    R090 S0      
317GND              VIA   -    MD0100PA00X+027802Y+148477X0200Y    R090 S0      
317GND              VIA   -    MD0100PA00X+028322Y+147999X0200Y    R090 S0      
317GND              VIA   -    MD0100PA00X+028322Y+148477X0200Y    R090 S0      
317GND              VIA   -    MD0100PA00X+016571Y+150608X0200Y    R270 S0      
317GND              VIA   -    MD0100PA00X+016051Y+150608X0200Y    R270 S0      
317GND              VIA   -    MD0100PA00X+016051Y+150130X0200Y    R270 S0      
317GND              VIA   -    MD0100PA00X+016571Y+148428X0200Y    R270 S0      
317GND              VIA   -    MD0100PA00X+016571Y+147950X0200Y    R270 S0      
317GND              VIA   -    MD0100PA00X+016051Y+148428X0200Y    R270 S0      
317GND              VIA   -    MD0100PA00X+016051Y+147950X0200Y    R270 S0      
317GND              VIA   -    MD0100PA00X+017345Y+145290X0200Y         S0      
317GND              VIA   -    MD0100PA00X+018205Y+145290X0200Y    R180 S0      
317GND              VIA   -    MD0100PA00X+019355Y+146260X0200Y         S0      
317GND              VIA   -    MD0100PA00X+020215Y+146260X0200Y    R180 S0      
317GND              VIA   -    MD0100PA00X+018685Y+147230X0200Y         S0      
317GND              VIA   -    MD0100PA00X+019545Y+147230X0200Y    R180 S0      
317GND              VIA   -    MD0100PA00X+022035Y+146260X0200Y         S0      
317GND              VIA   -    MD0100PA00X+022895Y+146260X0200Y    R180 S0      
317GND              VIA   -    MD0100PA00X+021365Y+147230X0200Y         S0      
317GND              VIA   -    MD0100PA00X+022225Y+147230X0200Y    R180 S0      
317GND              VIA   -    MD0100PA00X+022705Y+145290X0200Y         S0      
317GND              VIA   -    MD0100PA00X+023565Y+145290X0200Y    R180 S0      
317GND              VIA   -    MD0100PA00X+024045Y+147230X0200Y         S0      
317GND              VIA   -    MD0100PA00X+024905Y+147230X0200Y    R180 S0      
317GND              VIA   -    MD0100PA00X+024715Y+146260X0200Y         S0      
317GND              VIA   -    MD0100PA00X+025575Y+146260X0200Y    R180 S0      
317GND              VIA   -    MD0100PA00X+025385Y+145290X0200Y         S0      
317GND              VIA   -    MD0100PA00X+026245Y+145290X0200Y    R180 S0      
317GND              VIA   -    MD0100PA00X+026725Y+145290X0200Y         S0      
317GND              VIA   -    MD0100PA00X+027585Y+145290X0200Y    R180 S0      
317GND              VIA   -    MD0100PA00X+028062Y+147808X0200Y    R090 S0      
317GND              VIA   -    MD0100PA00X+028062Y+148668X0200Y    R270 S0      
317GND              VIA   -    MD0100PA00X+028062Y+150008X0200Y    R270 S0      
317GND              VIA   -    MD0100PA00X+016311Y+149949X0200Y    R090 S0      
317GND              VIA   -    MD0100PA00X+016311Y+148619X0200Y    R270 S0      
317GND              VIA   -    MD0100PA00X+016311Y+147759X0200Y    R090 S0      
327GND              C1769 -2   M      A18X+070583Y+163104X0198Y0197R180 S2      
317GND              VIA   -    MD0100PA00X+070583Y+163357X0200Y         S0      
327GND              U195  -2          A18X+069088Y+163164X0160Y0200R270 S2      
317GND              VIA   -    MD0100PA00X+068831Y+163164X0200Y         S0      
327GND              R2916 -2          A18X+067739Y+164204X0198Y0197     S2      
317GND              VIA   -    MD0100PA00X+067398Y+163929X0200Y         S0      
327GND              R2915 -2          A18X+067739Y+162904X0198Y0197     S2      
317GND              VIA   -    MD0100PA00X+067489Y+162904X0200Y         S0      
327GND              R6237 -2          A18X+068548Y+168476X0198Y0197R180 S2      
317GND              VIA   -    MD0100PA00X+068548Y+168226X0200Y         S0      
327GND              U142  -2          A18X+070537Y+167994X0250Y0480     S2      
317GND              VIA   -    MD0100PA00X+070537Y+168406X0200Y         S0      
327GND              U6004 -S          A18X+069424Y+167894X0320Y0360R180 S2      
317GND              VIA   -    MD0100PA00X+069540Y+168589X0200Y         S0      
317GND              VIA   -    MD0100PA00X+112030Y+168206X0200Y         S0      
317GND              VIA   -    M      A01X+110500Y+168213X0200Y         S2      
017GND              VIA   -    M      A18X+110500Y+168213X0260Y         S2      
017GND                    -    MD0100PA00X+110500Y+168213                       
317GND              VIA   -    M      A01X+111600Y+167103X0200Y         S2      
017GND              VIA   -    M      A18X+111600Y+167103X0260Y         S2      
017GND                    -    MD0100PA00X+111600Y+167103                       
317GND              VIA   -    MD0080PA00X+037134Y+153606X0160Y    R180 S0      
317GND              VIA   -    MD0080PA00X+036189Y+153606X0160Y    R180 S0      
317GND              VIA   -    MD0080PA00X+035716Y+153606X0160Y    R180 S0      
317GND              VIA   -    MD0080PA00X+034771Y+153606X0160Y    R180 S0      
317GND              VIA   -    MD0080PA00X+033826Y+153606X0160Y    R180 S0      
317GND              VIA   -    MD0080PA00X+033354Y+153606X0160Y    R180 S0      
317GND              VIA   -    MD0080PA00X+038106Y+151424X0160Y    R180 S0      
317GND              VIA   -    MD0080PA00X+038078Y+153606X0160Y    R180 S0      
317GND              VIA   -    MD0100PA00X+054479Y+149148X0200Y    R090 S0      
317GND              VIA   -    MD0100PA00X+017344Y+146520X0200Y         S0      
317GND              VIA   -    MD0100PA00X+017535Y+146260X0200Y    R180 S0      
317GND              VIA   -    MD0100PA00X+017344Y+146000X0200Y         S0      
317GND              VIA   -    MD0100PA00X+016866Y+146520X0200Y         S0      
317GND              VIA   -    MD0100PA00X+016675Y+146260X0200Y         S0      
317GND              VIA   -    MD0100PA00X+016866Y+146000X0200Y         S0      
327GND              U8006 -2          A18X+073750Y+167268X0240Y0420     S2      
317GND              VIA   -    MD0100PA00X+073837Y+167791X0200Y         S0      
317GND              VIA   -    MD0100PA00X+073492Y+165783X0200Y         S0      
327GND              U8005 -2          A18X+074374Y+165366X0240Y0420R180 S2      
317GND              VIA   -    MD0100PA00X+074374Y+165733X0200Y         S0      
317GND              VIA   -    MD0100PA00X+073600Y+169551X0200Y         S0      
327GND              Q131  -1          A18X+065572Y+169558X0170Y0200R090 S2      
317GND              VIA   -    MD0100PA00X+065944Y+169470X0200Y         S0      
327GND              Q132  -4          A18X+066320Y+171470X0170Y0200R090 S2      
317GND              VIA   -    MD0100PA00X+066184Y+171734X0200Y         S0      
317GND              VIA   -    M      A01X+109647Y+164347X0200Y         S2      
017GND              VIA   -    M      A18X+109647Y+164347X0260Y         S2      
017GND                    -    MD0100PA00X+109647Y+164347                       
317GND              VIA   -    MD0100PA00X+112020Y+164660X0180Y         S0      
317GND              VIA   -    MD0100PA00X+112549Y+164175X0180Y         S0      
317GND              VIA   -    MD0100PA00X+112060Y+165204X0180Y         S0      
317GND              VIA   -    MD0100PA00X+112577Y+165219X0180Y         S0      
317GND              VIA   -    MD0100PA00X+113024Y+165219X0180Y         S0      
317GND              VIA   -    MD0100PA00X+113068Y+164695X0180Y         S0      
317GND              VIA   -    MD0100PA00X+113077Y+164175X0180Y         S0      
317GND              VIA   -    MD0100PA00X+112038Y+164168X0180Y         S0      
327GND              U314  -33  M      A01X+112552Y+164694X1240Y1240     S1      
327GND              C1751 -2          A18X+068292Y+165450X0198Y0197     S2      
317GND              VIA   -    MD0100PA00X+068292Y+165712X0200Y         S0      
327GND              C1881 -2          A18X+020085Y+165817X0198Y0197     S2      
317GND              VIA   -    MD0100PA00X+020085Y+165566X0200Y         S0      
317GND              VIA   -    MD0100PA00X+020112Y+166860X0200Y         S0      
327GND              R3513 -2          A18X+020366Y+167875X0198Y0197R270 S2      
317GND              VIA   -    MD0100PA00X+020381Y+168117X0200Y         S0      
327GND              Q107  -1          A18X+019530Y+169199X0170Y0200R270 S2      
317GND              VIA   -    MD0100PA00X+019530Y+169490X0200Y         S0      
327GND              C1974 -2          A18X+020381Y+169884X0198Y0197R090 S2      
327GND              R3473 -2          A18X+020381Y+169387X0198Y0197R270 S2      
317GND              VIA   -    MD0100PA00X+020381Y+169637X0200Y         S0      
327GND              Q101  -1          A18X+019530Y+170711X0170Y0200R270 S2      
317GND              VIA   -    MD0100PA00X+019274Y+170711X0200Y         S0      
327GND              Q101  -4          A18X+018782Y+170199X0170Y0200R270 S2      
317GND              VIA   -    MD0100PA00X+019039Y+170199X0200Y         S0      
327GND              R3907 -2          A01X+106822Y+166000X0198Y0197R090 S1      
317GND              VIA   -    M      A01X+106822Y+166278X0200Y         S2      
017GND              VIA   -    M      A18X+106822Y+166278X0260Y         S2      
017GND                    -    MD0100PA00X+106822Y+166278                       
327GND              C1797 -2          A01X+106422Y+166000X0198Y0197R090 S1      
317GND              VIA   -    MD0100PA00X+106422Y+166273X0200Y         S0      
327GND              C2179 -2          A01X+106375Y+165107X0198Y0197R090 S1      
317GND              VIA   -    M      A01X+106375Y+165383X0200Y         S2      
017GND              VIA   -    M      A18X+106375Y+165383X0260Y         S2      
017GND                    -    MD0100PA00X+106375Y+165383                       
327GND              R2585 -2          A01X+106809Y+165107X0198Y0197R090 S1      
317GND              VIA   -    MD0100PA00X+106809Y+165410X0200Y         S0      
327GND              U290  -S          A01X+105087Y+165610X0320Y0360R180 S1      
317GND              VIA   -    M      A01X+105087Y+165955X0200Y         S2      
017GND              VIA   -    M      A18X+105087Y+165955X0260Y         S2      
017GND                    -    MD0100PA00X+105087Y+165955                       
327GND              R3428 -2          A18X+020781Y+170899X0198Y0197R270 S2      
327GND              U196  -2          A01X+018176Y+171800X0160Y0200R270 S1      
317GND              VIA   -    M      A01X+018434Y+171800X0200Y         S2      
017GND              VIA   -    M      A18X+018434Y+171800X0260Y         S2      
017GND                    -    MD0100PA00X+018434Y+171800                       
327GND              U256  -2          A01X+015526Y+171850X0160Y0200R270 S1      
317GND              VIA   -    MD0100PA00X+015786Y+171850X0200Y         S0      
327GND              R4603 -2          A01X+011758Y+171245X0198Y0197     S1      
317GND              VIA   -    M      A01X+012005Y+171245X0200Y         S2      
017GND              VIA   -    M      A18X+012005Y+171245X0260Y         S2      
017GND                    -    MD0100PA00X+012005Y+171245                       
327GND              R3508 -2          A01X+018176Y+172895X0198Y0197R090 S1      
317GND              VIA   -    MD0100PA00X+018176Y+173135X0200Y    R180 S0      
327GND              C1977 -2          A01X+016750Y+171542X0198Y0197R270 S1      
317GND              VIA   -    MD0100PA00X+016750Y+171286X0200Y         S0      
327GND              U252  -2          A01X+019876Y+171500X0160Y0200R270 S1      
317GND              VIA   -    MD0100PA00X+020153Y+171500X0200Y         S0      
327GND              R3467 -2          A01X+019770Y+172300X0198Y0197R180 S1      
317GND              VIA   -    MD0100PA00X+019515Y+172300X0200Y         S0      
327GND              R3509 -2          A01X+018176Y+170731X0198Y0197R270 S1      
317GND              VIA   -    MD0100PA00X+017944Y+170881X0200Y         S0      
327GND              R3507 -2          A01X+017192Y+171100X0198Y0197R180 S1      
317GND              VIA   -    M      A01X+017192Y+170843X0200Y         S2      
017GND              VIA   -    M      A18X+017192Y+170843X0260Y         S2      
017GND                    -    MD0100PA00X+017192Y+170843                       
327GND              R2937 -2          A01X+017192Y+172500X0198Y0197R180 S1      
317GND              VIA   -    MD0100PA00X+017192Y+172758X0200Y         S0      
327GND              C1770 -2          A01X+019400Y+171492X0198Y0197R270 S1      
317GND              VIA   -    MD0100PA00X+019400Y+171236X0200Y         S0      
327GND              R3466 -2          A01X+015574Y+172650X0198Y0197R180 S1      
317GND              VIA   -    M      A01X+015574Y+172973X0200Y         S2      
017GND              VIA   -    M      A18X+015574Y+172973X0260Y         S2      
017GND                    -    MD0100PA00X+015574Y+172973                       
327GND              C1957 -2          A01X+021100Y+171192X0198Y0197R270 S1      
317GND              VIA   -    MD0100PA00X+021110Y+170899X0200Y         S0      
327GND              R2932 -2          A01X+015474Y+170742X0198Y0197R270 S1      
317GND              VIA   -    MD0100PA00X+015282Y+170550X0200Y         S0      
327GND              R2918 -2          A01X+014990Y+171279X0198Y0197R270 S1      
317GND              VIA   -    MD0100PA00X+014728Y+171279X0200Y         S0      
327GND              PC438 -2          A01X+021365Y+141919X0198Y0197     S1      
317GND              VIA   -    MD0100PA00X+021365Y+141626X0200Y         S0      
317GND              VIA   -    MD0100PA00X+144850Y+160100X0180Y         S0      
317GND              VIA   -    MD0100PA00X+144550Y+161150X0180Y         S0      
317GND              VIA   -    MD0100PA00X+145258Y+167330X0200Y         S0      
327GND              R4199 -2          A01X+145258Y+167088X0198Y0197R090 S1      
317GND              VIA   -    MD0100PA00X+144758Y+167330X0200Y         S0      
327GND              R4207 -2          A01X+144758Y+167088X0198Y0197R090 S1      
317GND              VIA   -    MD0100PA00X+144258Y+167330X0200Y         S0      
327GND              C2010 -2          A01X+144258Y+167088X0198Y0197R090 S1      
327GND              R4191 -2          A01X+145758Y+167088X0198Y0197R090 S1      
317GND              VIA   -    MD0100PA00X+145685Y+167332X0200Y         S0      
317GND              VIA   -    MD0100PA00X+092600Y+095272X0190Y         S0      
317GND              VIA   -    MD0100PA00X+094314Y+097713X0190Y         S0      
317GND              VIA   -    MD0100PA00X+094292Y+098255X0190Y         S0      
317GND              VIA   -    MD0100PA00X+090880Y+098529X0190Y         S0      
317GND              VIA   -    MD0100PA00X+090920Y+097071X0190Y         S0      
317GND              VIA   -    MD0100PA00X+091007Y+096033X0190Y         S0      
317GND              VIA   -    MD0100PA00X+090989Y+095022X0190Y         S0      
317GND              VIA   -    MD0100PA00X+092606Y+093873X0190Y         S0      
317GND              VIA   -    MD0100PA00X+093967Y+094517X0190Y         S0      
317GND              VIA   -    MD0100PA00X+094039Y+085995X0190Y         S0      
317GND              VIA   -    MD0100PA00X+095805Y+085938X0190Y         S0      
317GND              VIA   -    MD0100PA00X+093195Y+089140X0190Y         S0      
317GND              VIA   -    MD0100PA00X+094806Y+089147X0190Y         S0      
317GND              VIA   -    MD0100PA00X+092028Y+090055X0190Y         S0      
317GND              VIA   -    MD0100PA00X+090472Y+092179X0190Y         S0      
317GND              VIA   -    MD0100PA00X+089782Y+090909X0190Y         S0      
317GND              VIA   -    MD0100PA00X+091992Y+090892X0190Y         S0      
317GND              VIA   -    MD0100PA00X+092041Y+091827X0190Y         S0      
317GND              VIA   -    MD0100PA00X+092854Y+091345X0190Y         S0      
317GND              VIA   -    MD0100PA00X+095137Y+091365X0190Y         S0      
317GND              VIA   -    MD0100PA00X+094051Y+091813X0190Y         S0      
317GND              VIA   -    MD0100PA00X+093188Y+091817X0190Y         S0      
317GND              VIA   -    MD0100PA00X+083176Y+090132X0190Y         S0      
317GND              VIA   -    MD0100PA00X+160196Y+135177X0200Y         S0      
327GND              U101  -3          A18X+159725Y+135177X0220Y0530R090 S2      
317GND              VIA   -    MD0100PA00X+160177Y+133729X0200Y         S0      
327GND              U82   -3          A18X+159725Y+133729X0220Y0530R090 S2      
317GND              VIA   -    MD0100PA00X+157791Y+134162X0200Y         S0      
327GND              C218  -2          A18X+158092Y+134162X0198Y0197R090 S2      
317GND              VIA   -    MD0100PA00X+157834Y+135610X0200Y         S0      
327GND              C226  -2          A18X+158092Y+135610X0198Y0197R090 S2      
317GND              VIA   -    MD0100PA00X+157550Y+135610X0200Y         S0      
327GND              C5000 -2          A18X+157291Y+135610X0198Y0197R090 S2      
317GND              VIA   -    MD0100PA00X+074670Y+031565X0200Y         S0      
327GND              U6    -5          A18X+093634Y+093398X0130Y0250R270 S2      
317GND              VIA   -    MD0100PA00X+093302Y+093398X0200Y         S0      
327GND              C25   -2          A18X+094850Y+093092X0198Y0197R090 S2      
317GND              VIA   -    MD0100PA00X+095150Y+093092X0200Y         S0      
327GND              C24   -2          A18X+091800Y+092508X0198Y0197R270 S2      
327GND              C8066 -2   M      A01X+113785Y+145637X0198Y0197R270 S1      
327GND              R6086 -2          A01X+113385Y+145637X0198Y0197R270 S1      
317GND              VIA   -    MD0100PA00X+113785Y+145349X0200Y         S0      
317GND              VIA   -    MD0100PA00X+095242Y+087658X0200Y         S0      
327GND              C3    -2          A18X+091550Y+085692X0198Y0197R090 S2      
327GND              C1796 -2          A01X+009219Y+171624X0198Y0197R180 S1      
317GND              VIA   -    MD0100PA00X+009219Y+171374X0200Y    R180 S0      
327GND              U194  -4          A01X+010253Y+169883X0140Y0560R270 S1      
317GND              VIA   -    M      A01X+010645Y+169644X0200Y         S2      
017GND              VIA   -    M      A18X+010645Y+169644X0260Y         S2      
017GND                    -    MD0100PA00X+010645Y+169644                       
327GND              C1766 -2          A01X+013264Y+170935X0198Y0197     S1      
317GND              VIA   -    MD0100PA00X+013264Y+171185X0200Y         S0      
327GND              U200  -4          A01X+012016Y+172612X0140Y0560R090 S1      
317GND              VIA   -    MD0100PA00X+012446Y+172612X0200Y    R180 S0      
317GND              VIA   -    MD0100PA00X+164803Y+171876X0200Y    R270 S0      
327GND              R4159 -2          A01X+165051Y+171876X0198Y0197R090 S1      
317GND              VIA   -    MD0100PA00X+164801Y+171368X0200Y         S0      
317GND              VIA   -    MD0100PA00X+164803Y+173391X0200Y    R270 S0      
327GND              R2829 -2          A01X+165051Y+173391X0198Y0197R090 S1      
317GND              VIA   -    MD0100PA00X+164801Y+172883X0200Y         S0      
317GND              VIA   -    MD0100PA00X+166552Y+171688X0200Y         S0      
327GND              Q135  -1          A01X+166302Y+171688X0170Y0200R090 S1      
317GND              VIA   -    MD0100PA00X+165700Y+170861X0200Y    R090 S0      
327GND              C4    -2          A01X+165451Y+170861X0198Y0197R270 S1      
317GND              VIA   -    MD0100PA00X+166552Y+173203X0200Y         S0      
327GND              Q69   -1          A01X+166302Y+173203X0170Y0200R090 S1      
317GND              VIA   -    MD0100PA00X+165700Y+172376X0200Y    R090 S0      
327GND              C1772 -2          A01X+165451Y+172376X0198Y0197R270 S1      
317GND              VIA   -    MD0100PA00X+166800Y+171176X0200Y    R180 S0      
327GND              Q135  -4          A01X+167050Y+171176X0170Y0200R090 S1      
317GND              VIA   -    MD0100PA00X+166800Y+172691X0200Y    R180 S0      
327GND              Q69   -4          A01X+167050Y+172691X0170Y0200R090 S1      
327GND              Q106  -4          A01X+174462Y+170826X0170Y0200R090 S1      
317GND              VIA   -    MD0100PA00X+174212Y+170826X0200Y    R180 S0      
327GND              Q106  -1          A01X+173714Y+171338X0170Y0200R090 S1      
317GND              VIA   -    MD0100PA00X+173964Y+171338X0200Y         S0      
317GND              VIA   -    MD0100PA00X+175286Y+171638X0200Y         S0      
317GND              VIA   -    MD0100PA00X+145558Y+163611X0200Y    R180 S0      
327GND              U270  -4          A01X+145558Y+164034X0240Y0520     S1      
327GND              C1787 -2          A01X+113126Y+157210X0198Y0197R090 S1      
317GND              VIA   -    MD0100PA00X+113376Y+157210X0200Y    R090 S0      
317GND              VIA   -    M      A01X+111907Y+155146X0200Y    R090 S2      
017GND              VIA   -    M      A18X+111907Y+155146X0260Y    R090 S2      
017GND                    -    MD0100PA00X+111907Y+155146                       
327GND              U143  -5          A01X+111907Y+154673X0170Y0590R180 S1      
317GND              H6002 -1   MD1660PA00X+088752Y+152819X3150Y    R270 S3      
327GND              PC1789-2   M      A01X+078928Y+152740X0198Y0197R090 S1      
317GND              VIA   -    MD0100PA00X+079182Y+152740X0200Y    R180 S0      
327GND              PJ38  -11  M      A01X+077953Y+152819X0240Y0650R270 S1      
317GND              VIA   -    MD0100PA00X+078428Y+152819X0200Y    R270 S0      
327GND              PJ38  -G2  M      A01X+077122Y+153496X0551Y2303R090 S1      
317GND              VIA   -    MD0100PA00X+075818Y+153496X0200Y    R090 S0      
317GND              VIA   -    MD0100PA00X+078426Y+153496X0200Y    R270 S0      
327GND              PJ38  -21  M      A01X+076291Y+152622X0240Y0650R090 S1      
317GND              VIA   -    MD0100PA00X+075816Y+152622X0200Y    R090 S0      
327GND              PJ38  -G1  M      A01X+077122Y+148205X0551Y2303R090 S1      
317GND              VIA   -    MD0100PA00X+075818Y+148205X0200Y    R090 S0      
317GND              VIA   -    MD0100PA00X+078426Y+148205X0200Y    R270 S0      
317GND              JP4003-3   MD0410PA00X+108097Y+164096X0610Y         S3      
317GND              VIA   -    MD0100PA00X+140506Y+163961X0200Y    R270 S0      
327GND              Q134  -4          A01X+140506Y+164211X0170Y0200R180 S1      
317GND              VIA   -    MD0100PA00X+139994Y+163713X0200Y    R090 S0      
327GND              Q134  -1          A01X+139994Y+163463X0170Y0200R180 S1      
327GND              U204  -3          A01X+141874Y+162563X0170Y0240     S1      
317GND              VIA   -    MD0100PA00X+141874Y+162290X0200Y    R270 S0      
327GND              C1803 -2          A01X+141362Y+164092X0198Y0197R090 S1      
317GND              VIA   -    MD0100PA00X+141320Y+164392X0200Y    R180 S0      
317GND              VIA   -    M      A01X+119798Y+168827X0200Y    R270 S2      
017GND              VIA   -    M      A18X+119798Y+168827X0260Y    R270 S2      
017GND                    -    MD0100PA00X+119798Y+168827                       
327GND              Q130  -1          A01X+119773Y+168539X0170Y0200     S1      
327GND              Q130  -4          A01X+119261Y+167791X0170Y0200     S1      
317GND              VIA   -    MD0100PA00X+119261Y+168041X0200Y    R090 S0      
327GND              C16   -2          A01X+118946Y+169385X0198Y0197R180 S1      
317GND              VIA   -    M      A01X+118946Y+169137X0200Y         S2      
017GND              VIA   -    M      A18X+118946Y+169137X0260Y         S2      
017GND                    -    MD0100PA00X+118946Y+169137                       
327GND              R4132 -2          A01X+119961Y+169785X0198Y0197     S1      
317GND              VIA   -    MD0100PA00X+119961Y+170033X0200Y    R180 S0      
317GND              VIA   -    MD0100PA00X+038718Y+155080X0180Y         S0      
317GND              VIA   -    MD0100PA00X+038246Y+155090X0180Y         S0      
317GND              VIA   -    MD0100PA00X+037773Y+155090X0180Y         S0      
317GND              VIA   -    MD0100PA00X+037301Y+155070X0180Y         S0      
317GND              VIA   -    MD0100PA00X+036828Y+155090X0180Y         S0      
317GND              VIA   -    MD0100PA00X+036356Y+155090X0180Y         S0      
317GND              VIA   -    MD0100PA00X+035884Y+155090X0180Y         S0      
317GND              VIA   -    MD0100PA00X+035411Y+155090X0180Y         S0      
317GND              VIA   -    MD0100PA00X+034466Y+155070X0180Y         S0      
317GND              VIA   -    MD0100PA00X+034939Y+155080X0180Y         S0      
317GND              VIA   -    MD0100PA00X+033994Y+155090X0180Y         S0      
317GND              VIA   -    MD0100PA00X+033521Y+155090X0180Y         S0      
317GND              VIA   -    MD0100PA00X+033049Y+155070X0180Y         S0      
317GND              VIA   -    MD0100PA00X+032576Y+155090X0180Y         S0      
317GND              VIA   -    MD0100PA00X+031632Y+155080X0180Y         S0      
317GND              VIA   -    MD0100PA00X+032104Y+155080X0180Y         S0      
317GND              VIA   -    MD0100PA00X+165132Y+164480X0180Y         S0      
317GND              VIA   -    MD0100PA00X+165132Y+164979X0180Y         S0      
317GND              VIA   -    MD0100PA00X+165132Y+163288X0180Y         S0      
317GND              VIA   -    MD0100PA00X+165132Y+163788X0180Y         S0      
317GND              VIA   -    MD0100PA00X+164529Y+165979X0180Y         S0      
317GND              VIA   -    MD0100PA00X+164034Y+165979X0180Y         S0      
317GND              VIA   -    MD0100PA00X+163323Y+165979X0180Y         S0      
317GND              VIA   -    MD0100PA00X+164636Y+164480X0180Y         S0      
317GND              VIA   -    MD0100PA00X+163926Y+164480X0180Y         S0      
317GND              VIA   -    MD0100PA00X+163430Y+164480X0180Y         S0      
317GND              VIA   -    MD0100PA00X+164636Y+164979X0180Y         S0      
317GND              VIA   -    MD0100PA00X+164529Y+165480X0180Y         S0      
317GND              VIA   -    MD0100PA00X+163926Y+164979X0180Y         S0      
317GND              VIA   -    MD0100PA00X+164034Y+165480X0180Y         S0      
317GND              VIA   -    MD0100PA00X+163430Y+164979X0180Y         S0      
317GND              VIA   -    MD0100PA00X+163323Y+165480X0180Y         S0      
317GND              VIA   -    MD0100PA00X+164529Y+162788X0180Y         S0      
317GND              VIA   -    MD0100PA00X+164034Y+162788X0180Y         S0      
317GND              VIA   -    MD0100PA00X+163323Y+162788X0180Y         S0      
317GND              VIA   -    MD0100PA00X+164636Y+163288X0180Y         S0      
317GND              VIA   -    MD0100PA00X+164636Y+163788X0180Y         S0      
317GND              VIA   -    MD0100PA00X+163926Y+163279X0180Y         S0      
317GND              VIA   -    MD0100PA00X+163926Y+163788X0180Y         S0      
317GND              VIA   -    MD0100PA00X+163430Y+163279X0180Y         S0      
317GND              VIA   -    MD0100PA00X+163430Y+163788X0180Y         S0      
317GND              VIA   -    MD0100PA00X+164034Y+162288X0180Y         S0      
317GND              VIA   -    MD0100PA00X+164529Y+162288X0180Y         S0      
317GND              VIA   -    MD0100PA00X+163323Y+162288X0180Y         S0      
317GND              VIA   -    MD0100PA00X+162828Y+165979X0180Y         S0      
317GND              VIA   -    MD0100PA00X+162117Y+165979X0180Y         S0      
317GND              VIA   -    MD0100PA00X+162720Y+164480X0180Y         S0      
317GND              VIA   -    MD0100PA00X+162224Y+164480X0180Y         S0      
317GND              VIA   -    MD0100PA00X+162720Y+164979X0180Y         S0      
317GND              VIA   -    MD0100PA00X+162828Y+165480X0180Y         S0      
317GND              VIA   -    MD0100PA00X+162224Y+164979X0180Y         S0      
317GND              VIA   -    MD0100PA00X+162117Y+165480X0180Y         S0      
317GND              VIA   -    MD0100PA00X+162828Y+162788X0180Y         S0      
317GND              VIA   -    MD0100PA00X+162117Y+162788X0180Y         S0      
317GND              VIA   -    MD0100PA00X+162720Y+163288X0180Y         S0      
317GND              VIA   -    MD0100PA00X+162720Y+163788X0180Y         S0      
317GND              VIA   -    MD0100PA00X+162224Y+163288X0180Y         S0      
317GND              VIA   -    MD0100PA00X+162224Y+163788X0180Y         S0      
317GND              VIA   -    MD0100PA00X+162828Y+162288X0180Y         S0      
317GND              VIA   -    MD0100PA00X+162117Y+162288X0180Y         S0      
317GND              VIA   -    MD0100PA00X+160911Y+165979X0180Y         S0      
317GND              VIA   -    MD0100PA00X+161622Y+165979X0180Y         S0      
317GND              VIA   -    MD0100PA00X+160416Y+165979X0180Y         S0      
317GND              VIA   -    MD0100PA00X+161018Y+164480X0180Y         S0      
317GND              VIA   -    MD0100PA00X+161514Y+164480X0180Y         S0      
317GND              VIA   -    MD0100PA00X+161018Y+164979X0180Y         S0      
317GND              VIA   -    MD0100PA00X+161514Y+164979X0180Y         S0      
317GND              VIA   -    MD0100PA00X+160911Y+165480X0180Y         S0      
317GND              VIA   -    MD0100PA00X+161622Y+165480X0180Y         S0      
317GND              VIA   -    MD0100PA00X+160416Y+165480X0180Y         S0      
317GND              VIA   -    MD0100PA00X+161622Y+162788X0180Y         S0      
317GND              VIA   -    MD0100PA00X+160911Y+162788X0180Y         S0      
317GND              VIA   -    MD0100PA00X+160416Y+162788X0180Y         S0      
317GND              VIA   -    MD0100PA00X+161514Y+163288X0180Y         S0      
317GND              VIA   -    MD0100PA00X+161018Y+163288X0180Y         S0      
317GND              VIA   -    MD0100PA00X+161514Y+163788X0180Y         S0      
317GND              VIA   -    MD0100PA00X+161018Y+163788X0180Y         S0      
317GND              VIA   -    MD0100PA00X+161622Y+162288X0180Y         S0      
317GND              VIA   -    MD0100PA00X+160416Y+162288X0180Y         S0      
317GND              VIA   -    MD0100PA00X+160911Y+162288X0180Y         S0      
317GND              VIA   -    MD0100PA00X+159705Y+165979X0180Y         S0      
317GND              VIA   -    MD0100PA00X+159210Y+165979X0180Y         S0      
317GND              VIA   -    MD0100PA00X+159812Y+164480X0180Y         S0      
317GND              VIA   -    MD0100PA00X+160308Y+164480X0180Y         S0      
317GND              VIA   -    MD0100PA00X+159102Y+164480X0180Y         S0      
317GND              VIA   -    MD0100PA00X+159812Y+164979X0180Y         S0      
317GND              VIA   -    MD0100PA00X+160308Y+164979X0180Y         S0      
317GND              VIA   -    MD0100PA00X+159705Y+165480X0180Y         S0      
317GND              VIA   -    MD0100PA00X+159102Y+164979X0180Y         S0      
317GND              VIA   -    MD0100PA00X+159210Y+165480X0180Y         S0      
317GND              VIA   -    MD0100PA00X+159705Y+162788X0180Y         S0      
317GND              VIA   -    MD0100PA00X+159210Y+162788X0180Y         S0      
317GND              VIA   -    MD0100PA00X+160308Y+163288X0180Y         S0      
317GND              VIA   -    MD0100PA00X+159812Y+163288X0180Y         S0      
317GND              VIA   -    MD0100PA00X+160308Y+163788X0180Y         S0      
317GND              VIA   -    MD0100PA00X+159812Y+163788X0180Y         S0      
317GND              VIA   -    MD0100PA00X+159102Y+163288X0180Y         S0      
317GND              VIA   -    MD0100PA00X+159102Y+163788X0180Y         S0      
317GND              VIA   -    MD0100PA00X+159210Y+162288X0180Y         S0      
317GND              VIA   -    MD0100PA00X+159705Y+162288X0180Y         S0      
317GND              VIA   -    MD0100PA00X+158499Y+165979X0180Y         S0      
317GND              VIA   -    MD0100PA00X+158004Y+165979X0180Y         S0      
317GND              VIA   -    MD0100PA00X+158606Y+164480X0180Y         S0      
317GND              VIA   -    MD0100PA00X+157896Y+164480X0180Y         S0      
317GND              VIA   -    MD0100PA00X+157400Y+164480X0180Y         S0      
317GND              VIA   -    MD0100PA00X+158606Y+164979X0180Y         S0      
317GND              VIA   -    MD0100PA00X+158499Y+165480X0180Y         S0      
317GND              VIA   -    MD0100PA00X+157896Y+164979X0180Y         S0      
317GND              VIA   -    MD0100PA00X+158004Y+165480X0180Y         S0      
317GND              VIA   -    MD0100PA00X+157400Y+164979X0180Y         S0      
317GND              VIA   -    MD0100PA00X+158499Y+162788X0180Y         S0      
317GND              VIA   -    MD0100PA00X+158004Y+162788X0180Y         S0      
317GND              VIA   -    MD0100PA00X+158606Y+163288X0180Y         S0      
317GND              VIA   -    MD0100PA00X+158606Y+163788X0180Y         S0      
317GND              VIA   -    MD0100PA00X+157896Y+163288X0180Y         S0      
317GND              VIA   -    MD0100PA00X+157896Y+163788X0180Y         S0      
317GND              VIA   -    MD0100PA00X+157400Y+163288X0180Y         S0      
317GND              VIA   -    MD0100PA00X+157400Y+163788X0180Y         S0      
317GND              VIA   -    MD0100PA00X+158004Y+162288X0180Y         S0      
317GND              VIA   -    MD0100PA00X+158499Y+162288X0180Y         S0      
317GND              VIA   -    MD0100PA00X+157293Y+165979X0180Y         S0      
317GND              VIA   -    MD0100PA00X+156798Y+165979X0180Y         S0      
317GND              VIA   -    MD0100PA00X+156087Y+165979X0180Y         S0      
317GND              VIA   -    MD0100PA00X+156690Y+164480X0180Y         S0      
317GND              VIA   -    MD0100PA00X+156194Y+164480X0180Y         S0      
317GND              VIA   -    MD0100PA00X+156690Y+164979X0180Y         S0      
317GND              VIA   -    MD0100PA00X+157293Y+165480X0180Y         S0      
317GND              VIA   -    MD0100PA00X+156798Y+165480X0180Y         S0      
317GND              VIA   -    MD0100PA00X+156194Y+164979X0180Y         S0      
317GND              VIA   -    MD0100PA00X+156087Y+165480X0180Y         S0      
317GND              VIA   -    MD0100PA00X+156798Y+162788X0180Y         S0      
317GND              VIA   -    MD0100PA00X+157293Y+162788X0180Y         S0      
317GND              VIA   -    MD0100PA00X+156087Y+162788X0180Y         S0      
317GND              VIA   -    MD0100PA00X+156690Y+163288X0180Y         S0      
317GND              VIA   -    MD0100PA00X+156690Y+163788X0180Y         S0      
317GND              VIA   -    MD0100PA00X+156194Y+163288X0180Y         S0      
317GND              VIA   -    MD0100PA00X+156194Y+163788X0180Y         S0      
317GND              VIA   -    MD0100PA00X+156798Y+162288X0180Y         S0      
317GND              VIA   -    MD0100PA00X+157293Y+162288X0180Y         S0      
317GND              VIA   -    MD0100PA00X+156087Y+162288X0180Y         S0      
317GND              VIA   -    MD0100PA00X+154881Y+165979X0180Y         S0      
317GND              VIA   -    MD0100PA00X+155592Y+165979X0180Y         S0      
317GND              VIA   -    MD0100PA00X+154386Y+165979X0180Y         S0      
317GND              VIA   -    MD0100PA00X+154988Y+164480X0180Y         S0      
317GND              VIA   -    MD0100PA00X+155484Y+164480X0180Y         S0      
317GND              VIA   -    MD0100PA00X+154988Y+164979X0180Y         S0      
317GND              VIA   -    MD0100PA00X+155484Y+164979X0180Y         S0      
317GND              VIA   -    MD0100PA00X+154881Y+165480X0180Y         S0      
317GND              VIA   -    MD0100PA00X+155592Y+165480X0180Y         S0      
317GND              VIA   -    MD0100PA00X+154386Y+165480X0180Y         S0      
317GND              VIA   -    MD0100PA00X+155592Y+162788X0180Y         S0      
317GND              VIA   -    MD0100PA00X+154881Y+162788X0180Y         S0      
317GND              VIA   -    MD0100PA00X+154386Y+162788X0180Y         S0      
317GND              VIA   -    MD0100PA00X+155484Y+163288X0180Y         S0      
317GND              VIA   -    MD0100PA00X+154988Y+163288X0180Y         S0      
317GND              VIA   -    MD0100PA00X+155484Y+163788X0180Y         S0      
317GND              VIA   -    MD0100PA00X+154988Y+163788X0180Y         S0      
317GND              VIA   -    MD0100PA00X+155592Y+162288X0180Y         S0      
317GND              VIA   -    MD0100PA00X+154386Y+162288X0180Y         S0      
317GND              VIA   -    MD0100PA00X+154881Y+162288X0180Y         S0      
317GND              VIA   -    MD0100PA00X+153675Y+165979X0180Y         S0      
317GND              VIA   -    MD0100PA00X+153180Y+165979X0180Y         S0      
317GND              VIA   -    MD0100PA00X+153782Y+164480X0180Y         S0      
317GND              VIA   -    MD0100PA00X+154278Y+164480X0180Y         S0      
317GND              VIA   -    MD0100PA00X+153072Y+164480X0180Y         S0      
317GND              VIA   -    MD0100PA00X+153782Y+164979X0180Y         S0      
317GND              VIA   -    MD0100PA00X+154278Y+164979X0180Y         S0      
317GND              VIA   -    MD0100PA00X+153675Y+165480X0180Y         S0      
317GND              VIA   -    MD0100PA00X+153072Y+164979X0180Y         S0      
317GND              VIA   -    MD0100PA00X+153180Y+165480X0180Y         S0      
317GND              VIA   -    MD0100PA00X+153675Y+162788X0180Y         S0      
317GND              VIA   -    MD0100PA00X+153180Y+162788X0180Y         S0      
317GND              VIA   -    MD0100PA00X+154278Y+163279X0180Y         S0      
317GND              VIA   -    MD0100PA00X+153782Y+163279X0180Y         S0      
317GND              VIA   -    MD0100PA00X+154278Y+163788X0180Y         S0      
317GND              VIA   -    MD0100PA00X+153782Y+163788X0180Y         S0      
317GND              VIA   -    MD0100PA00X+153072Y+163288X0180Y         S0      
317GND              VIA   -    MD0100PA00X+153072Y+163788X0180Y         S0      
317GND              VIA   -    MD0100PA00X+153180Y+162288X0180Y         S0      
317GND              VIA   -    MD0100PA00X+153675Y+162288X0180Y         S0      
317GND              VIA   -    MD0100PA00X+151974Y+165979X0180Y         S0      
317GND              VIA   -    MD0100PA00X+152499Y+165979X0180Y         S0      
317GND              VIA   -    MD0100PA00X+152576Y+164480X0180Y         S0      
317GND              VIA   -    MD0100PA00X+151866Y+164480X0180Y         S0      
317GND              VIA   -    MD0100PA00X+152576Y+164979X0180Y         S0      
317GND              VIA   -    MD0100PA00X+151974Y+165480X0180Y         S0      
317GND              VIA   -    MD0100PA00X+152469Y+165480X0180Y         S0      
317GND              VIA   -    MD0100PA00X+151866Y+164979X0180Y         S0      
317GND              VIA   -    MD0100PA00X+152469Y+162788X0180Y         S0      
317GND              VIA   -    MD0100PA00X+151974Y+162788X0180Y         S0      
317GND              VIA   -    MD0100PA00X+152576Y+163288X0180Y         S0      
317GND              VIA   -    MD0100PA00X+152576Y+163788X0180Y         S0      
317GND              VIA   -    MD0100PA00X+151866Y+163288X0180Y         S0      
317GND              VIA   -    MD0100PA00X+151866Y+163788X0180Y         S0      
317GND              VIA   -    MD0100PA00X+151974Y+162288X0180Y         S0      
317GND              VIA   -    MD0100PA00X+152469Y+162288X0180Y         S0      
317GND              VIA   -    MD0100PA00X+150768Y+165979X0180Y         S0      
317GND              VIA   -    MD0100PA00X+150057Y+165979X0180Y         S0      
317GND              VIA   -    MD0100PA00X+150660Y+164480X0180Y         S0      
317GND              VIA   -    MD0100PA00X+151370Y+164480X0180Y         S0      
317GND              VIA   -    MD0100PA00X+150164Y+164480X0180Y         S0      
317GND              VIA   -    MD0100PA00X+150660Y+164979X0180Y         S0      
317GND              VIA   -    MD0100PA00X+151370Y+164979X0180Y         S0      
317GND              VIA   -    MD0100PA00X+151263Y+165480X0180Y         S0      
317GND              VIA   -    MD0100PA00X+150768Y+165480X0180Y         S0      
317GND              VIA   -    MD0100PA00X+150164Y+164979X0180Y         S0      
317GND              VIA   -    MD0100PA00X+150057Y+165480X0180Y         S0      
317GND              VIA   -    MD0100PA00X+150768Y+162788X0180Y         S0      
317GND              VIA   -    MD0100PA00X+151263Y+162788X0180Y         S0      
317GND              VIA   -    MD0100PA00X+150057Y+162788X0180Y         S0      
317GND              VIA   -    MD0100PA00X+151370Y+163288X0180Y         S0      
317GND              VIA   -    MD0100PA00X+151370Y+163788X0180Y         S0      
317GND              VIA   -    MD0100PA00X+150660Y+163288X0180Y         S0      
317GND              VIA   -    MD0100PA00X+150660Y+163788X0180Y         S0      
317GND              VIA   -    MD0100PA00X+150164Y+163288X0180Y         S0      
317GND              VIA   -    MD0100PA00X+150164Y+163788X0180Y         S0      
317GND              VIA   -    MD0100PA00X+150768Y+162288X0180Y         S0      
317GND              VIA   -    MD0100PA00X+151263Y+162288X0180Y         S0      
317GND              VIA   -    MD0100PA00X+150057Y+162288X0180Y         S0      
317GND              VIA   -    MD0100PA00X+149562Y+165979X0180Y         S0      
317GND              VIA   -    MD0100PA00X+148851Y+165979X0180Y         S0      
317GND              VIA   -    MD0100PA00X+149454Y+164480X0180Y         S0      
317GND              VIA   -    MD0100PA00X+148958Y+164480X0180Y         S0      
317GND              VIA   -    MD0100PA00X+149454Y+164979X0180Y         S0      
317GND              VIA   -    MD0100PA00X+148958Y+164979X0180Y         S0      
317GND              VIA   -    MD0100PA00X+149562Y+165480X0180Y         S0      
317GND              VIA   -    MD0100PA00X+148851Y+165480X0180Y         S0      
317GND              VIA   -    MD0100PA00X+149562Y+162788X0180Y         S0      
317GND              VIA   -    MD0100PA00X+148851Y+162788X0180Y         S0      
317GND              VIA   -    MD0100PA00X+148958Y+163288X0180Y         S0      
317GND              VIA   -    MD0100PA00X+149454Y+163288X0180Y         S0      
317GND              VIA   -    MD0100PA00X+148958Y+163788X0180Y         S0      
317GND              VIA   -    MD0100PA00X+149454Y+163788X0180Y         S0      
317GND              VIA   -    MD0100PA00X+149562Y+162288X0180Y         S0      
317GND              VIA   -    MD0100PA00X+148851Y+162288X0180Y         S0      
317GND              VIA   -    MD0100PA00X+148356Y+165979X0180Y         S0      
317GND              VIA   -    MD0100PA00X+147645Y+165979X0180Y         S0      
317GND              VIA   -    MD0100PA00X+147150Y+165979X0180Y         S0      
317GND              VIA   -    MD0100PA00X+148248Y+164480X0180Y         S0      
317GND              VIA   -    MD0100PA00X+147752Y+164480X0180Y         S0      
317GND              VIA   -    MD0100PA00X+147042Y+164480X0180Y         S0      
317GND              VIA   -    MD0100PA00X+147752Y+164979X0180Y         S0      
317GND              VIA   -    MD0100PA00X+148248Y+164979X0180Y         S0      
317GND              VIA   -    MD0100PA00X+148356Y+165480X0180Y         S0      
317GND              VIA   -    MD0100PA00X+147645Y+165480X0180Y         S0      
317GND              VIA   -    MD0100PA00X+147042Y+164979X0180Y         S0      
317GND              VIA   -    MD0100PA00X+147150Y+165480X0180Y         S0      
317GND              VIA   -    MD0100PA00X+147645Y+162788X0180Y         S0      
317GND              VIA   -    MD0100PA00X+148356Y+162788X0180Y         S0      
317GND              VIA   -    MD0100PA00X+147150Y+162788X0180Y         S0      
317GND              VIA   -    MD0100PA00X+147752Y+163288X0180Y         S0      
317GND              VIA   -    MD0100PA00X+148248Y+163288X0180Y         S0      
317GND              VIA   -    MD0100PA00X+147752Y+163788X0180Y         S0      
317GND              VIA   -    MD0100PA00X+148248Y+163788X0180Y         S0      
317GND              VIA   -    MD0100PA00X+147042Y+163788X0180Y         S0      
317GND              VIA   -    MD0100PA00X+147042Y+163288X0180Y         S0      
317GND              VIA   -    MD0100PA00X+148356Y+162288X0180Y         S0      
317GND              VIA   -    MD0100PA00X+147150Y+162288X0180Y         S0      
317GND              VIA   -    MD0100PA00X+147645Y+162288X0180Y         S0      
317GND              VIA   -    MD0100PA00X+146439Y+165979X0180Y         S0      
317GND              VIA   -    MD0100PA00X+146546Y+164480X0180Y         S0      
317GND              VIA   -    MD0100PA00X+146546Y+164979X0180Y         S0      
317GND              VIA   -    MD0100PA00X+146439Y+165480X0180Y         S0      
317GND              VIA   -    MD0100PA00X+146439Y+162788X0180Y         S0      
317GND              VIA   -    MD0100PA00X+145944Y+162788X0180Y         S0      
317GND              VIA   -    MD0100PA00X+146546Y+163288X0180Y         S0      
317GND              VIA   -    MD0100PA00X+146546Y+163788X0180Y         S0      
317GND              VIA   -    MD0100PA00X+145944Y+162288X0180Y         S0      
317GND              VIA   -    MD0100PA00X+146439Y+162288X0180Y         S0      
317GND              VIA   -    MD0100PA00X+138112Y+165979X0180Y         S0      
317GND              VIA   -    MD0100PA00X+138715Y+164480X0180Y         S0      
317GND              VIA   -    MD0100PA00X+138219Y+164480X0180Y         S0      
317GND              VIA   -    MD0100PA00X+138715Y+164979X0180Y         S0      
317GND              VIA   -    MD0100PA00X+138219Y+164979X0180Y         S0      
317GND              VIA   -    MD0100PA00X+138112Y+165480X0180Y         S0      
317GND              VIA   -    MD0100PA00X+138112Y+162788X0180Y         S0      
317GND              VIA   -    MD0100PA00X+138715Y+163288X0180Y         S0      
317GND              VIA   -    MD0100PA00X+138219Y+163288X0180Y         S0      
317GND              VIA   -    MD0100PA00X+138715Y+163788X0180Y         S0      
317GND              VIA   -    MD0100PA00X+138219Y+163788X0180Y         S0      
317GND              VIA   -    MD0100PA00X+138112Y+162288X0180Y         S0      
317GND              VIA   -    MD0100PA00X+137616Y+165979X0180Y         S0      
317GND              VIA   -    MD0100PA00X+136906Y+165979X0180Y         S0      
317GND              VIA   -    MD0100PA00X+137509Y+164480X0180Y         S0      
317GND              VIA   -    MD0100PA00X+137013Y+164480X0180Y         S0      
317GND              VIA   -    MD0100PA00X+137509Y+164979X0180Y         S0      
317GND              VIA   -    MD0100PA00X+137616Y+165480X0180Y         S0      
317GND              VIA   -    MD0100PA00X+137013Y+164979X0180Y         S0      
317GND              VIA   -    MD0100PA00X+136906Y+165480X0180Y         S0      
317GND              VIA   -    MD0100PA00X+137616Y+162788X0180Y         S0      
317GND              VIA   -    MD0100PA00X+136906Y+162788X0180Y         S0      
317GND              VIA   -    MD0100PA00X+137509Y+163279X0180Y         S0      
317GND              VIA   -    MD0100PA00X+137509Y+163788X0180Y         S0      
317GND              VIA   -    MD0100PA00X+137013Y+163279X0180Y         S0      
317GND              VIA   -    MD0100PA00X+137013Y+163788X0180Y         S0      
317GND              VIA   -    MD0100PA00X+137616Y+162288X0180Y         S0      
317GND              VIA   -    MD0100PA00X+136906Y+162288X0180Y         S0      
317GND              VIA   -    MD0100PA00X+136410Y+165979X0180Y         S0      
317GND              VIA   -    MD0100PA00X+135700Y+165979X0180Y         S0      
317GND              VIA   -    MD0100PA00X+135204Y+165979X0180Y         S0      
317GND              VIA   -    MD0100PA00X+136303Y+164480X0180Y         S0      
317GND              VIA   -    MD0100PA00X+135097Y+164480X0180Y         S0      
317GND              VIA   -    MD0100PA00X+135807Y+164480X0180Y         S0      
317GND              VIA   -    MD0100PA00X+136303Y+164979X0180Y         S0      
317GND              VIA   -    MD0100PA00X+136410Y+165480X0180Y         S0      
317GND              VIA   -    MD0100PA00X+135097Y+164979X0180Y         S0      
317GND              VIA   -    MD0100PA00X+135807Y+164979X0180Y         S0      
317GND              VIA   -    MD0100PA00X+135700Y+165480X0180Y         S0      
317GND              VIA   -    MD0100PA00X+135204Y+165480X0180Y         S0      
317GND              VIA   -    MD0100PA00X+136410Y+162788X0180Y         S0      
317GND              VIA   -    MD0100PA00X+135204Y+162788X0180Y         S0      
317GND              VIA   -    MD0100PA00X+135700Y+162788X0180Y         S0      
317GND              VIA   -    MD0100PA00X+136303Y+163288X0180Y         S0      
317GND              VIA   -    MD0100PA00X+136303Y+163788X0180Y         S0      
317GND              VIA   -    MD0100PA00X+135807Y+163288X0180Y         S0      
317GND              VIA   -    MD0100PA00X+135807Y+163788X0180Y         S0      
317GND              VIA   -    MD0100PA00X+135097Y+163288X0180Y         S0      
317GND              VIA   -    MD0100PA00X+135097Y+163788X0180Y         S0      
317GND              VIA   -    MD0100PA00X+136410Y+162288X0180Y         S0      
317GND              VIA   -    MD0100PA00X+135700Y+162288X0180Y         S0      
317GND              VIA   -    MD0100PA00X+135204Y+162288X0180Y         S0      
317GND              VIA   -    MD0100PA00X+134494Y+165979X0180Y         S0      
317GND              VIA   -    MD0100PA00X+133998Y+165979X0180Y         S0      
317GND              VIA   -    MD0100PA00X+134601Y+164480X0180Y         S0      
317GND              VIA   -    MD0100PA00X+133891Y+164480X0180Y         S0      
317GND              VIA   -    MD0100PA00X+134601Y+164979X0180Y         S0      
317GND              VIA   -    MD0100PA00X+134494Y+165480X0180Y         S0      
317GND              VIA   -    MD0100PA00X+133891Y+164979X0180Y         S0      
317GND              VIA   -    MD0100PA00X+133998Y+165480X0180Y         S0      
317GND              VIA   -    MD0100PA00X+134494Y+162788X0180Y         S0      
317GND              VIA   -    MD0100PA00X+133998Y+162788X0180Y         S0      
317GND              VIA   -    MD0100PA00X+134601Y+163288X0180Y         S0      
317GND              VIA   -    MD0100PA00X+134601Y+163788X0180Y         S0      
317GND              VIA   -    MD0100PA00X+133891Y+163288X0180Y         S0      
317GND              VIA   -    MD0100PA00X+133891Y+163788X0180Y         S0      
317GND              VIA   -    MD0100PA00X+134494Y+162288X0180Y         S0      
317GND              VIA   -    MD0100PA00X+133998Y+162288X0180Y         S0      
317GND              VIA   -    MD0100PA00X+133288Y+165979X0180Y         S0      
317GND              VIA   -    MD0100PA00X+132792Y+165979X0180Y         S0      
317GND              VIA   -    MD0100PA00X+132082Y+165979X0180Y         S0      
317GND              VIA   -    MD0100PA00X+133395Y+164480X0180Y         S0      
317GND              VIA   -    MD0100PA00X+132189Y+164480X0180Y         S0      
317GND              VIA   -    MD0100PA00X+132685Y+164480X0180Y         S0      
317GND              VIA   -    MD0100PA00X+133395Y+164979X0180Y         S0      
317GND              VIA   -    MD0100PA00X+133288Y+165480X0180Y         S0      
317GND              VIA   -    MD0100PA00X+132189Y+164979X0180Y         S0      
317GND              VIA   -    MD0100PA00X+132685Y+164979X0180Y         S0      
317GND              VIA   -    MD0100PA00X+132792Y+165480X0180Y         S0      
317GND              VIA   -    MD0100PA00X+132082Y+165480X0180Y         S0      
317GND              VIA   -    MD0100PA00X+133288Y+162788X0180Y         S0      
317GND              VIA   -    MD0100PA00X+132082Y+162788X0180Y         S0      
317GND              VIA   -    MD0100PA00X+132792Y+162788X0180Y         S0      
317GND              VIA   -    MD0100PA00X+133395Y+163288X0180Y         S0      
317GND              VIA   -    MD0100PA00X+133395Y+163788X0180Y         S0      
317GND              VIA   -    MD0100PA00X+132685Y+163288X0180Y         S0      
317GND              VIA   -    MD0100PA00X+132189Y+163288X0180Y         S0      
317GND              VIA   -    MD0100PA00X+132685Y+163788X0180Y         S0      
317GND              VIA   -    MD0100PA00X+132189Y+163788X0180Y         S0      
317GND              VIA   -    MD0100PA00X+133288Y+162288X0180Y         S0      
317GND              VIA   -    MD0100PA00X+132082Y+162288X0180Y         S0      
317GND              VIA   -    MD0100PA00X+132792Y+162288X0180Y         S0      
317GND              VIA   -    MD0100PA00X+131586Y+165979X0180Y         S0      
317GND              VIA   -    MD0100PA00X+130876Y+165979X0180Y         S0      
317GND              VIA   -    MD0100PA00X+131479Y+164480X0180Y         S0      
317GND              VIA   -    MD0100PA00X+130983Y+164480X0180Y         S0      
317GND              VIA   -    MD0100PA00X+131479Y+164979X0180Y         S0      
317GND              VIA   -    MD0100PA00X+131586Y+165480X0180Y         S0      
317GND              VIA   -    MD0100PA00X+130983Y+164979X0180Y         S0      
317GND              VIA   -    MD0100PA00X+130876Y+165480X0180Y         S0      
317GND              VIA   -    MD0100PA00X+131586Y+162788X0180Y         S0      
317GND              VIA   -    MD0100PA00X+130876Y+162788X0180Y         S0      
317GND              VIA   -    MD0100PA00X+131479Y+163288X0180Y         S0      
317GND              VIA   -    MD0100PA00X+131479Y+163788X0180Y         S0      
317GND              VIA   -    MD0100PA00X+130983Y+163288X0180Y         S0      
317GND              VIA   -    MD0100PA00X+130983Y+163788X0180Y         S0      
317GND              VIA   -    MD0100PA00X+131586Y+162288X0180Y         S0      
317GND              VIA   -    MD0100PA00X+130876Y+162288X0180Y         S0      
317GND              VIA   -    MD0100PA00X+130380Y+165979X0180Y         S0      
317GND              VIA   -    MD0100PA00X+129670Y+165979X0180Y         S0      
317GND              VIA   -    MD0100PA00X+129174Y+165979X0180Y         S0      
317GND              VIA   -    MD0100PA00X+130273Y+164480X0180Y         S0      
317GND              VIA   -    MD0100PA00X+129067Y+164480X0180Y         S0      
317GND              VIA   -    MD0100PA00X+129777Y+164480X0180Y         S0      
317GND              VIA   -    MD0100PA00X+130273Y+164979X0180Y         S0      
317GND              VIA   -    MD0100PA00X+130380Y+165480X0180Y         S0      
317GND              VIA   -    MD0100PA00X+129067Y+164979X0180Y         S0      
317GND              VIA   -    MD0100PA00X+129777Y+164979X0180Y         S0      
317GND              VIA   -    MD0100PA00X+129670Y+165480X0180Y         S0      
317GND              VIA   -    MD0100PA00X+129174Y+165480X0180Y         S0      
317GND              VIA   -    MD0100PA00X+130380Y+162788X0180Y         S0      
317GND              VIA   -    MD0100PA00X+129174Y+162788X0180Y         S0      
317GND              VIA   -    MD0100PA00X+129670Y+162788X0180Y         S0      
317GND              VIA   -    MD0100PA00X+130273Y+163288X0180Y         S0      
317GND              VIA   -    MD0100PA00X+130273Y+163788X0180Y         S0      
317GND              VIA   -    MD0100PA00X+129777Y+163288X0180Y         S0      
317GND              VIA   -    MD0100PA00X+129777Y+163788X0180Y         S0      
317GND              VIA   -    MD0100PA00X+129067Y+163288X0180Y         S0      
317GND              VIA   -    MD0100PA00X+129067Y+163788X0180Y         S0      
317GND              VIA   -    MD0100PA00X+130380Y+162288X0180Y         S0      
317GND              VIA   -    MD0100PA00X+129670Y+162288X0180Y         S0      
317GND              VIA   -    MD0100PA00X+129174Y+162288X0180Y         S0      
317GND              VIA   -    MD0100PA00X+128464Y+165979X0180Y         S0      
317GND              VIA   -    MD0100PA00X+127968Y+165979X0180Y         S0      
317GND              VIA   -    MD0100PA00X+128571Y+164480X0180Y         S0      
317GND              VIA   -    MD0100PA00X+127861Y+164480X0180Y         S0      
317GND              VIA   -    MD0100PA00X+128571Y+164979X0180Y         S0      
317GND              VIA   -    MD0100PA00X+128464Y+165480X0180Y         S0      
317GND              VIA   -    MD0100PA00X+127861Y+164979X0180Y         S0      
317GND              VIA   -    MD0100PA00X+127968Y+165480X0180Y         S0      
317GND              VIA   -    MD0100PA00X+128464Y+162788X0180Y         S0      
317GND              VIA   -    MD0100PA00X+127968Y+162788X0180Y         S0      
317GND              VIA   -    MD0100PA00X+128571Y+163288X0180Y         S0      
317GND              VIA   -    MD0100PA00X+128571Y+163788X0180Y         S0      
317GND              VIA   -    MD0100PA00X+127861Y+163279X0180Y         S0      
317GND              VIA   -    MD0100PA00X+127861Y+163788X0180Y         S0      
317GND              VIA   -    MD0100PA00X+128464Y+162288X0180Y         S0      
317GND              VIA   -    MD0100PA00X+127968Y+162288X0180Y         S0      
317GND              VIA   -    MD0100PA00X+127258Y+165979X0180Y         S0      
317GND              VIA   -    MD0100PA00X+126762Y+165979X0180Y         S0      
317GND              VIA   -    MD0100PA00X+126052Y+165979X0180Y         S0      
317GND              VIA   -    MD0100PA00X+127365Y+164480X0180Y         S0      
317GND              VIA   -    MD0100PA00X+126159Y+164480X0180Y         S0      
317GND              VIA   -    MD0100PA00X+126655Y+164480X0180Y         S0      
317GND              VIA   -    MD0100PA00X+127365Y+164979X0180Y         S0      
317GND              VIA   -    MD0100PA00X+127258Y+165480X0180Y         S0      
317GND              VIA   -    MD0100PA00X+126159Y+164979X0180Y         S0      
317GND              VIA   -    MD0100PA00X+126655Y+164979X0180Y         S0      
317GND              VIA   -    MD0100PA00X+126762Y+165480X0180Y         S0      
317GND              VIA   -    MD0100PA00X+126052Y+165480X0180Y         S0      
317GND              VIA   -    MD0100PA00X+127258Y+162788X0180Y         S0      
317GND              VIA   -    MD0100PA00X+126052Y+162788X0180Y         S0      
317GND              VIA   -    MD0100PA00X+126762Y+162788X0180Y         S0      
317GND              VIA   -    MD0100PA00X+127365Y+163279X0180Y         S0      
317GND              VIA   -    MD0100PA00X+127365Y+163788X0180Y         S0      
317GND              VIA   -    MD0100PA00X+126655Y+163288X0180Y         S0      
317GND              VIA   -    MD0100PA00X+126159Y+163288X0180Y         S0      
317GND              VIA   -    MD0100PA00X+126655Y+163788X0180Y         S0      
317GND              VIA   -    MD0100PA00X+126159Y+163788X0180Y         S0      
317GND              VIA   -    MD0100PA00X+127258Y+162288X0180Y         S0      
317GND              VIA   -    MD0100PA00X+126052Y+162288X0180Y         S0      
317GND              VIA   -    MD0100PA00X+126762Y+162288X0180Y         S0      
317GND              VIA   -    MD0100PA00X+125556Y+165979X0180Y         S0      
317GND              VIA   -    MD0100PA00X+124866Y+165959X0180Y         S0      
317GND              VIA   -    MD0100PA00X+124953Y+164480X0180Y         S0      
317GND              VIA   -    MD0100PA00X+125449Y+164480X0180Y         S0      
317GND              VIA   -    MD0100PA00X+125556Y+165480X0180Y         S0      
317GND              VIA   -    MD0100PA00X+124953Y+164979X0180Y         S0      
317GND              VIA   -    MD0100PA00X+125449Y+164979X0180Y         S0      
317GND              VIA   -    MD0100PA00X+124846Y+165480X0180Y         S0      
317GND              VIA   -    MD0100PA00X+125556Y+162788X0180Y         S0      
317GND              VIA   -    MD0100PA00X+124846Y+162788X0180Y         S0      
317GND              VIA   -    MD0100PA00X+124953Y+163288X0180Y         S0      
317GND              VIA   -    MD0100PA00X+124953Y+163788X0180Y         S0      
317GND              VIA   -    MD0100PA00X+125449Y+163288X0180Y         S0      
317GND              VIA   -    MD0100PA00X+125449Y+163788X0180Y         S0      
317GND              VIA   -    MD0100PA00X+125556Y+162288X0180Y         S0      
317GND              VIA   -    MD0100PA00X+124846Y+162288X0180Y         S0      
317GND              VIA   -    MD0100PA00X+124350Y+165979X0180Y         S0      
317GND              VIA   -    MD0100PA00X+123640Y+165979X0180Y         S0      
317GND              VIA   -    MD0100PA00X+123144Y+165979X0180Y         S0      
317GND              VIA   -    MD0100PA00X+124243Y+164480X0180Y         S0      
317GND              VIA   -    MD0100PA00X+123747Y+164480X0180Y         S0      
317GND              VIA   -    MD0100PA00X+124243Y+164979X0180Y         S0      
317GND              VIA   -    MD0100PA00X+124350Y+165480X0180Y         S0      
317GND              VIA   -    MD0100PA00X+123747Y+164979X0180Y         S0      
317GND              VIA   -    MD0100PA00X+123640Y+165480X0180Y         S0      
317GND              VIA   -    MD0100PA00X+123144Y+165480X0180Y         S0      
317GND              VIA   -    MD0100PA00X+124350Y+162788X0180Y         S0      
317GND              VIA   -    MD0100PA00X+123144Y+162788X0180Y         S0      
317GND              VIA   -    MD0100PA00X+123640Y+162788X0180Y         S0      
317GND              VIA   -    MD0100PA00X+124243Y+163288X0180Y         S0      
317GND              VIA   -    MD0100PA00X+124243Y+163788X0180Y         S0      
317GND              VIA   -    MD0100PA00X+123747Y+163288X0180Y         S0      
317GND              VIA   -    MD0100PA00X+123747Y+163788X0180Y         S0      
317GND              VIA   -    MD0100PA00X+124350Y+162288X0180Y         S0      
317GND              VIA   -    MD0100PA00X+123640Y+162288X0180Y         S0      
317GND              VIA   -    MD0100PA00X+123144Y+162288X0180Y         S0      
317GND              VIA   -    MD0100PA00X+121938Y+165979X0180Y         S0      
317GND              VIA   -    MD0100PA00X+122434Y+165979X0180Y         S0      
317GND              VIA   -    MD0100PA00X+123037Y+164480X0180Y         S0      
317GND              VIA   -    MD0100PA00X+122541Y+164480X0180Y         S0      
317GND              VIA   -    MD0100PA00X+121831Y+164480X0180Y         S0      
317GND              VIA   -    MD0100PA00X+123037Y+164979X0180Y         S0      
317GND              VIA   -    MD0100PA00X+122541Y+164979X0180Y         S0      
317GND              VIA   -    MD0100PA00X+121831Y+164979X0180Y         S0      
317GND              VIA   -    MD0100PA00X+121938Y+165480X0180Y         S0      
317GND              VIA   -    MD0100PA00X+122434Y+165480X0180Y         S0      
317GND              VIA   -    MD0100PA00X+122434Y+162788X0180Y         S0      
317GND              VIA   -    MD0100PA00X+121938Y+162788X0180Y         S0      
317GND              VIA   -    MD0100PA00X+122541Y+163288X0180Y         S0      
317GND              VIA   -    MD0100PA00X+123037Y+163288X0180Y         S0      
317GND              VIA   -    MD0100PA00X+122541Y+163788X0180Y         S0      
317GND              VIA   -    MD0100PA00X+123037Y+163788X0180Y         S0      
317GND              VIA   -    MD0100PA00X+121831Y+163288X0180Y         S0      
317GND              VIA   -    MD0100PA00X+121831Y+163788X0180Y         S0      
317GND              VIA   -    MD0100PA00X+122434Y+162288X0180Y         S0      
317GND              VIA   -    MD0100PA00X+121938Y+162288X0180Y         S0      
317GND              VIA   -    MD0100PA00X+121228Y+165979X0180Y         S0      
317GND              VIA   -    MD0100PA00X+120732Y+165979X0180Y         S0      
317GND              VIA   -    MD0100PA00X+121335Y+164480X0180Y         S0      
317GND              VIA   -    MD0100PA00X+120129Y+164480X0180Y         S0      
317GND              VIA   -    MD0100PA00X+120625Y+164480X0180Y         S0      
317GND              VIA   -    MD0100PA00X+121335Y+164979X0180Y         S0      
317GND              VIA   -    MD0100PA00X+121228Y+165480X0180Y         S0      
317GND              VIA   -    MD0100PA00X+120129Y+164979X0180Y         S0      
317GND              VIA   -    MD0100PA00X+120625Y+164979X0180Y         S0      
317GND              VIA   -    MD0100PA00X+120732Y+165480X0180Y         S0      
317GND              VIA   -    MD0100PA00X+121228Y+162788X0180Y         S0      
317GND              VIA   -    MD0100PA00X+120732Y+162788X0180Y         S0      
317GND              VIA   -    MD0100PA00X+121335Y+163288X0180Y         S0      
317GND              VIA   -    MD0100PA00X+121335Y+163788X0180Y         S0      
317GND              VIA   -    MD0100PA00X+120625Y+163788X0180Y         S0      
317GND              VIA   -    MD0100PA00X+120625Y+163288X0180Y         S0      
317GND              VIA   -    MD0100PA00X+120129Y+163288X0180Y         S0      
317GND              VIA   -    MD0100PA00X+120129Y+163788X0180Y         S0      
317GND              VIA   -    MD0100PA00X+121228Y+162288X0180Y         S0      
317GND              VIA   -    MD0100PA00X+120732Y+162288X0180Y         S0      
317GND              VIA   -    MD0100PA00X+119526Y+165979X0180Y         S0      
317GND              VIA   -    MD0100PA00X+120022Y+165979X0180Y         S0      
317GND              VIA   -    MD0100PA00X+119526Y+165480X0180Y         S0      
317GND              VIA   -    MD0100PA00X+120022Y+165480X0180Y         S0      
317GND              VIA   -    MD0100PA00X+120022Y+162788X0180Y         S0      
317GND              VIA   -    MD0100PA00X+119526Y+162788X0180Y         S0      
317GND              VIA   -    MD0100PA00X+120022Y+162288X0180Y         S0      
317GND              VIA   -    MD0100PA00X+119526Y+162288X0180Y         S0      
317GND              VIA   -    MD0100PA00X+063742Y+162180X0180Y         S0      
317GND              VIA   -    MD0100PA00X+063849Y+161679X0180Y         S0      
317GND              VIA   -    MD0100PA00X+063742Y+162679X0180Y         S0      
317GND              VIA   -    MD0100PA00X+064345Y+161679X0180Y         S0      
317GND              VIA   -    MD0100PA00X+063849Y+161180X0180Y         S0      
317GND              VIA   -    MD0100PA00X+064345Y+161180X0180Y         S0      
317GND              VIA   -    MD0100PA00X+063849Y+160488X0180Y         S0      
317GND              VIA   -    MD0100PA00X+064345Y+160488X0180Y         S0      
317GND              VIA   -    MD0100PA00X+063849Y+159988X0180Y         S0      
317GND              VIA   -    MD0100PA00X+064345Y+159988X0180Y         S0      
317GND              VIA   -    MD0100PA00X+063742Y+159488X0180Y         S0      
317GND              VIA   -    MD0100PA00X+063742Y+158988X0180Y         S0      
317GND              VIA   -    MD0100PA00X+062536Y+162679X0180Y         S0      
317GND              VIA   -    MD0100PA00X+062040Y+162679X0180Y         S0      
317GND              VIA   -    MD0100PA00X+062536Y+162180X0180Y         S0      
317GND              VIA   -    MD0100PA00X+062040Y+162180X0180Y         S0      
317GND              VIA   -    MD0100PA00X+062643Y+161679X0180Y         S0      
317GND              VIA   -    MD0100PA00X+063246Y+162180X0180Y         S0      
317GND              VIA   -    MD0100PA00X+063246Y+162679X0180Y         S0      
317GND              VIA   -    MD0100PA00X+063139Y+161679X0180Y         S0      
317GND              VIA   -    MD0100PA00X+062643Y+160488X0180Y         S0      
317GND              VIA   -    MD0100PA00X+062643Y+159979X0180Y         S0      
317GND              VIA   -    MD0100PA00X+062643Y+161180X0180Y         S0      
317GND              VIA   -    MD0100PA00X+063139Y+160488X0180Y         S0      
317GND              VIA   -    MD0100PA00X+063139Y+159979X0180Y         S0      
317GND              VIA   -    MD0100PA00X+063139Y+161180X0180Y         S0      
317GND              VIA   -    MD0100PA00X+062536Y+159488X0180Y         S0      
317GND              VIA   -    MD0100PA00X+062040Y+159488X0180Y         S0      
317GND              VIA   -    MD0100PA00X+062536Y+158988X0180Y         S0      
317GND              VIA   -    MD0100PA00X+063246Y+159488X0180Y         S0      
317GND              VIA   -    MD0100PA00X+060834Y+162679X0180Y         S0      
317GND              VIA   -    MD0100PA00X+061330Y+162679X0180Y         S0      
317GND              VIA   -    MD0100PA00X+060834Y+162180X0180Y         S0      
317GND              VIA   -    MD0100PA00X+061330Y+162180X0180Y         S0      
317GND              VIA   -    MD0100PA00X+061437Y+161679X0180Y         S0      
317GND              VIA   -    MD0100PA00X+060727Y+161679X0180Y         S0      
317GND              VIA   -    MD0100PA00X+061933Y+161679X0180Y         S0      
317GND              VIA   -    MD0100PA00X+060727Y+160488X0180Y         S0      
317GND              VIA   -    MD0100PA00X+060727Y+159988X0180Y         S0      
317GND              VIA   -    MD0100PA00X+061437Y+160488X0180Y         S0      
317GND              VIA   -    MD0100PA00X+061437Y+159988X0180Y         S0      
317GND              VIA   -    MD0100PA00X+061437Y+161180X0180Y         S0      
317GND              VIA   -    MD0100PA00X+060727Y+161180X0180Y         S0      
317GND              VIA   -    MD0100PA00X+061933Y+160488X0180Y         S0      
317GND              VIA   -    MD0100PA00X+061933Y+159988X0180Y         S0      
317GND              VIA   -    MD0100PA00X+061933Y+161180X0180Y         S0      
317GND              VIA   -    MD0100PA00X+061330Y+159488X0180Y         S0      
317GND              VIA   -    MD0100PA00X+060834Y+159488X0180Y         S0      
317GND              VIA   -    MD0100PA00X+061330Y+158988X0180Y         S0      
317GND              VIA   -    MD0100PA00X+059628Y+162679X0180Y         S0      
317GND              VIA   -    MD0100PA00X+059628Y+162180X0180Y         S0      
317GND              VIA   -    MD0100PA00X+059521Y+161679X0180Y         S0      
317GND              VIA   -    MD0100PA00X+059025Y+161679X0180Y         S0      
317GND              VIA   -    MD0100PA00X+060124Y+162679X0180Y         S0      
317GND              VIA   -    MD0100PA00X+060124Y+162180X0180Y         S0      
317GND              VIA   -    MD0100PA00X+060231Y+161679X0180Y         S0      
317GND              VIA   -    MD0100PA00X+059025Y+160488X0180Y         S0      
317GND              VIA   -    MD0100PA00X+059521Y+160488X0180Y         S0      
317GND              VIA   -    MD0100PA00X+059025Y+159988X0180Y         S0      
317GND              VIA   -    MD0100PA00X+059521Y+159988X0180Y         S0      
317GND              VIA   -    MD0100PA00X+059521Y+161180X0180Y         S0      
317GND              VIA   -    MD0100PA00X+059025Y+161180X0180Y         S0      
317GND              VIA   -    MD0100PA00X+060231Y+160488X0180Y         S0      
317GND              VIA   -    MD0100PA00X+060231Y+159988X0180Y         S0      
317GND              VIA   -    MD0100PA00X+060231Y+161180X0180Y         S0      
317GND              VIA   -    MD0100PA00X+059628Y+159488X0180Y         S0      
317GND              VIA   -    MD0100PA00X+060124Y+159488X0180Y         S0      
317GND              VIA   -    MD0100PA00X+060124Y+158988X0180Y         S0      
317GND              VIA   -    MD0100PA00X+057712Y+162679X0180Y         S0      
317GND              VIA   -    MD0100PA00X+058422Y+162679X0180Y         S0      
317GND              VIA   -    MD0100PA00X+057712Y+162180X0180Y         S0      
317GND              VIA   -    MD0100PA00X+058422Y+162180X0180Y         S0      
317GND              VIA   -    MD0100PA00X+058315Y+161679X0180Y         S0      
317GND              VIA   -    MD0100PA00X+057819Y+161679X0180Y         S0      
317GND              VIA   -    MD0100PA00X+058918Y+162679X0180Y         S0      
317GND              VIA   -    MD0100PA00X+058918Y+162180X0180Y         S0      
317GND              VIA   -    MD0100PA00X+057819Y+160488X0180Y         S0      
317GND              VIA   -    MD0100PA00X+058315Y+160488X0180Y         S0      
317GND              VIA   -    MD0100PA00X+057819Y+159988X0180Y         S0      
317GND              VIA   -    MD0100PA00X+058315Y+159988X0180Y         S0      
317GND              VIA   -    MD0100PA00X+058315Y+161180X0180Y         S0      
317GND              VIA   -    MD0100PA00X+057819Y+161180X0180Y         S0      
317GND              VIA   -    MD0100PA00X+058422Y+159488X0180Y         S0      
317GND              VIA   -    MD0100PA00X+057712Y+159488X0180Y         S0      
317GND              VIA   -    MD0100PA00X+057712Y+158988X0180Y         S0      
317GND              VIA   -    MD0100PA00X+058918Y+159488X0180Y         S0      
317GND              VIA   -    MD0100PA00X+058918Y+158988X0180Y         S0      
317GND              VIA   -    MD0100PA00X+056010Y+162679X0180Y         S0      
317GND              VIA   -    MD0100PA00X+056506Y+162679X0180Y         S0      
317GND              VIA   -    MD0100PA00X+056010Y+162180X0180Y         S0      
317GND              VIA   -    MD0100PA00X+056506Y+162180X0180Y         S0      
317GND              VIA   -    MD0100PA00X+056613Y+161679X0180Y         S0      
317GND              VIA   -    MD0100PA00X+057216Y+162679X0180Y         S0      
317GND              VIA   -    MD0100PA00X+057216Y+162180X0180Y         S0      
317GND              VIA   -    MD0100PA00X+057109Y+161679X0180Y         S0      
317GND              VIA   -    MD0100PA00X+056613Y+160488X0180Y         S0      
317GND              VIA   -    MD0100PA00X+056613Y+159988X0180Y         S0      
317GND              VIA   -    MD0100PA00X+056613Y+161180X0180Y         S0      
317GND              VIA   -    MD0100PA00X+057109Y+160488X0180Y         S0      
317GND              VIA   -    MD0100PA00X+057109Y+159988X0180Y         S0      
317GND              VIA   -    MD0100PA00X+057109Y+161180X0180Y         S0      
317GND              VIA   -    MD0100PA00X+056506Y+159488X0180Y         S0      
317GND              VIA   -    MD0100PA00X+056010Y+159488X0180Y         S0      
317GND              VIA   -    MD0100PA00X+056506Y+158988X0180Y         S0      
317GND              VIA   -    MD0100PA00X+057216Y+159488X0180Y         S0      
317GND              VIA   -    MD0100PA00X+054804Y+162180X0180Y         S0      
317GND              VIA   -    MD0100PA00X+054804Y+162679X0180Y         S0      
317GND              VIA   -    MD0100PA00X+055300Y+162679X0180Y         S0      
317GND              VIA   -    MD0100PA00X+055300Y+162180X0180Y         S0      
317GND              VIA   -    MD0100PA00X+055407Y+161679X0180Y         S0      
317GND              VIA   -    MD0100PA00X+054697Y+161679X0180Y         S0      
317GND              VIA   -    MD0100PA00X+055903Y+161679X0180Y         S0      
317GND              VIA   -    MD0100PA00X+054697Y+160488X0180Y         S0      
317GND              VIA   -    MD0100PA00X+054697Y+159988X0180Y         S0      
317GND              VIA   -    MD0100PA00X+055407Y+160488X0180Y         S0      
317GND              VIA   -    MD0100PA00X+055407Y+159988X0180Y         S0      
317GND              VIA   -    MD0100PA00X+055407Y+161180X0180Y         S0      
317GND              VIA   -    MD0100PA00X+054697Y+161180X0180Y         S0      
317GND              VIA   -    MD0100PA00X+055903Y+160488X0180Y         S0      
317GND              VIA   -    MD0100PA00X+055903Y+159988X0180Y         S0      
317GND              VIA   -    MD0100PA00X+055903Y+161180X0180Y         S0      
317GND              VIA   -    MD0100PA00X+055300Y+159488X0180Y         S0      
317GND              VIA   -    MD0100PA00X+054804Y+159488X0180Y         S0      
317GND              VIA   -    MD0100PA00X+055300Y+158988X0180Y         S0      
317GND              VIA   -    MD0100PA00X+053598Y+162679X0180Y         S0      
317GND              VIA   -    MD0100PA00X+053598Y+162180X0180Y         S0      
317GND              VIA   -    MD0100PA00X+053491Y+161679X0180Y         S0      
317GND              VIA   -    MD0100PA00X+054094Y+162679X0180Y         S0      
317GND              VIA   -    MD0100PA00X+054094Y+162180X0180Y         S0      
317GND              VIA   -    MD0100PA00X+054201Y+161679X0180Y         S0      
317GND              VIA   -    MD0100PA00X+053491Y+160488X0180Y         S0      
317GND              VIA   -    MD0100PA00X+053491Y+159979X0180Y         S0      
317GND              VIA   -    MD0100PA00X+053491Y+161180X0180Y         S0      
317GND              VIA   -    MD0100PA00X+054201Y+160488X0180Y         S0      
317GND              VIA   -    MD0100PA00X+054201Y+159988X0180Y         S0      
317GND              VIA   -    MD0100PA00X+054201Y+161180X0180Y         S0      
317GND              VIA   -    MD0100PA00X+053598Y+159488X0180Y         S0      
317GND              VIA   -    MD0100PA00X+054094Y+159488X0180Y         S0      
317GND              VIA   -    MD0100PA00X+054094Y+158988X0180Y         S0      
317GND              VIA   -    MD0100PA00X+051682Y+162679X0180Y         S0      
317GND              VIA   -    MD0100PA00X+052392Y+162679X0180Y         S0      
317GND              VIA   -    MD0100PA00X+051682Y+162180X0180Y         S0      
317GND              VIA   -    MD0100PA00X+052392Y+162180X0180Y         S0      
317GND              VIA   -    MD0100PA00X+052285Y+161679X0180Y         S0      
317GND              VIA   -    MD0100PA00X+051789Y+161679X0180Y         S0      
317GND              VIA   -    MD0100PA00X+052888Y+162679X0180Y         S0      
317GND              VIA   -    MD0100PA00X+052888Y+162180X0180Y         S0      
317GND              VIA   -    MD0100PA00X+052995Y+161679X0180Y         S0      
317GND              VIA   -    MD0100PA00X+051789Y+160488X0180Y         S0      
317GND              VIA   -    MD0100PA00X+052285Y+160488X0180Y         S0      
317GND              VIA   -    MD0100PA00X+051789Y+159988X0180Y         S0      
317GND              VIA   -    MD0100PA00X+052285Y+159988X0180Y         S0      
317GND              VIA   -    MD0100PA00X+052285Y+161180X0180Y         S0      
317GND              VIA   -    MD0100PA00X+051789Y+161180X0180Y         S0      
317GND              VIA   -    MD0100PA00X+052995Y+160488X0180Y         S0      
317GND              VIA   -    MD0100PA00X+052995Y+159979X0180Y         S0      
317GND              VIA   -    MD0100PA00X+052995Y+161180X0180Y         S0      
317GND              VIA   -    MD0100PA00X+052392Y+159488X0180Y         S0      
317GND              VIA   -    MD0100PA00X+051682Y+159488X0180Y         S0      
317GND              VIA   -    MD0100PA00X+051682Y+158988X0180Y         S0      
317GND              VIA   -    MD0100PA00X+052888Y+159488X0180Y         S0      
317GND              VIA   -    MD0100PA00X+052888Y+158988X0180Y         S0      
317GND              VIA   -    MD0100PA00X+050476Y+162679X0180Y         S0      
317GND              VIA   -    MD0100PA00X+050476Y+162180X0180Y         S0      
317GND              VIA   -    MD0100PA00X+051079Y+161679X0180Y         S0      
317GND              VIA   -    MD0100PA00X+050583Y+161679X0180Y         S0      
317GND              VIA   -    MD0100PA00X+051186Y+162679X0180Y         S0      
317GND              VIA   -    MD0100PA00X+051186Y+162180X0180Y         S0      
317GND              VIA   -    MD0100PA00X+051079Y+160488X0180Y         S0      
317GND              VIA   -    MD0100PA00X+051079Y+159988X0180Y         S0      
317GND              VIA   -    MD0100PA00X+050583Y+160488X0180Y         S0      
317GND              VIA   -    MD0100PA00X+050583Y+159988X0180Y         S0      
317GND              VIA   -    MD0100PA00X+051079Y+161180X0180Y         S0      
317GND              VIA   -    MD0100PA00X+050583Y+161180X0180Y         S0      
317GND              VIA   -    MD0100PA00X+050476Y+159488X0180Y         S0      
317GND              VIA   -    MD0100PA00X+050476Y+158988X0180Y         S0      
317GND              VIA   -    MD0100PA00X+051186Y+159488X0180Y         S0      
317GND              VIA   -    MD0100PA00X+048774Y+162679X0180Y         S0      
317GND              VIA   -    MD0100PA00X+049270Y+162679X0180Y         S0      
317GND              VIA   -    MD0100PA00X+048774Y+162180X0180Y         S0      
317GND              VIA   -    MD0100PA00X+049270Y+162180X0180Y         S0      
317GND              VIA   -    MD0100PA00X+049377Y+161679X0180Y         S0      
317GND              VIA   -    MD0100PA00X+048667Y+161679X0180Y         S0      
317GND              VIA   -    MD0100PA00X+049980Y+162679X0180Y         S0      
317GND              VIA   -    MD0100PA00X+049980Y+162180X0180Y         S0      
317GND              VIA   -    MD0100PA00X+049873Y+161679X0180Y         S0      
317GND              VIA   -    MD0100PA00X+048667Y+160488X0180Y         S0      
317GND              VIA   -    MD0100PA00X+048667Y+159988X0180Y         S0      
317GND              VIA   -    MD0100PA00X+049377Y+160488X0180Y         S0      
317GND              VIA   -    MD0100PA00X+049377Y+159988X0180Y         S0      
317GND              VIA   -    MD0100PA00X+049377Y+161180X0180Y         S0      
317GND              VIA   -    MD0100PA00X+048667Y+161180X0180Y         S0      
317GND              VIA   -    MD0100PA00X+049873Y+160488X0180Y         S0      
317GND              VIA   -    MD0100PA00X+049873Y+159988X0180Y         S0      
317GND              VIA   -    MD0100PA00X+049873Y+161180X0180Y         S0      
317GND              VIA   -    MD0100PA00X+049270Y+159488X0180Y         S0      
317GND              VIA   -    MD0100PA00X+048774Y+159488X0180Y         S0      
317GND              VIA   -    MD0100PA00X+049270Y+158988X0180Y         S0      
317GND              VIA   -    MD0100PA00X+049980Y+159488X0180Y         S0      
317GND              VIA   -    MD0100PA00X+048064Y+162679X0180Y         S0      
317GND              VIA   -    MD0100PA00X+047568Y+162679X0180Y         S0      
317GND              VIA   -    MD0100PA00X+048064Y+162180X0180Y         S0      
317GND              VIA   -    MD0100PA00X+047568Y+162180X0180Y         S0      
317GND              VIA   -    MD0100PA00X+047461Y+161679X0180Y         S0      
317GND              VIA   -    MD0100PA00X+048171Y+161679X0180Y         S0      
317GND              VIA   -    MD0100PA00X+047461Y+160488X0180Y         S0      
317GND              VIA   -    MD0100PA00X+047461Y+159988X0180Y         S0      
317GND              VIA   -    MD0100PA00X+047461Y+161180X0180Y         S0      
317GND              VIA   -    MD0100PA00X+048171Y+160488X0180Y         S0      
317GND              VIA   -    MD0100PA00X+048171Y+159988X0180Y         S0      
317GND              VIA   -    MD0100PA00X+048171Y+161180X0180Y         S0      
317GND              VIA   -    MD0100PA00X+047568Y+159488X0180Y         S0      
317GND              VIA   -    MD0100PA00X+048064Y+159488X0180Y         S0      
317GND              VIA   -    MD0100PA00X+048064Y+158988X0180Y         S0      
317GND              VIA   -    MD0100PA00X+046362Y+162679X0180Y         S0      
317GND              VIA   -    MD0100PA00X+046362Y+162180X0180Y         S0      
317GND              VIA   -    MD0100PA00X+046858Y+162679X0180Y         S0      
317GND              VIA   -    MD0100PA00X+046858Y+162180X0180Y         S0      
317GND              VIA   -    MD0100PA00X+046965Y+161679X0180Y         S0      
317GND              VIA   -    MD0100PA00X+045759Y+161679X0180Y         S0      
317GND              VIA   -    MD0100PA00X+046255Y+161679X0180Y         S0      
317GND              VIA   -    MD0100PA00X+046965Y+160488X0180Y         S0      
317GND              VIA   -    MD0100PA00X+046965Y+159988X0180Y         S0      
317GND              VIA   -    MD0100PA00X+046965Y+161180X0180Y         S0      
317GND              VIA   -    MD0100PA00X+045759Y+161180X0180Y         S0      
317GND              VIA   -    MD0100PA00X+046255Y+161180X0180Y         S0      
317GND              VIA   -    MD0100PA00X+045759Y+160488X0180Y         S0      
317GND              VIA   -    MD0100PA00X+046255Y+160488X0180Y         S0      
317GND              VIA   -    MD0100PA00X+046255Y+159988X0180Y         S0      
317GND              VIA   -    MD0100PA00X+045759Y+159988X0180Y         S0      
317GND              VIA   -    MD0100PA00X+045652Y+159488X0180Y         S0      
317GND              VIA   -    MD0100PA00X+046362Y+159488X0180Y         S0      
317GND              VIA   -    MD0100PA00X+046362Y+158988X0180Y         S0      
317GND              VIA   -    MD0100PA00X+045652Y+158988X0180Y         S0      
317GND              VIA   -    MD0100PA00X+046858Y+159488X0180Y         S0      
317GND              VIA   -    MD0100PA00X+046858Y+158988X0180Y         S0      
317GND              VIA   -    MD0100PA00X+045156Y+159488X0180Y         S0      
317GND              VIA   -    MD0100PA00X+045156Y+158988X0180Y         S0      
317GND              VIA   -    MD0100PA00X+036721Y+161679X0180Y         S0      
317GND              VIA   -    MD0100PA00X+037432Y+161679X0180Y         S0      
317GND              VIA   -    MD0100PA00X+037927Y+161679X0180Y         S0      
317GND              VIA   -    MD0100PA00X+036721Y+161180X0180Y         S0      
317GND              VIA   -    MD0100PA00X+037432Y+161180X0180Y         S0      
317GND              VIA   -    MD0100PA00X+037927Y+161180X0180Y         S0      
317GND              VIA   -    MD0100PA00X+037927Y+159988X0180Y         S0      
317GND              VIA   -    MD0100PA00X+037432Y+159988X0180Y         S0      
317GND              VIA   -    MD0100PA00X+037927Y+160488X0180Y         S0      
317GND              VIA   -    MD0100PA00X+037432Y+160488X0180Y         S0      
317GND              VIA   -    MD0100PA00X+036721Y+159979X0180Y         S0      
317GND              VIA   -    MD0100PA00X+036721Y+160488X0180Y         S0      
317GND              VIA   -    MD0100PA00X+036829Y+158988X0180Y         S0      
317GND              VIA   -    MD0100PA00X+037324Y+159488X0180Y         S0      
317GND              VIA   -    MD0100PA00X+036829Y+159488X0180Y         S0      
317GND              VIA   -    MD0100PA00X+035515Y+161679X0180Y         S0      
317GND              VIA   -    MD0100PA00X+036226Y+161679X0180Y         S0      
317GND              VIA   -    MD0100PA00X+035515Y+161180X0180Y         S0      
317GND              VIA   -    MD0100PA00X+036226Y+161180X0180Y         S0      
317GND              VIA   -    MD0100PA00X+036226Y+159979X0180Y         S0      
317GND              VIA   -    MD0100PA00X+036226Y+160488X0180Y         S0      
317GND              VIA   -    MD0100PA00X+035515Y+159988X0180Y         S0      
317GND              VIA   -    MD0100PA00X+035515Y+160488X0180Y         S0      
317GND              VIA   -    MD0100PA00X+035623Y+158988X0180Y         S0      
317GND              VIA   -    MD0100PA00X+035623Y+159488X0180Y         S0      
317GND              VIA   -    MD0100PA00X+036118Y+159488X0180Y         S0      
317GND              VIA   -    MD0100PA00X+033814Y+161679X0180Y         S0      
317GND              VIA   -    MD0100PA00X+034309Y+161679X0180Y         S0      
317GND              VIA   -    MD0100PA00X+035020Y+161679X0180Y         S0      
317GND              VIA   -    MD0100PA00X+033814Y+161180X0180Y         S0      
317GND              VIA   -    MD0100PA00X+034309Y+161180X0180Y         S0      
317GND              VIA   -    MD0100PA00X+035020Y+161180X0180Y         S0      
317GND              VIA   -    MD0100PA00X+035020Y+159988X0180Y         S0      
317GND              VIA   -    MD0100PA00X+035020Y+160488X0180Y         S0      
317GND              VIA   -    MD0100PA00X+034309Y+159988X0180Y         S0      
317GND              VIA   -    MD0100PA00X+033814Y+159988X0180Y         S0      
317GND              VIA   -    MD0100PA00X+034309Y+160488X0180Y         S0      
317GND              VIA   -    MD0100PA00X+033814Y+160488X0180Y         S0      
317GND              VIA   -    MD0100PA00X+034417Y+158988X0180Y         S0      
317GND              VIA   -    MD0100PA00X+034417Y+159488X0180Y         S0      
317GND              VIA   -    MD0100PA00X+033706Y+159488X0180Y         S0      
317GND              VIA   -    MD0100PA00X+034912Y+159488X0180Y         S0      
317GND              VIA   -    MD0100PA00X+032608Y+161679X0180Y         S0      
317GND              VIA   -    MD0100PA00X+033103Y+161679X0180Y         S0      
317GND              VIA   -    MD0100PA00X+032608Y+161180X0180Y         S0      
317GND              VIA   -    MD0100PA00X+033103Y+161180X0180Y         S0      
317GND              VIA   -    MD0100PA00X+033103Y+159988X0180Y         S0      
317GND              VIA   -    MD0100PA00X+032608Y+159988X0180Y         S0      
317GND              VIA   -    MD0100PA00X+033103Y+160488X0180Y         S0      
317GND              VIA   -    MD0100PA00X+032608Y+160488X0180Y         S0      
317GND              VIA   -    MD0100PA00X+033211Y+158988X0180Y         S0      
317GND              VIA   -    MD0100PA00X+032500Y+159488X0180Y         S0      
317GND              VIA   -    MD0100PA00X+033211Y+159488X0180Y         S0      
317GND              VIA   -    MD0100PA00X+030691Y+161679X0180Y         S0      
317GND              VIA   -    MD0100PA00X+031402Y+161679X0180Y         S0      
317GND              VIA   -    MD0100PA00X+031897Y+161679X0180Y         S0      
317GND              VIA   -    MD0100PA00X+030691Y+161180X0180Y         S0      
317GND              VIA   -    MD0100PA00X+031402Y+161180X0180Y         S0      
317GND              VIA   -    MD0100PA00X+031897Y+161180X0180Y         S0      
317GND              VIA   -    MD0100PA00X+031897Y+159988X0180Y         S0      
317GND              VIA   -    MD0100PA00X+031402Y+159988X0180Y         S0      
317GND              VIA   -    MD0100PA00X+031897Y+160488X0180Y         S0      
317GND              VIA   -    MD0100PA00X+031402Y+160488X0180Y         S0      
317GND              VIA   -    MD0100PA00X+030691Y+159988X0180Y         S0      
317GND              VIA   -    MD0100PA00X+030691Y+160488X0180Y         S0      
317GND              VIA   -    MD0100PA00X+032005Y+158988X0180Y         S0      
317GND              VIA   -    MD0100PA00X+030799Y+158988X0180Y         S0      
317GND              VIA   -    MD0100PA00X+031294Y+159488X0180Y         S0      
317GND              VIA   -    MD0100PA00X+030799Y+159488X0180Y         S0      
317GND              VIA   -    MD0100PA00X+032005Y+159488X0180Y         S0      
317GND              VIA   -    MD0100PA00X+029485Y+161679X0180Y         S0      
317GND              VIA   -    MD0100PA00X+030196Y+161679X0180Y         S0      
317GND              VIA   -    MD0100PA00X+029485Y+161180X0180Y         S0      
317GND              VIA   -    MD0100PA00X+030196Y+161180X0180Y         S0      
317GND              VIA   -    MD0100PA00X+030196Y+159988X0180Y         S0      
317GND              VIA   -    MD0100PA00X+030196Y+160488X0180Y         S0      
317GND              VIA   -    MD0100PA00X+029485Y+159988X0180Y         S0      
317GND              VIA   -    MD0100PA00X+029485Y+160488X0180Y         S0      
317GND              VIA   -    MD0100PA00X+029593Y+158988X0180Y         S0      
317GND              VIA   -    MD0100PA00X+029593Y+159488X0180Y         S0      
317GND              VIA   -    MD0100PA00X+030088Y+159488X0180Y         S0      
317GND              VIA   -    MD0100PA00X+027784Y+161679X0180Y         S0      
317GND              VIA   -    MD0100PA00X+028279Y+161679X0180Y         S0      
317GND              VIA   -    MD0100PA00X+028990Y+161679X0180Y         S0      
317GND              VIA   -    MD0100PA00X+027784Y+161180X0180Y         S0      
317GND              VIA   -    MD0100PA00X+028279Y+161180X0180Y         S0      
317GND              VIA   -    MD0100PA00X+028990Y+161180X0180Y         S0      
317GND              VIA   -    MD0100PA00X+028990Y+159988X0180Y         S0      
317GND              VIA   -    MD0100PA00X+028990Y+160488X0180Y         S0      
317GND              VIA   -    MD0100PA00X+028279Y+159988X0180Y         S0      
317GND              VIA   -    MD0100PA00X+027784Y+159988X0180Y         S0      
317GND              VIA   -    MD0100PA00X+028279Y+160488X0180Y         S0      
317GND              VIA   -    MD0100PA00X+027784Y+160488X0180Y         S0      
317GND              VIA   -    MD0100PA00X+028387Y+158988X0180Y         S0      
317GND              VIA   -    MD0100PA00X+028387Y+159488X0180Y         S0      
317GND              VIA   -    MD0100PA00X+027676Y+159488X0180Y         S0      
317GND              VIA   -    MD0100PA00X+028882Y+159488X0180Y         S0      
317GND              VIA   -    MD0100PA00X+026578Y+161679X0180Y         S0      
317GND              VIA   -    MD0100PA00X+027073Y+161679X0180Y         S0      
317GND              VIA   -    MD0100PA00X+026578Y+161180X0180Y         S0      
317GND              VIA   -    MD0100PA00X+027073Y+161180X0180Y         S0      
317GND              VIA   -    MD0100PA00X+027073Y+159979X0180Y         S0      
317GND              VIA   -    MD0100PA00X+026578Y+159979X0180Y         S0      
317GND              VIA   -    MD0100PA00X+027073Y+160488X0180Y         S0      
317GND              VIA   -    MD0100PA00X+026578Y+160488X0180Y         S0      
317GND              VIA   -    MD0100PA00X+027181Y+158988X0180Y         S0      
317GND              VIA   -    MD0100PA00X+026470Y+159488X0180Y         S0      
317GND              VIA   -    MD0100PA00X+027181Y+159488X0180Y         S0      
317GND              VIA   -    MD0100PA00X+025372Y+161679X0180Y         S0      
317GND              VIA   -    MD0100PA00X+025867Y+161679X0180Y         S0      
317GND              VIA   -    MD0100PA00X+025372Y+161180X0180Y         S0      
317GND              VIA   -    MD0100PA00X+025867Y+161180X0180Y         S0      
317GND              VIA   -    MD0100PA00X+025867Y+159988X0180Y         S0      
317GND              VIA   -    MD0100PA00X+025372Y+159988X0180Y         S0      
317GND              VIA   -    MD0100PA00X+025867Y+160488X0180Y         S0      
317GND              VIA   -    MD0100PA00X+025372Y+160488X0180Y         S0      
317GND              VIA   -    MD0100PA00X+025975Y+158988X0180Y         S0      
317GND              VIA   -    MD0100PA00X+024769Y+158988X0180Y         S0      
317GND              VIA   -    MD0100PA00X+025264Y+159488X0180Y         S0      
317GND              VIA   -    MD0100PA00X+024769Y+159488X0180Y         S0      
317GND              VIA   -    MD0100PA00X+025975Y+159488X0180Y         S0      
317GND              VIA   -    MD0100PA00X+023455Y+161679X0180Y         S0      
317GND              VIA   -    MD0100PA00X+024166Y+161679X0180Y         S0      
317GND              VIA   -    MD0100PA00X+024661Y+161679X0180Y         S0      
317GND              VIA   -    MD0100PA00X+023455Y+161180X0180Y         S0      
317GND              VIA   -    MD0100PA00X+024166Y+161180X0180Y         S0      
317GND              VIA   -    MD0100PA00X+024661Y+161180X0180Y         S0      
317GND              VIA   -    MD0100PA00X+024166Y+159988X0180Y         S0      
317GND              VIA   -    MD0100PA00X+024166Y+160488X0180Y         S0      
317GND              VIA   -    MD0100PA00X+023455Y+159988X0180Y         S0      
317GND              VIA   -    MD0100PA00X+023455Y+160488X0180Y         S0      
317GND              VIA   -    MD0100PA00X+024661Y+159988X0180Y         S0      
317GND              VIA   -    MD0100PA00X+024661Y+160488X0180Y         S0      
317GND              VIA   -    MD0100PA00X+023563Y+158988X0180Y         S0      
317GND              VIA   -    MD0100PA00X+023563Y+159488X0180Y         S0      
317GND              VIA   -    MD0100PA00X+024058Y+159488X0180Y         S0      
317GND              VIA   -    MD0100PA00X+022249Y+161679X0180Y         S0      
317GND              VIA   -    MD0100PA00X+021754Y+161679X0180Y         S0      
317GND              VIA   -    MD0100PA00X+022960Y+161679X0180Y         S0      
317GND              VIA   -    MD0100PA00X+022249Y+161180X0180Y         S0      
317GND              VIA   -    MD0100PA00X+021754Y+161180X0180Y         S0      
317GND              VIA   -    MD0100PA00X+022960Y+161180X0180Y         S0      
317GND              VIA   -    MD0100PA00X+022960Y+159988X0180Y         S0      
317GND              VIA   -    MD0100PA00X+022960Y+160488X0180Y         S0      
317GND              VIA   -    MD0100PA00X+021754Y+159988X0180Y         S0      
317GND              VIA   -    MD0100PA00X+022249Y+159988X0180Y         S0      
317GND              VIA   -    MD0100PA00X+021754Y+160488X0180Y         S0      
317GND              VIA   -    MD0100PA00X+022249Y+160488X0180Y         S0      
317GND              VIA   -    MD0100PA00X+022357Y+158988X0180Y         S0      
317GND              VIA   -    MD0100PA00X+022357Y+159488X0180Y         S0      
317GND              VIA   -    MD0100PA00X+022852Y+159488X0180Y         S0      
317GND              VIA   -    MD0100PA00X+020548Y+161679X0180Y         S0      
317GND              VIA   -    MD0100PA00X+021043Y+161679X0180Y         S0      
317GND              VIA   -    MD0100PA00X+021043Y+161180X0180Y         S0      
317GND              VIA   -    MD0100PA00X+020548Y+161180X0180Y         S0      
317GND              VIA   -    MD0100PA00X+020548Y+159988X0180Y         S0      
317GND              VIA   -    MD0100PA00X+021043Y+159988X0180Y         S0      
317GND              VIA   -    MD0100PA00X+020548Y+160488X0180Y         S0      
317GND              VIA   -    MD0100PA00X+021043Y+160488X0180Y         S0      
317GND              VIA   -    MD0100PA00X+021151Y+158988X0180Y         S0      
317GND              VIA   -    MD0100PA00X+021646Y+159488X0180Y         S0      
317GND              VIA   -    MD0100PA00X+020440Y+159488X0180Y         S0      
317GND              VIA   -    MD0100PA00X+021151Y+159488X0180Y         S0      
317GND              VIA   -    MD0100PA00X+019342Y+161679X0180Y         S0      
317GND              VIA   -    MD0100PA00X+019837Y+161679X0180Y         S0      
317GND              VIA   -    MD0100PA00X+019342Y+161180X0180Y         S0      
317GND              VIA   -    MD0100PA00X+019837Y+161180X0180Y         S0      
317GND              VIA   -    MD0100PA00X+019837Y+160488X0180Y         S0      
317GND              VIA   -    MD0100PA00X+019837Y+159988X0180Y         S0      
317GND              VIA   -    MD0100PA00X+019342Y+159988X0180Y         S0      
317GND              VIA   -    MD0100PA00X+019342Y+160488X0180Y         S0      
317GND              VIA   -    MD0100PA00X+019945Y+158988X0180Y         S0      
317GND              VIA   -    MD0100PA00X+018739Y+158988X0180Y         S0      
317GND              VIA   -    MD0100PA00X+019945Y+159488X0180Y         S0      
317GND              VIA   -    MD0100PA00X+019234Y+159488X0180Y         S0      
317GND              VIA   -    MD0100PA00X+018739Y+159488X0180Y         S0      
327GND              C296  -2          A18X+033642Y+057850X0198Y0197     S2      
317GND              VIA   -    MD0100PA00X+033350Y+057850X0200Y         S0      
327GND              C297  -2          A18X+033642Y+058250X0198Y0197     S2      
317GND              VIA   -    MD0100PA00X+033350Y+058250X0200Y         S0      
327GND              C295  -2          A01X+034558Y+058642X0198Y0197R180 S1      
327GND              C1517 -2          A01X+108694Y+037319X0198Y0197R180 S1      
317GND              VIA   -    MD0100PA00X+108694Y+037053X0200Y         S0      
317GND              VIA   -    MD0100PA00X+002131Y+039571X0200Y         S0      
317GND              VIA   -    MD0100PA00X+002731Y+038393X0200Y         S0      
327GND              U8000 -2          A18X+072376Y+056850X0160Y0200R270 S2      
317GND              VIA   -    MD0100PA00X+090850Y+092750X0200Y         S0      
317GND              VIA   -    MD0100PA00X+091150Y+093100X0200Y         S0      
327GND              U213  -9   M      A18X+090999Y+092943X0591Y0591R090 S2      
327GND              R5004 -2          A18X+090500Y+091242X0198Y0197R090 S2      
317GND              VIA   -    MD0100PA00X+090500Y+090900X0200Y         S0      
327GND              C9    -2          A18X+090900Y+091242X0198Y0197R090 S2      
317GND              VIA   -    MD0100PA00X+090900Y+090900X0200Y         S0      
317GND              VIA   -    MD0100PA00X+091800Y+092800X0200Y         S0      
317GND              VIA   -    MD0100PA00X+053200Y+042650X0200Y         S0      
327GND              C23   -2          A18X+092960Y+088550X0198Y0197R270 S2      
317GND              VIA   -    MD0100PA00X+092960Y+088900X0200Y         S0      
327GND              C26   -2          A18X+093400Y+086092X0198Y0197R090 S2      
317GND              VIA   -    MD0100PA00X+093092Y+086092X0200Y         S0      
317GND              VIA   -    MD0100PA00X+025847Y+077541X0200Y         S0      
317GND              VIA   -    M      A01X+133082Y+051826X0200Y    R270 S2      
017GND              VIA   -    M      A18X+133082Y+051826X0260Y    R270 S2      
017GND                    -    MD0100PA00X+133082Y+051826                       
317GND              VIA   -    MD0100PA00X+133076Y+052175X0200Y    R270 S0      
327GND              PC8002-2          A01X+132701Y+051968X0400Y0500R180 S1      
317GND              VIA   -    MD0100PA00X+072672Y+057491X0200Y         S0      
317GND              VIA   -    MD0100PA00X+074228Y+056667X0200Y         S0      
327GND              Q70   -4          A01X+170550Y+171176X0170Y0200R090 S1      
327GND              Q70   -1          A01X+169802Y+171688X0170Y0200R090 S1      
327GND              Q136  -4          A01X+174462Y+172342X0170Y0200R090 S1      
327GND              Q136  -1          A01X+173714Y+172853X0170Y0200R090 S1      
327GND              R2833 -2          A01X+168551Y+171876X0198Y0197R090 S1      
327GND              R4161 -2          A01X+172463Y+173042X0198Y0197R090 S1      
327GND              C1754 -2          A01X+168951Y+170861X0198Y0197R270 S1      
327GND              C5    -2          A01X+172863Y+172026X0198Y0197R270 S1      
327GND              R3471 -2          A01X+172463Y+171526X0198Y0197R090 S1      
317GND              VIA   -    MD0100PA00X+173112Y+170512X0200Y    R090 S0      
317GND              VIA   -    MD0100PA00X+171915Y+170319X0200Y    R270 S0      
317GND              VIA   -    MD0100PA00X+170300Y+171176X0200Y    R180 S0      
317GND              VIA   -    MD0100PA00X+170052Y+171688X0200Y         S0      
317GND              VIA   -    MD0100PA00X+174212Y+172342X0200Y    R180 S0      
317GND              VIA   -    MD0100PA00X+173964Y+172853X0200Y         S0      
317GND              VIA   -    MD0100PA00X+169200Y+170861X0200Y    R090 S0      
317GND              VIA   -    MD0100PA00X+173112Y+172026X0200Y    R090 S0      
317GND              VIA   -    MD0100PA00X+168052Y+172682X0200Y         S0      
317GND              VIA   -    MD0100PA00X+168272Y+171770X0200Y    R270 S0      
317GND              VIA   -    MD0100PA00X+172215Y+173042X0200Y    R270 S0      
317GND              VIA   -    MD0100PA00X+168301Y+171368X0200Y         S0      
317GND              VIA   -    MD0100PA00X+172213Y+172534X0200Y         S0      
317GND              VIA   -    MD0100PA00X+172215Y+171526X0200Y    R270 S0      
327GND              U8009 -2          A01X+054826Y+044416X0240Y0420R180 S1      
317GND              VIA   -    MD0100PA00X+054886Y+044045X0200Y         S0      
317GND              VIA   -    MD0100PA00X+056358Y+044842X0200Y         S0      
317GND              VIA   -    MD0100PA00X+054350Y+046350X0200Y         S0      
317GND              VIA   -    MD0100PA00X+054484Y+043970X0200Y         S0      
327GND              U8007 -2          A01X+048826Y+042266X0240Y0420R180 S1      
317GND              VIA   -    MD0100PA00X+048826Y+041898X0200Y         S0      
317GND              VIA   -    MD0100PA00X+050150Y+043300X0200Y         S0      
317GND              VIA   -    MD0100PA00X+063661Y+051260X0200Y         S0      
317GND              VIA   -    MD0100PA00X+064977Y+050574X0200Y         S0      
317GND              VIA   -    MD0100PA00X+067150Y+052950X0200Y         S0      
327GND              U6006 -1          A01X+045347Y+049724X0260Y0380R270 S1      
317GND              VIA   -    MD0100PA00X+044976Y+049724X0200Y         S0      
317GND              VIA   -    MD0100PA00X+046592Y+048992X0200Y         S0      
317GND              VIA   -    MD0100PA00X+043950Y+048400X0200Y         S0      
317GND              VIA   -    MD0100PA00X+031042Y+024392X0200Y         S0      
317GND              VIA   -    MD0100PA00X+030892Y+026008X0200Y         S0      
327GND              R6050 -2          A01X+080958Y+050400X0198Y0197     S1      
317GND              VIA   -    MD0100PA00X+081250Y+050400X0200Y         S0      
327GND              Q3    -1          A01X+081744Y+052076X0170Y0200R180 S1      
317GND              VIA   -    MD0100PA00X+081744Y+051794X0200Y         S0      
317GND              VIA   -    MD0100PA00X+082450Y+051450X0200Y         S0      
317GND              VIA   -    MD0100PA00X+078500Y+056350X0200Y         S0      
327GND              U8004 -3          A18X+079406Y+055674X0170Y0240R180 S2      
317GND              VIA   -    MD0100PA00X+079406Y+055356X0200Y         S0      
327GND              U8004 -2          A18X+079150Y+055674X0170Y0240R180 S2      
317GND              VIA   -    MD0100PA00X+079150Y+056000X0200Y         S0      
317GND              VIA   -    MD0100PA00X+079442Y+054142X0200Y         S0      
317GND              VIA   -    MD0100PA00X+141462Y+024445X0200Y    R090 S0      
317GND              VIA   -    MD0100PA00X+087450Y+032800X0200Y         S0      
327GND              U8003 -1          A01X+088474Y+032003X0260Y0380R180 S1      
317GND              VIA   -    MD0100PA00X+088474Y+031600X0200Y         S0      
327GND              U9    -2          A01X+119619Y+010088X0160Y0360R270 S1      
317GND              VIA   -    MD0100PA00X+163250Y+038150X0200Y         S0      
317GND              VIA   -    MD0100PA00X+163093Y+039800X0200Y         S0      
327GND              PC8013-2          A18X+176398Y+021296X0400Y0500R090 S2      
327GND              PC8014-2          A18X+175692Y+021290X0400Y0500R090 S2      
327GND              C693  -2          A01X+168494Y+023149X0198Y0197R090 S1      
327GND              U2    -4          A18X+090394Y+086956X0240Y0460R180 S2      
317GND              VIA   -    MD0100PA00X+090394Y+087400X0200Y         S0      
327GND              U4    -5          A18X+091676Y+097517X0130Y0250     S2      
317GND              VIA   -    MD0100PA00X+091676Y+097234X0200Y         S0      
327GND              C11   -2          A18X+091676Y+098993X0198Y0197R270 S2      
317GND              VIA   -    MD0100PA00X+091927Y+098993X0200Y    R090 S0      
317GND              VIA   -    MD0100PA00X+091850Y+085692X0200Y         S0      
327GND              C2    -2          A18X+091738Y+088503X0198Y0197R270 S2      
317GND              VIA   -    MD0100PA00X+091762Y+088754X0200Y         S0      
327GND              PC8012-2          A18X+046201Y+065326X0400Y0500R090 S2      
317GND              VIA   -    MD0100PA00X+102142Y+040492X0200Y         S0      
317GND              VIA   -    MD0100PA00X+004000Y+032350X0200Y         S0      
317GND              VIA   -    MD0100PA00X+003650Y+032350X0200Y         S0      
327GND              U58   -2          A01X+004726Y+031110X0170Y0240R270 S1      
317GND              VIA   -    MD0100PA00X+006758Y+028750X0200Y         S0      
317GND              VIA   -    MD0100PA00X+082666Y+042342X0200Y         S0      
327GND              U160  -8          A01X+042890Y+022225X0240Y0540R270 S1      
327GND              U160  -7          A01X+042890Y+022520X0160Y0540R270 S1      
327GND              U212  -8          A01X+050694Y+022493X0240Y0540R270 S1      
327GND              U212  -7          A01X+050694Y+022788X0160Y0540R270 S1      
317GND              VIA   -    MD0100PA00X+037719Y+138770X0200Y    R180 S0      
327GND              PC375 -2          A01X+037434Y+138770X0198Y0197     S1      
327GND              J19   -143        A01X+112101Y+125211X0205Y0590R090 S1      
327GND              J19   -288        A01X+110487Y+125545X0205Y0590R090 S1      
327GND              J21   -143        A01X+109131Y+125211X0205Y0590R090 S1      
327GND              J21   -288        A01X+107517Y+125545X0205Y0590R090 S1      
327GND              J23   -143        A01X+106161Y+125211X0205Y0590R090 S1      
327GND              J17   -143        A01X+115071Y+125211X0205Y0590R090 S1      
327GND              J17   -288        A01X+113457Y+125545X0205Y0590R090 S1      
327GND              J15   -288        A01X+116427Y+125545X0205Y0590R090 S1      
327GND              J15   -143        A01X+118041Y+125211X0205Y0590R090 S1      
327GND              J1    -288        A01X+119397Y+125545X0205Y0590R090 S1      
327GND              J1    -143        A01X+121011Y+125211X0205Y0590R090 S1      
327GND              PC119_-2          A18X+122813Y+136179X0400Y0500R270 S2      
327GND              PC125_-2          A18X+121976Y+136179X0400Y0500R270 S2      
327GND              PC158_-2          A18X+119533Y+136179X0400Y0500R270 S2      
327GND              PC152_-2          A18X+118696Y+136179X0400Y0500R270 S2      
327GND              PC159_-2          A18X+116243Y+136179X0400Y0500R270 S2      
327GND              PC153_-2          A18X+115406Y+136179X0400Y0500R270 S2      
327GND              PC181_-2          A18X+112136Y+136179X0400Y0500R270 S2      
327GND              PC184_-2          A18X+112973Y+136179X0400Y0500R270 S2      
327GND              PC182_-2          A18X+108876Y+136179X0400Y0500R270 S2      
327GND              PC185_-2          A18X+109713Y+136179X0400Y0500R270 S2      
327GND              VIA   -           A18X+120780Y+134852X0260Y    R090 S2      
327GND              PC162 -2          A18X+118073Y+135073X0950Y1110R270 S2      
327GND              VIA   -           A18X+114582Y+134825X0260Y    R090 S2      
327GND              PC165 -2          A18X+111963Y+135083X0950Y1110R270 S2      
327GND              PC160 -2          A18X+108353Y+135063X0950Y1110R270 S2      
327GND              PC130_-2          A18X+122730Y+133453X0400Y0500R090 S2      
327GND              PC129_-2          A18X+121880Y+133455X0400Y0500R090 S2      
327GND              PC128_-2          A18X+121063Y+133453X0400Y0500R090 S2      
327GND              PC127_-2          A18X+120173Y+133453X0400Y0500R090 S2      
327GND              PC166_-2          A18X+116623Y+133413X0400Y0500R090 S2      
327GND              PC169_-2          A18X+115672Y+133415X0400Y0500R090 S2      
327GND              PC168_-2          A18X+114901Y+133415X0400Y0500R090 S2      
327GND              PC190_-2          A18X+113360Y+133415X0400Y0500R090 S2      
327GND              PC170_-2          A18X+114130Y+133415X0400Y0500R090 S2      
327GND              PC192_-2          A18X+110573Y+133423X0400Y0500R090 S2      
327GND              PC189_-2          A18X+109730Y+133415X0400Y0500R090 S2      
327GND              VIA   -           A18X+106368Y+134030X0260Y    R270 S2      
327GND              PC191_-2          A18X+106973Y+133413X0400Y0500R090 S2      
327GND              PR410 -2          A18X+106397Y+133278X0198Y0197R270 S2      
327GND              VIA   -           A18X+104868Y+134030X0260Y    R270 S2      
327GND              PC117_-2          A01X+122965Y+136404X0198Y0197R270 S1      
327GND              PC115_-2          A01X+123352Y+136403X0198Y0197R270 S1      
327GND              PU14  -2   M      A01X+120589Y+137221X0090Y0240R090 S1      
327GND              PC109 -2          A01X+120084Y+137709X0198Y0197R090 S1      
327GND              PU14  -5          A01X+120589Y+136690X0090Y0240R090 S1      
327GND              PR509 -2          A01X+120086Y+135977X0198Y0197R090 S1      
327GND              PC111_-2          A01X+120084Y+136344X0198Y0197R270 S1      
327GND              PC150_-2          A01X+119685Y+136404X0198Y0197R270 S1      
327GND              PU17  -2   M      A01X+117309Y+137221X0090Y0240R090 S1      
327GND              PC143 -2          A01X+116804Y+137709X0198Y0197R090 S1      
327GND              PU17  -5          A01X+117309Y+136690X0090Y0240R090 S1      
327GND              PR221 -2          A01X+116806Y+135977X0198Y0197R090 S1      
327GND              PC147_-2          A01X+116804Y+136344X0198Y0197R270 S1      
327GND              PC151_-2          A01X+116395Y+136404X0198Y0197R270 S1      
327GND              PU18  -2   M      A01X+114019Y+137221X0090Y0240R090 S1      
327GND              PC142 -2          A01X+113514Y+137709X0198Y0197R090 S1      
327GND              PU18  -5          A01X+114019Y+136690X0090Y0240R090 S1      
327GND              PR223 -2          A01X+113516Y+135977X0198Y0197R090 S1      
327GND              PC179_-2          A01X+113125Y+136404X0198Y0197R270 S1      
327GND              PC144_-2          A01X+113514Y+136344X0198Y0197R270 S1      
327GND              PU19  -2   M      A01X+110749Y+137221X0090Y0240R090 S1      
327GND              PC172 -2          A01X+110244Y+137709X0198Y0197R090 S1      
327GND              PU19  -5          A01X+110749Y+136690X0090Y0240R090 S1      
327GND              PR379 -2          A01X+110246Y+135977X0198Y0197R090 S1      
327GND              PC174_-2          A01X+110244Y+136344X0198Y0197R270 S1      
327GND              PC180_-2          A01X+109865Y+136404X0198Y0197R270 S1      
327GND              PU20  -2   M      A01X+107489Y+137221X0090Y0240R090 S1      
327GND              PC171 -2          A01X+106984Y+137709X0198Y0197R090 S1      
327GND              PU20  -5          A01X+107489Y+136690X0090Y0240R090 S1      
327GND              PR291 -2          A01X+106986Y+135977X0198Y0197R090 S1      
327GND              PC173_-2          A01X+106984Y+136344X0198Y0197R270 S1      
327GND              PL16  -2          A01X+105471Y+134456X0790Y1660R090 S1      
327GND              PL13  -3          A01X+121580Y+132372X0540Y1780R270 S1      
327GND              PL17  -3          A01X+118300Y+132372X0540Y1780R270 S1      
327GND              U25   -A3         A01X+154389Y+087429X0177Y    R180 S1      
327GND              U25   -A9         A01X+152168Y+087429X0177Y    R180 S1      
327GND              U25   -A15        A01X+149948Y+087429X0177Y    R180 S1      
327GND              U25   -A21        A01X+147728Y+087429X0177Y    R180 S1      
327GND              U25   -A27        A01X+145507Y+087429X0177Y    R180 S1      
327GND              U25   -A43        A01X+139956Y+087429X0177Y    R180 S1      
327GND              U25   -A44        A01X+139586Y+087429X0177Y    R180 S1      
327GND              U25   -A47        A01X+138476Y+087429X0177Y    R180 S1      
327GND              U25   -A49        A01X+137735Y+087429X0177Y    R180 S1      
327GND              U25   -A53        A01X+136255Y+087429X0177Y    R180 S1      
327GND              U25   -A61        A01X+133294Y+087429X0177Y    R180 S1      
327GND              U25   -A67        A01X+131074Y+087429X0177Y    R180 S1      
327GND              U25   -A72        A01X+129224Y+087429X0177Y    R180 S1      
327GND              U25   -A73        A01X+128854Y+087429X0177Y    R180 S1      
327GND              U25   -B7         A01X+153094Y+087748X0177Y    R180 S1      
327GND              U25   -B8         A01X+152724Y+087748X0177Y    R180 S1      
327GND              U25   -B10        A01X+151984Y+087748X0177Y    R180 S1      
327GND              U25   -B11        A01X+151613Y+087748X0177Y    R180 S1      
327GND              U25   -B13        A01X+150873Y+087748X0177Y    R180 S1      
327GND              U25   -B18        A01X+149023Y+087748X0177Y    R180 S1      
327GND              U25   -B24        A01X+146802Y+087748X0177Y    R180 S1      
327GND              U25   -B27        A01X+145692Y+087748X0177Y    R180 S1      
327GND              U25   -B30        A01X+144582Y+087748X0177Y    R180 S1      
327GND              U25   -B33        A01X+143472Y+087748X0177Y    R180 S1      
327GND              U25   -B37        A01X+141991Y+087748X0177Y    R180 S1      
327GND              U25   -B39        A01X+141251Y+087748X0177Y    R180 S1      
327GND              U25   -B43        A01X+139771Y+087748X0177Y    R180 S1      
327GND              U25   -B46        A01X+138661Y+087748X0177Y    R180 S1      
327GND              U25   -B49        A01X+137550Y+087748X0177Y    R180 S1      
327GND              U25   -B52        A01X+136440Y+087748X0177Y    R180 S1      
327GND              U25   -B55        A01X+135330Y+087748X0177Y    R180 S1      
327GND              U25   -B59        A01X+133850Y+087748X0177Y    R180 S1      
327GND              U25   -B62        A01X+132739Y+087748X0177Y    R180 S1      
327GND              U25   -B65        A01X+131629Y+087748X0177Y    R180 S1      
327GND              U25   -B68        A01X+130519Y+087748X0177Y    R180 S1      
327GND              U25   -B70        A01X+129779Y+087748X0177Y    R180 S1      
327GND              U25   -C1         A01X+155129Y+088067X0177Y    R180 S1      
327GND              U25   -C5         A01X+153649Y+088067X0177Y    R180 S1      
327GND              U25   -C8         A01X+152539Y+088067X0177Y    R180 S1      
327GND              U25   -C10        A01X+151798Y+088067X0177Y    R180 S1      
327GND              U25   -C11        A01X+151428Y+088067X0177Y    R180 S1      
327GND              U25   -C13        A01X+150688Y+088067X0177Y    R180 S1      
327GND              U25   -C15        A01X+149948Y+088067X0177Y    R180 S1      
327GND              U25   -C21        A01X+147728Y+088067X0177Y    R180 S1      
327GND              U25   -C24        A01X+146617Y+088067X0177Y    R180 S1      
327GND              U25   -C27        A01X+145507Y+088067X0177Y    R180 S1      
327GND              U25   -C30        A01X+144397Y+088067X0177Y    R180 S1      
327GND              U25   -C36        A01X+142176Y+088067X0177Y    R180 S1      
327GND              U25   -C40        A01X+141066Y+088067X0177Y    R180 S1      
327GND              U25   -C43        A01X+139956Y+088067X0177Y    R180 S1      
327GND              U25   -C46        A01X+138846Y+088067X0177Y    R180 S1      
327GND              U25   -C49        A01X+137735Y+088067X0177Y    R180 S1      
327GND              U25   -C52        A01X+136625Y+088067X0177Y    R180 S1      
327GND              U25   -C55        A01X+135515Y+088067X0177Y    R180 S1      
327GND              U25   -C56        A01X+135145Y+088067X0177Y    R180 S1      
327GND              U25   -C57        A01X+134775Y+088067X0177Y    R180 S1      
327GND              U25   -C61        A01X+133294Y+088067X0177Y    R180 S1      
327GND              U25   -C64        A01X+132184Y+088067X0177Y    R180 S1      
327GND              U25   -C67        A01X+131074Y+088067X0177Y    R180 S1      
327GND              U25   -C69        A01X+130334Y+088067X0177Y    R180 S1      
327GND              U25   -C71        A01X+129594Y+088067X0177Y    R180 S1      
327GND              U25   -C73        A01X+128854Y+088067X0177Y    R180 S1      
327GND              U25   -C75        A01X+128113Y+088067X0177Y    R180 S1      
327GND              U25   -D2         A01X+154944Y+088386X0177Y    R180 S1      
327GND              U25   -D3         A01X+154574Y+088386X0177Y    R180 S1      
327GND              U25   -D5         A01X+153834Y+088386X0177Y    R180 S1      
327GND              U25   -D6         A01X+153464Y+088386X0177Y    R180 S1      
327GND              U25   -D9         A01X+152354Y+088386X0177Y    R180 S1      
327GND              U25   -D10        A01X+151984Y+088386X0177Y    R180 S1      
327GND              U25   -D12        A01X+151243Y+088386X0177Y    R180 S1      
327GND              U25   -D13        A01X+150873Y+088386X0177Y    R180 S1      
327GND              U25   -D16        A01X+149763Y+088386X0177Y    R180 S1      
327GND              U25   -D17        A01X+149393Y+088386X0177Y    R180 S1      
327GND              U25   -D19        A01X+148653Y+088386X0177Y    R180 S1      
327GND              U25   -D20        A01X+148283Y+088386X0177Y    R180 S1      
327GND              U25   -D21        A01X+147913Y+088386X0177Y    R180 S1      
327GND              U25   -D24        A01X+146802Y+088386X0177Y    R180 S1      
327GND              U25   -D25        A01X+146432Y+088386X0177Y    R180 S1      
327GND              U25   -D26        A01X+146062Y+088386X0177Y    R180 S1      
327GND              U25   -D27        A01X+145692Y+088386X0177Y    R180 S1      
327GND              U25   -D28        A01X+145322Y+088386X0177Y    R180 S1      
327GND              U25   -D29        A01X+144952Y+088386X0177Y    R180 S1      
327GND              U25   -D30        A01X+144582Y+088386X0177Y    R180 S1      
327GND              U25   -D31        A01X+144212Y+088386X0177Y    R180 S1      
327GND              U25   -D35        A01X+142732Y+088386X0177Y    R180 S1      
327GND              U25   -D37        A01X+141991Y+088386X0177Y    R180 S1      
327GND              U25   -D39        A01X+141251Y+088386X0177Y    R180 S1      
327GND              U25   -D40        A01X+140881Y+088386X0177Y    R180 S1      
327GND              U25   -D41        A01X+140511Y+088386X0177Y    R180 S1      
327GND              U25   -D42        A01X+140141Y+088386X0177Y    R180 S1      
327GND              U25   -D43        A01X+139771Y+088386X0177Y    R180 S1      
327GND              U25   -D44        A01X+139401Y+088386X0177Y    R180 S1      
327GND              U25   -D45        A01X+139031Y+088386X0177Y    R180 S1      
327GND              U25   -D46        A01X+138661Y+088386X0177Y    R180 S1      
327GND              U25   -D47        A01X+138290Y+088386X0177Y    R180 S1      
327GND              U25   -D48        A01X+137920Y+088386X0177Y    R180 S1      
327GND              U25   -D49        A01X+137550Y+088386X0177Y    R180 S1      
327GND              U25   -D50        A01X+137180Y+088386X0177Y    R180 S1      
327GND              U25   -D51        A01X+136810Y+088386X0177Y    R180 S1      
327GND              U25   -D52        A01X+136440Y+088386X0177Y    R180 S1      
327GND              U25   -D53        A01X+136070Y+088386X0177Y    R180 S1      
327GND              U25   -D54        A01X+135700Y+088386X0177Y    R180 S1      
327GND              U25   -D57        A01X+134590Y+088386X0177Y    R180 S1      
327GND              U25   -D59        A01X+133850Y+088386X0177Y    R180 S1      
327GND              U25   -D60        A01X+133480Y+088386X0177Y    R180 S1      
327GND              U25   -D61        A01X+133109Y+088386X0177Y    R180 S1      
327GND              U25   -D63        A01X+132369Y+088386X0177Y    R180 S1      
327GND              U25   -D64        A01X+131999Y+088386X0177Y    R180 S1      
327GND              U25   -D66        A01X+131259Y+088386X0177Y    R180 S1      
327GND              U25   -D67        A01X+130889Y+088386X0177Y    R180 S1      
327GND              U25   -D70        A01X+129779Y+088386X0177Y    R180 S1      
327GND              U25   -D71        A01X+129409Y+088386X0177Y    R180 S1      
327GND              U25   -D73        A01X+128668Y+088386X0177Y    R180 S1      
327GND              U25   -D74        A01X+128298Y+088386X0177Y    R180 S1      
327GND              U25   -E1         A01X+155129Y+088705X0177Y    R180 S1      
327GND              U25   -E3         A01X+154389Y+088705X0177Y    R180 S1      
327GND              U25   -E6         A01X+153279Y+088705X0177Y    R180 S1      
327GND              U25   -E7         A01X+152909Y+088705X0177Y    R180 S1      
327GND              U25   -E8         A01X+152539Y+088705X0177Y    R180 S1      
327GND              U25   -E10        A01X+151798Y+088705X0177Y    R180 S1      
327GND              U25   -E13        A01X+150688Y+088705X0177Y    R180 S1      
327GND              U25   -E14        A01X+150318Y+088705X0177Y    R180 S1      
327GND              U25   -E15        A01X+149948Y+088705X0177Y    R180 S1      
327GND              U25   -E17        A01X+149208Y+088705X0177Y    R180 S1      
327GND              U25   -E18        A01X+148838Y+088705X0177Y    R180 S1      
327GND              U25   -E20        A01X+148098Y+088705X0177Y    R180 S1      
327GND              U25   -E21        A01X+147728Y+088705X0177Y    R180 S1      
327GND              U25   -E52        A01X+136625Y+088705X0177Y    R180 S1      
327GND              U25   -E53        A01X+136255Y+088705X0177Y    R180 S1      
327GND              U25   -E55        A01X+135515Y+088705X0177Y    R180 S1      
327GND              U25   -E56        A01X+135145Y+088705X0177Y    R180 S1      
327GND              U25   -E58        A01X+134405Y+088705X0177Y    R180 S1      
327GND              U25   -E59        A01X+134035Y+088705X0177Y    R180 S1      
327GND              U25   -E61        A01X+133294Y+088705X0177Y    R180 S1      
327GND              U25   -E62        A01X+132924Y+088705X0177Y    R180 S1      
327GND              U25   -E63        A01X+132554Y+088705X0177Y    R180 S1      
327GND              U25   -E65        A01X+131814Y+088705X0177Y    R180 S1      
327GND              U25   -E66        A01X+131444Y+088705X0177Y    R180 S1      
327GND              U25   -E68        A01X+130704Y+088705X0177Y    R180 S1      
327GND              U25   -E69        A01X+130334Y+088705X0177Y    R180 S1      
327GND              U25   -E70        A01X+129964Y+088705X0177Y    R180 S1      
327GND              U25   -E72        A01X+129224Y+088705X0177Y    R180 S1      
327GND              U25   -E73        A01X+128854Y+088705X0177Y    R180 S1      
327GND              U25   -E75        A01X+128113Y+088705X0177Y    R180 S1      
327GND              U25   -F3         A01X+154574Y+089024X0177Y    R180 S1      
327GND              U25   -F5         A01X+153834Y+089024X0177Y    R180 S1      
327GND              U25   -F8         A01X+152724Y+089024X0177Y    R180 S1      
327GND              U25   -F10        A01X+151984Y+089024X0177Y    R180 S1      
327GND              U25   -F12        A01X+151243Y+089024X0177Y    R180 S1      
327GND              U25   -F15        A01X+150133Y+089024X0177Y    R180 S1      
327GND              U25   -F17        A01X+149393Y+089024X0177Y    R180 S1      
327GND              U25   -F19        A01X+148653Y+089024X0177Y    R180 S1      
327GND              U25   -F23        A01X+147172Y+089024X0177Y    R180 S1      
327GND              U25   -F24        A01X+146802Y+089024X0177Y    R180 S1      
327GND              U25   -F26        A01X+146062Y+089024X0177Y    R180 S1      
327GND              U25   -F27        A01X+145692Y+089024X0177Y    R180 S1      
327GND              U25   -F29        A01X+144952Y+089024X0177Y    R180 S1      
327GND              U25   -F30        A01X+144582Y+089024X0177Y    R180 S1      
327GND              U25   -F32        A01X+143842Y+089024X0177Y    R180 S1      
327GND              U25   -F33        A01X+143472Y+089024X0177Y    R180 S1      
327GND              U25   -F35        A01X+142732Y+089024X0177Y    R180 S1      
327GND              U25   -F36        A01X+142361Y+089024X0177Y    R180 S1      
327GND              U25   -F37        A01X+141991Y+089024X0177Y    R180 S1      
327GND              U25   -F39        A01X+141251Y+089024X0177Y    R180 S1      
327GND              U25   -F40        A01X+140881Y+089024X0177Y    R180 S1      
327GND              U25   -F41        A01X+140511Y+089024X0177Y    R180 S1      
327GND              U25   -F43        A01X+139771Y+089024X0177Y    R180 S1      
327GND              U25   -F44        A01X+139401Y+089024X0177Y    R180 S1      
327GND              U25   -F46        A01X+138661Y+089024X0177Y    R180 S1      
327GND              U25   -F47        A01X+138290Y+089024X0177Y    R180 S1      
327GND              U25   -F49        A01X+137550Y+089024X0177Y    R180 S1      
327GND              U25   -F50        A01X+137180Y+089024X0177Y    R180 S1      
327GND              U25   -F52        A01X+136440Y+089024X0177Y    R180 S1      
327GND              U25   -F53        A01X+136070Y+089024X0177Y    R180 S1      
327GND              U25   -F57        A01X+134590Y+089024X0177Y    R180 S1      
327GND              U25   -F59        A01X+133850Y+089024X0177Y    R180 S1      
327GND              U25   -F61        A01X+133109Y+089024X0177Y    R180 S1      
327GND              U25   -F64        A01X+131999Y+089024X0177Y    R180 S1      
327GND              U25   -F66        A01X+131259Y+089024X0177Y    R180 S1      
327GND              U25   -F68        A01X+130519Y+089024X0177Y    R180 S1      
327GND              U25   -F71        A01X+129409Y+089024X0177Y    R180 S1      
327GND              U25   -F73        A01X+128668Y+089024X0177Y    R180 S1      
327GND              U25   -G1         A01X+155129Y+089343X0177Y    R180 S1      
327GND              U25   -G4         A01X+154019Y+089343X0177Y    R180 S1      
327GND              U25   -G6         A01X+153279Y+089343X0177Y    R180 S1      
327GND              U25   -G8         A01X+152539Y+089343X0177Y    R180 S1      
327GND              U25   -G11        A01X+151428Y+089343X0177Y    R180 S1      
327GND              U25   -G13        A01X+150688Y+089343X0177Y    R180 S1      
327GND              U25   -G15        A01X+149948Y+089343X0177Y    R180 S1      
327GND              U25   -G18        A01X+148838Y+089343X0177Y    R180 S1      
327GND              U25   -G20        A01X+148098Y+089343X0177Y    R180 S1      
327GND              U25   -G22        A01X+147358Y+089343X0177Y    R180 S1      
327GND              U25   -G25        A01X+146247Y+089343X0177Y    R180 S1      
327GND              U25   -G28        A01X+145137Y+089343X0177Y    R180 S1      
327GND              U25   -G31        A01X+144027Y+089343X0177Y    R180 S1      
327GND              U25   -G34        A01X+142916Y+089343X0177Y    R180 S1      
327GND              U25   -G42        A01X+140326Y+089343X0177Y    R180 S1      
327GND              U25   -G45        A01X+139216Y+089343X0177Y    R180 S1      
327GND              U25   -G48        A01X+138106Y+089343X0177Y    R180 S1      
327GND              U25   -G51        A01X+136995Y+089343X0177Y    R180 S1      
327GND              U25   -G54        A01X+135885Y+089343X0177Y    R180 S1      
327GND              U25   -G56        A01X+135145Y+089343X0177Y    R180 S1      
327GND              U25   -G58        A01X+134405Y+089343X0177Y    R180 S1      
327GND              U25   -G61        A01X+133294Y+089343X0177Y    R180 S1      
327GND              U25   -G63        A01X+132554Y+089343X0177Y    R180 S1      
327GND              U25   -G65        A01X+131814Y+089343X0177Y    R180 S1      
327GND              U25   -G68        A01X+130704Y+089343X0177Y    R180 S1      
327GND              U25   -G70        A01X+129964Y+089343X0177Y    R180 S1      
327GND              U25   -G72        A01X+129224Y+089343X0177Y    R180 S1      
327GND              U25   -G75        A01X+128113Y+089343X0177Y    R180 S1      
327GND              U25   -H3         A01X+154574Y+089662X0177Y    R180 S1      
327GND              U25   -H8         A01X+152724Y+089662X0177Y    R180 S1      
327GND              U25   -H10        A01X+151984Y+089662X0177Y    R180 S1      
327GND              U25   -H15        A01X+150133Y+089662X0177Y    R180 S1      
327GND              U25   -H17        A01X+149393Y+089662X0177Y    R180 S1      
327GND              U25   -H22        A01X+147542Y+089662X0177Y    R180 S1      
327GND              U25   -H25        A01X+146432Y+089662X0177Y    R180 S1      
327GND              U25   -H28        A01X+145322Y+089662X0177Y    R180 S1      
327GND              U25   -H31        A01X+144212Y+089662X0177Y    R180 S1      
327GND              U25   -H34        A01X+143102Y+089662X0177Y    R180 S1      
327GND              U25   -H37        A01X+141991Y+089662X0177Y    R180 S1      
327GND              U25   -H39        A01X+141251Y+089662X0177Y    R180 S1      
327GND              U25   -H42        A01X+140141Y+089662X0177Y    R180 S1      
327GND              U25   -H45        A01X+139031Y+089662X0177Y    R180 S1      
327GND              U25   -H48        A01X+137920Y+089662X0177Y    R180 S1      
327GND              U25   -H51        A01X+136810Y+089662X0177Y    R180 S1      
327GND              U25   -H54        A01X+135700Y+089662X0177Y    R180 S1      
327GND              U25   -H59        A01X+133850Y+089662X0177Y    R180 S1      
327GND              U25   -H61        A01X+133109Y+089662X0177Y    R180 S1      
327GND              U25   -H66        A01X+131259Y+089662X0177Y    R180 S1      
327GND              U25   -H68        A01X+130519Y+089662X0177Y    R180 S1      
327GND              U25   -H73        A01X+128668Y+089662X0177Y    R180 S1      
327GND              U25   -J1         A01X+155129Y+089980X0177Y    R180 S1      
327GND              U25   -J4         A01X+154019Y+089980X0177Y    R180 S1      
327GND              U25   -J6         A01X+153279Y+089980X0177Y    R180 S1      
327GND              U25   -J8         A01X+152539Y+089980X0177Y    R180 S1      
327GND              U25   -J11        A01X+151428Y+089980X0177Y    R180 S1      
327GND              U25   -J13        A01X+150688Y+089980X0177Y    R180 S1      
327GND              U25   -J15        A01X+149948Y+089980X0177Y    R180 S1      
327GND              U25   -J18        A01X+148838Y+089980X0177Y    R180 S1      
327GND              U25   -J20        A01X+148098Y+089980X0177Y    R180 S1      
327GND              U25   -J22        A01X+147358Y+089980X0177Y    R180 S1      
327GND              U25   -J25        A01X+146247Y+089980X0177Y    R180 S1      
327GND              U25   -J28        A01X+145137Y+089980X0177Y    R180 S1      
327GND              U25   -J31        A01X+144027Y+089980X0177Y    R180 S1      
327GND              U25   -J34        A01X+142916Y+089980X0177Y    R180 S1      
327GND              U25   -J42        A01X+140326Y+089980X0177Y    R180 S1      
327GND              U25   -J45        A01X+139216Y+089980X0177Y    R180 S1      
327GND              U25   -J48        A01X+138106Y+089980X0177Y    R180 S1      
327GND              U25   -J51        A01X+136995Y+089980X0177Y    R180 S1      
327GND              U25   -J54        A01X+135885Y+089980X0177Y    R180 S1      
327GND              U25   -J56        A01X+135145Y+089980X0177Y    R180 S1      
327GND              U25   -J58        A01X+134405Y+089980X0177Y    R180 S1      
327GND              U25   -J61        A01X+133294Y+089980X0177Y    R180 S1      
327GND              U25   -J63        A01X+132554Y+089980X0177Y    R180 S1      
327GND              U25   -J65        A01X+131814Y+089980X0177Y    R180 S1      
327GND              U25   -J68        A01X+130704Y+089980X0177Y    R180 S1      
327GND              U25   -J70        A01X+129964Y+089980X0177Y    R180 S1      
327GND              U25   -J72        A01X+129224Y+089980X0177Y    R180 S1      
327GND              U25   -J75        A01X+128113Y+089980X0177Y    R180 S1      
327GND              U25   -K3         A01X+154574Y+090299X0177Y    R180 S1      
327GND              U25   -K5         A01X+153834Y+090299X0177Y    R180 S1      
327GND              U25   -K8         A01X+152724Y+090299X0177Y    R180 S1      
327GND              U25   -K10        A01X+151984Y+090299X0177Y    R180 S1      
327GND              U25   -K12        A01X+151243Y+090299X0177Y    R180 S1      
327GND              U25   -K15        A01X+150133Y+090299X0177Y    R180 S1      
327GND              U25   -K17        A01X+149393Y+090299X0177Y    R180 S1      
327GND              U25   -K19        A01X+148653Y+090299X0177Y    R180 S1      
327GND              U25   -K24        A01X+146802Y+090299X0177Y    R180 S1      
327GND              U25   -K25        A01X+146432Y+090299X0177Y    R180 S1      
327GND              U25   -K26        A01X+146062Y+090299X0177Y    R180 S1      
327GND              U25   -K27        A01X+145692Y+090299X0177Y    R180 S1      
327GND              U25   -K28        A01X+145322Y+090299X0177Y    R180 S1      
327GND              U25   -K29        A01X+144952Y+090299X0177Y    R180 S1      
327GND              U25   -K30        A01X+144582Y+090299X0177Y    R180 S1      
327GND              U25   -K31        A01X+144212Y+090299X0177Y    R180 S1      
327GND              U25   -K32        A01X+143842Y+090299X0177Y    R180 S1      
327GND              U25   -K33        A01X+143472Y+090299X0177Y    R180 S1      
327GND              U25   -K34        A01X+143102Y+090299X0177Y    R180 S1      
327GND              U25   -K37        A01X+141991Y+090299X0177Y    R180 S1      
327GND              U25   -K39        A01X+141251Y+090299X0177Y    R180 S1      
327GND              U25   -K42        A01X+140141Y+090299X0177Y    R180 S1      
327GND              U25   -K43        A01X+139771Y+090299X0177Y    R180 S1      
327GND              U25   -K44        A01X+139401Y+090299X0177Y    R180 S1      
327GND              U25   -K45        A01X+139031Y+090299X0177Y    R180 S1      
327GND              U25   -K46        A01X+138661Y+090299X0177Y    R180 S1      
327GND              U25   -K47        A01X+138290Y+090299X0177Y    R180 S1      
327GND              U25   -K48        A01X+137920Y+090299X0177Y    R180 S1      
327GND              U25   -K49        A01X+137550Y+090299X0177Y    R180 S1      
327GND              U25   -K50        A01X+137180Y+090299X0177Y    R180 S1      
327GND              U25   -K51        A01X+136810Y+090299X0177Y    R180 S1      
327GND              U25   -K52        A01X+136440Y+090299X0177Y    R180 S1      
327GND              U25   -K53        A01X+136070Y+090299X0177Y    R180 S1      
327GND              U25   -K57        A01X+134590Y+090299X0177Y    R180 S1      
327GND              U25   -K61        A01X+133109Y+090299X0177Y    R180 S1      
327GND              U25   -K64        A01X+131999Y+090299X0177Y    R180 S1      
327GND              U25   -K66        A01X+131259Y+090299X0177Y    R180 S1      
327GND              U25   -K68        A01X+130519Y+090299X0177Y    R180 S1      
327GND              U25   -K71        A01X+129409Y+090299X0177Y    R180 S1      
327GND              U25   -K73        A01X+128668Y+090299X0177Y    R180 S1      
327GND              U25   -L1         A01X+155129Y+090618X0177Y    R180 S1      
327GND              U25   -L6         A01X+153279Y+090618X0177Y    R180 S1      
327GND              U25   -L8         A01X+152539Y+090618X0177Y    R180 S1      
327GND              U25   -L13        A01X+150688Y+090618X0177Y    R180 S1      
327GND              U25   -L15        A01X+149948Y+090618X0177Y    R180 S1      
327GND              U25   -L20        A01X+148098Y+090618X0177Y    R180 S1      
327GND              U25   -L22        A01X+147358Y+090618X0177Y    R180 S1      
327GND              U25   -L25        A01X+146247Y+090618X0177Y    R180 S1      
327GND              U25   -L28        A01X+145137Y+090618X0177Y    R180 S1      
327GND              U25   -L31        A01X+144027Y+090618X0177Y    R180 S1      
327GND              U25   -L34        A01X+142916Y+090618X0177Y    R180 S1      
327GND              U25   -L35        A01X+142546Y+090618X0177Y    R180 S1      
327GND              U25   -L36        A01X+142176Y+090618X0177Y    R180 S1      
327GND              U25   -L40        A01X+141066Y+090618X0177Y    R180 S1      
327GND              U25   -L41        A01X+140696Y+090618X0177Y    R180 S1      
327GND              U25   -L42        A01X+140326Y+090618X0177Y    R180 S1      
327GND              U25   -L45        A01X+139216Y+090618X0177Y    R180 S1      
327GND              U25   -L48        A01X+138106Y+090618X0177Y    R180 S1      
327GND              U25   -L51        A01X+136995Y+090618X0177Y    R180 S1      
327GND              U25   -L54        A01X+135885Y+090618X0177Y    R180 S1      
327GND              U25   -L56        A01X+135145Y+090618X0177Y    R180 S1      
327GND              U25   -L61        A01X+133294Y+090618X0177Y    R180 S1      
327GND              U25   -L63        A01X+132554Y+090618X0177Y    R180 S1      
327GND              U25   -L68        A01X+130704Y+090618X0177Y    R180 S1      
327GND              U25   -L70        A01X+129964Y+090618X0177Y    R180 S1      
327GND              U25   -L75        A01X+128113Y+090618X0177Y    R180 S1      
327GND              U25   -M3         A01X+154574Y+090937X0177Y    R180 S1      
327GND              U25   -M5         A01X+153834Y+090937X0177Y    R180 S1      
327GND              U25   -M8         A01X+152724Y+090937X0177Y    R180 S1      
327GND              U25   -M12        A01X+151243Y+090937X0177Y    R180 S1      
327GND              U25   -M17        A01X+149393Y+090937X0177Y    R180 S1      
327GND              U25   -M19        A01X+148653Y+090937X0177Y    R180 S1      
327GND              U25   -M22        A01X+147542Y+090937X0177Y    R180 S1      
327GND              U25   -M28        A01X+145322Y+090937X0177Y    R180 S1      
327GND              U25   -M31        A01X+144212Y+090937X0177Y    R180 S1      
327GND              U25   -M37        A01X+141991Y+090937X0177Y    R180 S1      
327GND              U25   -M39        A01X+141251Y+090937X0177Y    R180 S1      
327GND              U25   -M45        A01X+139031Y+090937X0177Y    R180 S1      
327GND              U25   -M48        A01X+137920Y+090937X0177Y    R180 S1      
327GND              U25   -M51        A01X+136810Y+090937X0177Y    R180 S1      
327GND              U25   -M54        A01X+135700Y+090937X0177Y    R180 S1      
327GND              U25   -M59        A01X+133850Y+090937X0177Y    R180 S1      
327GND              U25   -M64        A01X+131999Y+090937X0177Y    R180 S1      
327GND              U25   -M68        A01X+130519Y+090937X0177Y    R180 S1      
327GND              U25   -M71        A01X+129409Y+090937X0177Y    R180 S1      
327GND              U25   -M73        A01X+128668Y+090937X0177Y    R180 S1      
327GND              U25   -N1         A01X+155129Y+091256X0177Y    R180 S1      
327GND              U25   -N4         A01X+154019Y+091256X0177Y    R180 S1      
327GND              U25   -N6         A01X+153279Y+091256X0177Y    R180 S1      
327GND              U25   -N8         A01X+152539Y+091256X0177Y    R180 S1      
327GND              U25   -N11        A01X+151428Y+091256X0177Y    R180 S1      
327GND              U25   -N13        A01X+150688Y+091256X0177Y    R180 S1      
327GND              U25   -N15        A01X+149948Y+091256X0177Y    R180 S1      
327GND              U25   -N18        A01X+148838Y+091256X0177Y    R180 S1      
327GND              U25   -N20        A01X+148098Y+091256X0177Y    R180 S1      
327GND              U25   -N22        A01X+147358Y+091256X0177Y    R180 S1      
327GND              U25   -N25        A01X+146247Y+091256X0177Y    R180 S1      
327GND              U25   -N28        A01X+145137Y+091256X0177Y    R180 S1      
327GND              U25   -N31        A01X+144027Y+091256X0177Y    R180 S1      
327GND              U25   -N34        A01X+142916Y+091256X0177Y    R180 S1      
327GND              U25   -N42        A01X+140326Y+091256X0177Y    R180 S1      
327GND              U25   -N45        A01X+139216Y+091256X0177Y    R180 S1      
327GND              U25   -N48        A01X+138106Y+091256X0177Y    R180 S1      
327GND              U25   -N51        A01X+136995Y+091256X0177Y    R180 S1      
327GND              U25   -N54        A01X+135885Y+091256X0177Y    R180 S1      
327GND              U25   -N56        A01X+135145Y+091256X0177Y    R180 S1      
327GND              U25   -N58        A01X+134405Y+091256X0177Y    R180 S1      
327GND              U25   -N61        A01X+133294Y+091256X0177Y    R180 S1      
327GND              U25   -N63        A01X+132554Y+091256X0177Y    R180 S1      
327GND              U25   -N65        A01X+131814Y+091256X0177Y    R180 S1      
327GND              U25   -N68        A01X+130704Y+091256X0177Y    R180 S1      
327GND              U25   -N70        A01X+129964Y+091256X0177Y    R180 S1      
327GND              U25   -N72        A01X+129224Y+091256X0177Y    R180 S1      
327GND              U25   -N75        A01X+128113Y+091256X0177Y    R180 S1      
327GND              U25   -P3         A01X+154574Y+091575X0177Y    R180 S1      
327GND              U25   -P8         A01X+152724Y+091575X0177Y    R180 S1      
327GND              U25   -P10        A01X+151984Y+091575X0177Y    R180 S1      
327GND              U25   -P15        A01X+150133Y+091575X0177Y    R180 S1      
327GND              U25   -P17        A01X+149393Y+091575X0177Y    R180 S1      
327GND              U25   -P23        A01X+147172Y+091575X0177Y    R180 S1      
327GND              U25   -P24        A01X+146802Y+091575X0177Y    R180 S1      
327GND              U25   -P26        A01X+146062Y+091575X0177Y    R180 S1      
327GND              U25   -P27        A01X+145692Y+091575X0177Y    R180 S1      
327GND              U25   -P28        A01X+145322Y+091575X0177Y    R180 S1      
327GND              U25   -P29        A01X+144952Y+091575X0177Y    R180 S1      
327GND              U25   -P30        A01X+144582Y+091575X0177Y    R180 S1      
327GND              U25   -P31        A01X+144212Y+091575X0177Y    R180 S1      
327GND              U25   -P32        A01X+143842Y+091575X0177Y    R180 S1      
327GND              U25   -P33        A01X+143472Y+091575X0177Y    R180 S1      
327GND              U25   -P34        A01X+143102Y+091575X0177Y    R180 S1      
327GND              U25   -P37        A01X+141991Y+091575X0177Y    R180 S1      
327GND              U25   -P39        A01X+141251Y+091575X0177Y    R180 S1      
327GND              U25   -P42        A01X+140141Y+091575X0177Y    R180 S1      
327GND              U25   -P43        A01X+139771Y+091575X0177Y    R180 S1      
327GND              U25   -P44        A01X+139401Y+091575X0177Y    R180 S1      
327GND              U25   -P45        A01X+139031Y+091575X0177Y    R180 S1      
327GND              U25   -P46        A01X+138661Y+091575X0177Y    R180 S1      
327GND              U25   -P47        A01X+138290Y+091575X0177Y    R180 S1      
327GND              U25   -P48        A01X+137920Y+091575X0177Y    R180 S1      
327GND              U25   -P49        A01X+137550Y+091575X0177Y    R180 S1      
327GND              U25   -P50        A01X+137180Y+091575X0177Y    R180 S1      
327GND              U25   -P51        A01X+136810Y+091575X0177Y    R180 S1      
327GND              U25   -P52        A01X+136440Y+091575X0177Y    R180 S1      
327GND              U25   -P53        A01X+136070Y+091575X0177Y    R180 S1      
327GND              U25   -P59        A01X+133850Y+091575X0177Y    R180 S1      
327GND              U25   -P61        A01X+133109Y+091575X0177Y    R180 S1      
327GND              U25   -P66        A01X+131259Y+091575X0177Y    R180 S1      
327GND              U25   -P73        A01X+128668Y+091575X0177Y    R180 S1      
327GND              U25   -R1         A01X+155129Y+091894X0177Y    R180 S1      
327GND              U25   -R4         A01X+154019Y+091894X0177Y    R180 S1      
327GND              U25   -R6         A01X+153279Y+091894X0177Y    R180 S1      
327GND              U25   -R8         A01X+152539Y+091894X0177Y    R180 S1      
327GND              U25   -R11        A01X+151428Y+091894X0177Y    R180 S1      
327GND              U25   -R13        A01X+150688Y+091894X0177Y    R180 S1      
327GND              U25   -R15        A01X+149948Y+091894X0177Y    R180 S1      
327GND              U25   -R18        A01X+148838Y+091894X0177Y    R180 S1      
327GND              U25   -R20        A01X+148098Y+091894X0177Y    R180 S1      
327GND              U25   -R22        A01X+147358Y+091894X0177Y    R180 S1      
327GND              U25   -R25        A01X+146247Y+091894X0177Y    R180 S1      
327GND              U25   -R28        A01X+145137Y+091894X0177Y    R180 S1      
327GND              U25   -R31        A01X+144027Y+091894X0177Y    R180 S1      
327GND              U25   -R34        A01X+142916Y+091894X0177Y    R180 S1      
327GND              U25   -R35        A01X+142546Y+091894X0177Y    R180 S1      
327GND              U25   -R36        A01X+142176Y+091894X0177Y    R180 S1      
327GND              U25   -R40        A01X+141066Y+091894X0177Y    R180 S1      
327GND              U25   -R41        A01X+140696Y+091894X0177Y    R180 S1      
327GND              U25   -R42        A01X+140326Y+091894X0177Y    R180 S1      
327GND              U25   -R45        A01X+139216Y+091894X0177Y    R180 S1      
327GND              U25   -R48        A01X+138106Y+091894X0177Y    R180 S1      
327GND              U25   -R51        A01X+136995Y+091894X0177Y    R180 S1      
327GND              U25   -R54        A01X+135885Y+091894X0177Y    R180 S1      
327GND              U25   -R56        A01X+135145Y+091894X0177Y    R180 S1      
327GND              U25   -R58        A01X+134405Y+091894X0177Y    R180 S1      
327GND              U25   -R61        A01X+133294Y+091894X0177Y    R180 S1      
327GND              U25   -R63        A01X+132554Y+091894X0177Y    R180 S1      
327GND              U25   -R65        A01X+131814Y+091894X0177Y    R180 S1      
327GND              U25   -R68        A01X+130704Y+091894X0177Y    R180 S1      
327GND              U25   -R70        A01X+129964Y+091894X0177Y    R180 S1      
327GND              U25   -R72        A01X+129224Y+091894X0177Y    R180 S1      
327GND              U25   -R75        A01X+128113Y+091894X0177Y    R180 S1      
327GND              U25   -T3         A01X+154574Y+092213X0177Y    R180 S1      
327GND              U25   -T5         A01X+153834Y+092213X0177Y    R180 S1      
327GND              U25   -T8         A01X+152724Y+092213X0177Y    R180 S1      
327GND              U25   -T10        A01X+151984Y+092213X0177Y    R180 S1      
327GND              U25   -T12        A01X+151243Y+092213X0177Y    R180 S1      
327GND              U25   -T15        A01X+150133Y+092213X0177Y    R180 S1      
327GND              U25   -T17        A01X+149393Y+092213X0177Y    R180 S1      
327GND              U25   -T19        A01X+148653Y+092213X0177Y    R180 S1      
327GND              U25   -T22        A01X+147542Y+092213X0177Y    R180 S1      
327GND              U25   -T25        A01X+146432Y+092213X0177Y    R180 S1      
327GND              U25   -T28        A01X+145322Y+092213X0177Y    R180 S1      
327GND              U25   -T31        A01X+144212Y+092213X0177Y    R180 S1      
327GND              U25   -T34        A01X+143102Y+092213X0177Y    R180 S1      
327GND              U25   -T37        A01X+141991Y+092213X0177Y    R180 S1      
327GND              U25   -T39        A01X+141251Y+092213X0177Y    R180 S1      
327GND              U25   -T42        A01X+140141Y+092213X0177Y    R180 S1      
327GND              U25   -T45        A01X+139031Y+092213X0177Y    R180 S1      
327GND              U25   -T48        A01X+137920Y+092213X0177Y    R180 S1      
327GND              U25   -T51        A01X+136810Y+092213X0177Y    R180 S1      
327GND              U25   -T54        A01X+135700Y+092213X0177Y    R180 S1      
327GND              U25   -T57        A01X+134590Y+092213X0177Y    R180 S1      
327GND              U25   -T59        A01X+133850Y+092213X0177Y    R180 S1      
327GND              U25   -T61        A01X+133109Y+092213X0177Y    R180 S1      
327GND              U25   -T64        A01X+131999Y+092213X0177Y    R180 S1      
327GND              U25   -AA1        A01X+155129Y+093807X0177Y    R180 S1      
327GND              U25   -AA4        A01X+154019Y+093807X0177Y    R180 S1      
327GND              U25   -AA6        A01X+153279Y+093807X0177Y    R180 S1      
327GND              U25   -AA8        A01X+152539Y+093807X0177Y    R180 S1      
327GND              U25   -AA11       A01X+151428Y+093807X0177Y    R180 S1      
327GND              U25   -AA13       A01X+150688Y+093807X0177Y    R180 S1      
327GND              U25   -AA15       A01X+149948Y+093807X0177Y    R180 S1      
327GND              U25   -AA18       A01X+148838Y+093807X0177Y    R180 S1      
327GND              U25   -AA20       A01X+148098Y+093807X0177Y    R180 S1      
327GND              U25   -AA31       A01X+144027Y+093807X0177Y    R180 S1      
327GND              U25   -AA34       A01X+142916Y+093807X0177Y    R180 S1      
327GND              U25   -AA35       A01X+142546Y+093807X0177Y    R180 S1      
327GND              U25   -AA36       A01X+142176Y+093807X0177Y    R180 S1      
327GND              U25   -AA40       A01X+141066Y+093807X0177Y    R180 S1      
327GND              U25   -AA41       A01X+140696Y+093807X0177Y    R180 S1      
327GND              U25   -AA45       A01X+139216Y+093807X0177Y    R180 S1      
327GND              U25   -AA56       A01X+135145Y+093807X0177Y    R180 S1      
327GND              U25   -AA58       A01X+134405Y+093807X0177Y    R180 S1      
327GND              U25   -AA61       A01X+133294Y+093807X0177Y    R180 S1      
327GND              U25   -AA63       A01X+132554Y+093807X0177Y    R180 S1      
327GND              U25   -AA65       A01X+131814Y+093807X0177Y    R180 S1      
327GND              U25   -AA68       A01X+130704Y+093807X0177Y    R180 S1      
327GND              U25   -AA70       A01X+129964Y+093807X0177Y    R180 S1      
327GND              U25   -AA75       A01X+128113Y+093807X0177Y    R180 S1      
327GND              U25   -AB3        A01X+154574Y+094126X0177Y    R180 S1      
327GND              U25   -AB5        A01X+153834Y+094126X0177Y    R180 S1      
327GND              U25   -AB8        A01X+152724Y+094126X0177Y    R180 S1      
327GND              U25   -AB10       A01X+151984Y+094126X0177Y    R180 S1      
327GND              U25   -AB12       A01X+151243Y+094126X0177Y    R180 S1      
327GND              U25   -AB15       A01X+150133Y+094126X0177Y    R180 S1      
327GND              U25   -AB17       A01X+149393Y+094126X0177Y    R180 S1      
327GND              U25   -AB19       A01X+148653Y+094126X0177Y    R180 S1      
327GND              U25   -AB22       A01X+147542Y+094126X0177Y    R180 S1      
327GND              U25   -AB25       A01X+146432Y+094126X0177Y    R180 S1      
327GND              U25   -AB28       A01X+145322Y+094126X0177Y    R180 S1      
327GND              U25   -AB31       A01X+144212Y+094126X0177Y    R180 S1      
327GND              U25   -AB34       A01X+143102Y+094126X0177Y    R180 S1      
327GND              U25   -AB37       A01X+141991Y+094126X0177Y    R180 S1      
327GND              U25   -AB39       A01X+141251Y+094126X0177Y    R180 S1      
327GND              U25   -AB42       A01X+140141Y+094126X0177Y    R180 S1      
327GND              U25   -AB45       A01X+139031Y+094126X0177Y    R180 S1      
327GND              U25   -AB48       A01X+137920Y+094126X0177Y    R180 S1      
327GND              U25   -AB51       A01X+136810Y+094126X0177Y    R180 S1      
327GND              U25   -AB54       A01X+135700Y+094126X0177Y    R180 S1      
327GND              U25   -AB57       A01X+134590Y+094126X0177Y    R180 S1      
327GND              U25   -AB59       A01X+133850Y+094126X0177Y    R180 S1      
327GND              U25   -AB61       A01X+133109Y+094126X0177Y    R180 S1      
327GND              U25   -AB64       A01X+131999Y+094126X0177Y    R180 S1      
327GND              U25   -AB66       A01X+131259Y+094126X0177Y    R180 S1      
327GND              U25   -AB68       A01X+130519Y+094126X0177Y    R180 S1      
327GND              U25   -AB71       A01X+129409Y+094126X0177Y    R180 S1      
327GND              U25   -AB73       A01X+128668Y+094126X0177Y    R180 S1      
327GND              U25   -AC1        A01X+155129Y+094445X0177Y    R180 S1      
327GND              U25   -AC6        A01X+153279Y+094445X0177Y    R180 S1      
327GND              U25   -AC8        A01X+152539Y+094445X0177Y    R180 S1      
327GND              U25   -AC13       A01X+150688Y+094445X0177Y    R180 S1      
327GND              U25   -AC15       A01X+149948Y+094445X0177Y    R180 S1      
327GND              U25   -AC20       A01X+148098Y+094445X0177Y    R180 S1      
327GND              U25   -AC22       A01X+147358Y+094445X0177Y    R180 S1      
327GND              U25   -AC25       A01X+146247Y+094445X0177Y    R180 S1      
327GND              U25   -AC28       A01X+145137Y+094445X0177Y    R180 S1      
327GND              U25   -AC31       A01X+144027Y+094445X0177Y    R180 S1      
327GND              U25   -AC34       A01X+142916Y+094445X0177Y    R180 S1      
327GND              U25   -AC42       A01X+140326Y+094445X0177Y    R180 S1      
327GND              U25   -AC45       A01X+139216Y+094445X0177Y    R180 S1      
327GND              U25   -AC48       A01X+138106Y+094445X0177Y    R180 S1      
327GND              U25   -AC51       A01X+136995Y+094445X0177Y    R180 S1      
327GND              U25   -AC54       A01X+135885Y+094445X0177Y    R180 S1      
327GND              U25   -AC56       A01X+135145Y+094445X0177Y    R180 S1      
327GND              U25   -AC61       A01X+133294Y+094445X0177Y    R180 S1      
327GND              U25   -AC63       A01X+132554Y+094445X0177Y    R180 S1      
327GND              U25   -AC68       A01X+130704Y+094445X0177Y    R180 S1      
327GND              U25   -AC70       A01X+129964Y+094445X0177Y    R180 S1      
327GND              U25   -AC75       A01X+128113Y+094445X0177Y    R180 S1      
327GND              U25   -AD3        A01X+154574Y+094764X0177Y    R180 S1      
327GND              U25   -AD5        A01X+153834Y+094764X0177Y    R180 S1      
327GND              U25   -AD8        A01X+152724Y+094764X0177Y    R180 S1      
327GND              U25   -AD10       A01X+151984Y+094764X0177Y    R180 S1      
327GND              U25   -AD12       A01X+151243Y+094764X0177Y    R180 S1      
327GND              U25   -AD15       A01X+150133Y+094764X0177Y    R180 S1      
327GND              U25   -AD17       A01X+149393Y+094764X0177Y    R180 S1      
327GND              U25   -AD19       A01X+148653Y+094764X0177Y    R180 S1      
327GND              U25   -AD23       A01X+147172Y+094764X0177Y    R180 S1      
327GND              U25   -AD24       A01X+146802Y+094764X0177Y    R180 S1      
327GND              U25   -AD25       A01X+146432Y+094764X0177Y    R180 S1      
327GND              U25   -AD26       A01X+146062Y+094764X0177Y    R180 S1      
327GND              U25   -AD27       A01X+145692Y+094764X0177Y    R180 S1      
327GND              U25   -AD28       A01X+145322Y+094764X0177Y    R180 S1      
327GND              U25   -AD29       A01X+144952Y+094764X0177Y    R180 S1      
327GND              U25   -AD30       A01X+144582Y+094764X0177Y    R180 S1      
327GND              U25   -AD32       A01X+143842Y+094764X0177Y    R180 S1      
327GND              U25   -AD33       A01X+143472Y+094764X0177Y    R180 S1      
327GND              U25   -AD34       A01X+143102Y+094764X0177Y    R180 S1      
327GND              U25   -AD37       A01X+141991Y+094764X0177Y    R180 S1      
327GND              U25   -AD39       A01X+141251Y+094764X0177Y    R180 S1      
327GND              U25   -AD42       A01X+140141Y+094764X0177Y    R180 S1      
327GND              U25   -AD43       A01X+139771Y+094764X0177Y    R180 S1      
327GND              U25   -AD44       A01X+139401Y+094764X0177Y    R180 S1      
327GND              U25   -AD45       A01X+139031Y+094764X0177Y    R180 S1      
327GND              U25   -AD46       A01X+138661Y+094764X0177Y    R180 S1      
327GND              U25   -AD47       A01X+138290Y+094764X0177Y    R180 S1      
327GND              U25   -AD48       A01X+137920Y+094764X0177Y    R180 S1      
327GND              U25   -T66        A01X+131259Y+092213X0177Y    R180 S1      
327GND              U25   -T68        A01X+130519Y+092213X0177Y    R180 S1      
327GND              U25   -T71        A01X+129409Y+092213X0177Y    R180 S1      
327GND              U25   -T73        A01X+128668Y+092213X0177Y    R180 S1      
327GND              U25   -U1         A01X+155129Y+092532X0177Y    R180 S1      
327GND              U25   -U6         A01X+153279Y+092532X0177Y    R180 S1      
327GND              U25   -U8         A01X+152539Y+092532X0177Y    R180 S1      
327GND              U25   -U13        A01X+150688Y+092532X0177Y    R180 S1      
327GND              U25   -U15        A01X+149948Y+092532X0177Y    R180 S1      
327GND              U25   -U20        A01X+148098Y+092532X0177Y    R180 S1      
327GND              U25   -U22        A01X+147358Y+092532X0177Y    R180 S1      
327GND              U25   -U25        A01X+146247Y+092532X0177Y    R180 S1      
327GND              U25   -U28        A01X+145137Y+092532X0177Y    R180 S1      
327GND              U25   -U31        A01X+144027Y+092532X0177Y    R180 S1      
327GND              U25   -U34        A01X+142916Y+092532X0177Y    R180 S1      
327GND              U25   -U42        A01X+140326Y+092532X0177Y    R180 S1      
327GND              U25   -U45        A01X+139216Y+092532X0177Y    R180 S1      
327GND              U25   -U48        A01X+138106Y+092532X0177Y    R180 S1      
327GND              U25   -U51        A01X+136995Y+092532X0177Y    R180 S1      
327GND              U25   -U54        A01X+135885Y+092532X0177Y    R180 S1      
327GND              U25   -U56        A01X+135145Y+092532X0177Y    R180 S1      
327GND              U25   -U61        A01X+133294Y+092532X0177Y    R180 S1      
327GND              U25   -U63        A01X+132554Y+092532X0177Y    R180 S1      
327GND              U25   -U68        A01X+130704Y+092532X0177Y    R180 S1      
327GND              U25   -U70        A01X+129964Y+092532X0177Y    R180 S1      
327GND              U25   -U75        A01X+128113Y+092532X0177Y    R180 S1      
327GND              U25   -V3         A01X+154574Y+092850X0177Y    R180 S1      
327GND              U25   -V5         A01X+153834Y+092850X0177Y    R180 S1      
327GND              U25   -V8         A01X+152724Y+092850X0177Y    R180 S1      
327GND              U25   -V10        A01X+151984Y+092850X0177Y    R180 S1      
327GND              U25   -V12        A01X+151243Y+092850X0177Y    R180 S1      
327GND              U25   -V15        A01X+150133Y+092850X0177Y    R180 S1      
327GND              U25   -V17        A01X+149393Y+092850X0177Y    R180 S1      
327GND              U25   -V19        A01X+148653Y+092850X0177Y    R180 S1      
327GND              U25   -V23        A01X+147172Y+092850X0177Y    R180 S1      
327GND              U25   -V24        A01X+146802Y+092850X0177Y    R180 S1      
327GND              U25   -V25        A01X+146432Y+092850X0177Y    R180 S1      
327GND              U25   -V26        A01X+146062Y+092850X0177Y    R180 S1      
327GND              U25   -V28        A01X+145322Y+092850X0177Y    R180 S1      
327GND              U25   -V29        A01X+144952Y+092850X0177Y    R180 S1      
327GND              U25   -V30        A01X+144582Y+092850X0177Y    R180 S1      
327GND              U25   -V31        A01X+144212Y+092850X0177Y    R180 S1      
327GND              U25   -V32        A01X+143842Y+092850X0177Y    R180 S1      
327GND              U25   -V33        A01X+143472Y+092850X0177Y    R180 S1      
327GND              U25   -V34        A01X+143102Y+092850X0177Y    R180 S1      
327GND              U25   -V37        A01X+141991Y+092850X0177Y    R180 S1      
327GND              U25   -V39        A01X+141251Y+092850X0177Y    R180 S1      
327GND              U25   -V42        A01X+140141Y+092850X0177Y    R180 S1      
327GND              U25   -V43        A01X+139771Y+092850X0177Y    R180 S1      
327GND              U25   -V44        A01X+139401Y+092850X0177Y    R180 S1      
327GND              U25   -V45        A01X+139031Y+092850X0177Y    R180 S1      
327GND              U25   -V46        A01X+138661Y+092850X0177Y    R180 S1      
327GND              U25   -V47        A01X+138290Y+092850X0177Y    R180 S1      
327GND              U25   -V48        A01X+137920Y+092850X0177Y    R180 S1      
327GND              U25   -V49        A01X+137550Y+092850X0177Y    R180 S1      
327GND              U25   -V50        A01X+137180Y+092850X0177Y    R180 S1      
327GND              U25   -V51        A01X+136810Y+092850X0177Y    R180 S1      
327GND              U25   -V52        A01X+136440Y+092850X0177Y    R180 S1      
327GND              U25   -V53        A01X+136070Y+092850X0177Y    R180 S1      
327GND              U25   -V57        A01X+134590Y+092850X0177Y    R180 S1      
327GND              U25   -V59        A01X+133850Y+092850X0177Y    R180 S1      
327GND              U25   -V61        A01X+133109Y+092850X0177Y    R180 S1      
327GND              U25   -V64        A01X+131999Y+092850X0177Y    R180 S1      
327GND              U25   -V66        A01X+131259Y+092850X0177Y    R180 S1      
327GND              U25   -V71        A01X+129409Y+092850X0177Y    R180 S1      
327GND              U25   -V73        A01X+128668Y+092850X0177Y    R180 S1      
327GND              U25   -W1         A01X+155129Y+093169X0177Y    R180 S1      
327GND              U25   -W4         A01X+154019Y+093169X0177Y    R180 S1      
327GND              U25   -W6         A01X+153279Y+093169X0177Y    R180 S1      
327GND              U25   -W8         A01X+152539Y+093169X0177Y    R180 S1      
327GND              U25   -W11        A01X+151428Y+093169X0177Y    R180 S1      
327GND              U25   -W13        A01X+150688Y+093169X0177Y    R180 S1      
327GND              U25   -W15        A01X+149948Y+093169X0177Y    R180 S1      
327GND              U25   -W18        A01X+148838Y+093169X0177Y    R180 S1      
327GND              U25   -W20        A01X+148098Y+093169X0177Y    R180 S1      
327GND              U25   -W22        A01X+147358Y+093169X0177Y    R180 S1      
327GND              U25   -W25        A01X+146247Y+093169X0177Y    R180 S1      
327GND              U25   -W28        A01X+145137Y+093169X0177Y    R180 S1      
327GND              U25   -W34        A01X+142916Y+093169X0177Y    R180 S1      
327GND              U25   -W35        A01X+142546Y+093169X0177Y    R180 S1      
327GND              U25   -W36        A01X+142176Y+093169X0177Y    R180 S1      
327GND              U25   -W40        A01X+141066Y+093169X0177Y    R180 S1      
327GND              U25   -W41        A01X+140696Y+093169X0177Y    R180 S1      
327GND              U25   -W42        A01X+140326Y+093169X0177Y    R180 S1      
327GND              U25   -W45        A01X+139216Y+093169X0177Y    R180 S1      
327GND              U25   -W48        A01X+138106Y+093169X0177Y    R180 S1      
327GND              U25   -W51        A01X+136995Y+093169X0177Y    R180 S1      
327GND              U25   -W54        A01X+135885Y+093169X0177Y    R180 S1      
327GND              U25   -W56        A01X+135145Y+093169X0177Y    R180 S1      
327GND              U25   -W58        A01X+134405Y+093169X0177Y    R180 S1      
327GND              U25   -W61        A01X+133294Y+093169X0177Y    R180 S1      
327GND              U25   -W63        A01X+132554Y+093169X0177Y    R180 S1      
327GND              U25   -W65        A01X+131814Y+093169X0177Y    R180 S1      
327GND              U25   -W68        A01X+130704Y+093169X0177Y    R180 S1      
327GND              U25   -W70        A01X+129964Y+093169X0177Y    R180 S1      
327GND              U25   -W72        A01X+129224Y+093169X0177Y    R180 S1      
327GND              U25   -W75        A01X+128113Y+093169X0177Y    R180 S1      
327GND              U25   -Y3         A01X+154574Y+093488X0177Y    R180 S1      
327GND              U25   -Y8         A01X+152724Y+093488X0177Y    R180 S1      
327GND              U25   -Y10        A01X+151984Y+093488X0177Y    R180 S1      
327GND              U25   -Y15        A01X+150133Y+093488X0177Y    R180 S1      
327GND              U25   -Y17        A01X+149393Y+093488X0177Y    R180 S1      
327GND              U25   -Y22        A01X+147542Y+093488X0177Y    R180 S1      
327GND              U25   -Y23        A01X+147172Y+093488X0177Y    R180 S1      
327GND              U25   -Y24        A01X+146802Y+093488X0177Y    R180 S1      
327GND              U25   -Y25        A01X+146432Y+093488X0177Y    R180 S1      
327GND              U25   -Y26        A01X+146062Y+093488X0177Y    R180 S1      
327GND              U25   -Y27        A01X+145692Y+093488X0177Y    R180 S1      
327GND              U25   -Y28        A01X+145322Y+093488X0177Y    R180 S1      
327GND              U25   -Y31        A01X+144212Y+093488X0177Y    R180 S1      
327GND              U25   -Y32        A01X+143842Y+093488X0177Y    R180 S1      
327GND              U25   -Y33        A01X+143472Y+093488X0177Y    R180 S1      
327GND              U25   -Y34        A01X+143102Y+093488X0177Y    R180 S1      
327GND              U25   -Y37        A01X+141991Y+093488X0177Y    R180 S1      
327GND              U25   -Y39        A01X+141251Y+093488X0177Y    R180 S1      
327GND              U25   -Y42        A01X+140141Y+093488X0177Y    R180 S1      
327GND              U25   -Y43        A01X+139771Y+093488X0177Y    R180 S1      
327GND              U25   -Y44        A01X+139401Y+093488X0177Y    R180 S1      
327GND              U25   -Y45        A01X+139031Y+093488X0177Y    R180 S1      
327GND              U25   -Y48        A01X+137920Y+093488X0177Y    R180 S1      
327GND              U25   -Y49        A01X+137550Y+093488X0177Y    R180 S1      
327GND              U25   -Y50        A01X+137180Y+093488X0177Y    R180 S1      
327GND              U25   -Y51        A01X+136810Y+093488X0177Y    R180 S1      
327GND              U25   -Y52        A01X+136440Y+093488X0177Y    R180 S1      
327GND              U25   -Y53        A01X+136070Y+093488X0177Y    R180 S1      
327GND              U25   -Y54        A01X+135700Y+093488X0177Y    R180 S1      
327GND              U25   -Y59        A01X+133850Y+093488X0177Y    R180 S1      
327GND              U25   -Y61        A01X+133109Y+093488X0177Y    R180 S1      
327GND              U25   -Y66        A01X+131259Y+093488X0177Y    R180 S1      
327GND              U25   -Y68        A01X+130519Y+093488X0177Y    R180 S1      
327GND              U25   -Y73        A01X+128668Y+093488X0177Y    R180 S1      
327GND              U25   -AD49       A01X+137550Y+094764X0177Y    R180 S1      
327GND              U25   -AD50       A01X+137180Y+094764X0177Y    R180 S1      
327GND              U25   -AD51       A01X+136810Y+094764X0177Y    R180 S1      
327GND              U25   -AD52       A01X+136440Y+094764X0177Y    R180 S1      
327GND              U25   -AD53       A01X+136070Y+094764X0177Y    R180 S1      
327GND              U25   -AD57       A01X+134590Y+094764X0177Y    R180 S1      
327GND              U25   -AD59       A01X+133850Y+094764X0177Y    R180 S1      
327GND              U25   -AD61       A01X+133109Y+094764X0177Y    R180 S1      
327GND              U25   -AD64       A01X+131999Y+094764X0177Y    R180 S1      
327GND              U25   -AD66       A01X+131259Y+094764X0177Y    R180 S1      
327GND              U25   -AD68       A01X+130519Y+094764X0177Y    R180 S1      
327GND              U25   -AD71       A01X+129409Y+094764X0177Y    R180 S1      
327GND              U25   -AD73       A01X+128668Y+094764X0177Y    R180 S1      
327GND              U25   -AE1        A01X+155129Y+095083X0177Y    R180 S1      
327GND              U25   -AE6        A01X+153279Y+095083X0177Y    R180 S1      
327GND              U25   -AE8        A01X+152539Y+095083X0177Y    R180 S1      
327GND              U25   -AE11       A01X+151428Y+095083X0177Y    R180 S1      
327GND              U25   -AE13       A01X+150688Y+095083X0177Y    R180 S1      
327GND              U25   -AE15       A01X+149948Y+095083X0177Y    R180 S1      
327GND              U25   -AE18       A01X+148838Y+095083X0177Y    R180 S1      
327GND              U25   -AE20       A01X+148098Y+095083X0177Y    R180 S1      
327GND              U25   -AE22       A01X+147358Y+095083X0177Y    R180 S1      
327GND              U25   -AE25       A01X+146247Y+095083X0177Y    R180 S1      
327GND              U25   -AE28       A01X+145137Y+095083X0177Y    R180 S1      
327GND              U25   -AE31       A01X+144027Y+095083X0177Y    R180 S1      
327GND              U25   -AE34       A01X+142916Y+095083X0177Y    R180 S1      
327GND              U25   -AE35       A01X+142546Y+095083X0177Y    R180 S1      
327GND              U25   -AE36       A01X+142176Y+095083X0177Y    R180 S1      
327GND              U25   -AE40       A01X+141066Y+095083X0177Y    R180 S1      
327GND              U25   -AE41       A01X+140696Y+095083X0177Y    R180 S1      
327GND              U25   -AE42       A01X+140326Y+095083X0177Y    R180 S1      
327GND              U25   -AE45       A01X+139216Y+095083X0177Y    R180 S1      
327GND              U25   -AE48       A01X+138106Y+095083X0177Y    R180 S1      
327GND              U25   -AE51       A01X+136995Y+095083X0177Y    R180 S1      
327GND              U25   -AE54       A01X+135885Y+095083X0177Y    R180 S1      
327GND              U25   -AE56       A01X+135145Y+095083X0177Y    R180 S1      
327GND              U25   -AE58       A01X+134405Y+095083X0177Y    R180 S1      
327GND              U25   -AE61       A01X+133294Y+095083X0177Y    R180 S1      
327GND              U25   -AE63       A01X+132554Y+095083X0177Y    R180 S1      
327GND              U25   -AE65       A01X+131814Y+095083X0177Y    R180 S1      
327GND              U25   -AE68       A01X+130704Y+095083X0177Y    R180 S1      
327GND              U25   -AE70       A01X+129964Y+095083X0177Y    R180 S1      
327GND              U25   -AE72       A01X+129224Y+095083X0177Y    R180 S1      
327GND              U25   -AE75       A01X+128113Y+095083X0177Y    R180 S1      
327GND              U25   -AF3        A01X+154574Y+095402X0177Y    R180 S1      
327GND              U25   -AF8        A01X+152724Y+095402X0177Y    R180 S1      
327GND              U25   -AF10       A01X+151984Y+095402X0177Y    R180 S1      
327GND              U25   -AF15       A01X+150133Y+095402X0177Y    R180 S1      
327GND              U25   -AF17       A01X+149393Y+095402X0177Y    R180 S1      
327GND              U25   -AF22       A01X+147542Y+095402X0177Y    R180 S1      
327GND              U25   -AF25       A01X+146432Y+095402X0177Y    R180 S1      
327GND              U25   -AF28       A01X+145322Y+095402X0177Y    R180 S1      
327GND              U25   -AF31       A01X+144212Y+095402X0177Y    R180 S1      
327GND              U25   -AF34       A01X+143102Y+095402X0177Y    R180 S1      
327GND              U25   -AF37       A01X+141991Y+095402X0177Y    R180 S1      
327GND              U25   -AF39       A01X+141251Y+095402X0177Y    R180 S1      
327GND              U25   -AF42       A01X+140141Y+095402X0177Y    R180 S1      
327GND              U25   -AF45       A01X+139031Y+095402X0177Y    R180 S1      
327GND              U25   -AF48       A01X+137920Y+095402X0177Y    R180 S1      
327GND              U25   -AF51       A01X+136810Y+095402X0177Y    R180 S1      
327GND              U25   -AF54       A01X+135700Y+095402X0177Y    R180 S1      
327GND              U25   -AF59       A01X+133850Y+095402X0177Y    R180 S1      
327GND              U25   -AF61       A01X+133109Y+095402X0177Y    R180 S1      
327GND              U25   -AF66       A01X+131259Y+095402X0177Y    R180 S1      
327GND              U25   -AF68       A01X+130519Y+095402X0177Y    R180 S1      
327GND              U25   -AF73       A01X+128668Y+095402X0177Y    R180 S1      
327GND              U25   -AG1        A01X+155129Y+095720X0177Y    R180 S1      
327GND              U25   -AG4        A01X+154019Y+095720X0177Y    R180 S1      
327GND              U25   -AG6        A01X+153279Y+095720X0177Y    R180 S1      
327GND              U25   -AG8        A01X+152539Y+095720X0177Y    R180 S1      
327GND              U25   -AG11       A01X+151428Y+095720X0177Y    R180 S1      
327GND              U25   -AG13       A01X+150688Y+095720X0177Y    R180 S1      
327GND              U25   -AG15       A01X+149948Y+095720X0177Y    R180 S1      
327GND              U25   -AG18       A01X+148838Y+095720X0177Y    R180 S1      
327GND              U25   -AG20       A01X+148098Y+095720X0177Y    R180 S1      
327GND              U25   -AG22       A01X+147358Y+095720X0177Y    R180 S1      
327GND              U25   -AG25       A01X+146247Y+095720X0177Y    R180 S1      
327GND              U25   -AG28       A01X+145137Y+095720X0177Y    R180 S1      
327GND              U25   -AG31       A01X+144027Y+095720X0177Y    R180 S1      
327GND              U25   -AG34       A01X+142916Y+095720X0177Y    R180 S1      
327GND              U25   -AG42       A01X+140326Y+095720X0177Y    R180 S1      
327GND              U25   -AG45       A01X+139216Y+095720X0177Y    R180 S1      
327GND              U25   -AG48       A01X+138106Y+095720X0177Y    R180 S1      
327GND              U25   -AG51       A01X+136995Y+095720X0177Y    R180 S1      
327GND              U25   -AG54       A01X+135885Y+095720X0177Y    R180 S1      
327GND              U25   -AG56       A01X+135145Y+095720X0177Y    R180 S1      
327GND              U25   -AG58       A01X+134405Y+095720X0177Y    R180 S1      
327GND              U25   -AG61       A01X+133294Y+095720X0177Y    R180 S1      
327GND              U25   -AG63       A01X+132554Y+095720X0177Y    R180 S1      
327GND              U25   -AG65       A01X+131814Y+095720X0177Y    R180 S1      
327GND              U25   -AG68       A01X+130704Y+095720X0177Y    R180 S1      
327GND              U25   -AG70       A01X+129964Y+095720X0177Y    R180 S1      
327GND              U25   -AG72       A01X+129224Y+095720X0177Y    R180 S1      
327GND              U25   -AG75       A01X+128113Y+095720X0177Y    R180 S1      
327GND              U25   -AH3        A01X+154574Y+096039X0177Y    R180 S1      
327GND              U25   -AH5        A01X+153834Y+096039X0177Y    R180 S1      
327GND              U25   -AH8        A01X+152724Y+096039X0177Y    R180 S1      
327GND              U25   -AH10       A01X+151984Y+096039X0177Y    R180 S1      
327GND              U25   -AH12       A01X+151243Y+096039X0177Y    R180 S1      
327GND              U25   -AH15       A01X+150133Y+096039X0177Y    R180 S1      
327GND              U25   -AH17       A01X+149393Y+096039X0177Y    R180 S1      
327GND              U25   -AH19       A01X+148653Y+096039X0177Y    R180 S1      
327GND              U25   -AH23       A01X+147172Y+096039X0177Y    R180 S1      
327GND              U25   -AH24       A01X+146802Y+096039X0177Y    R180 S1      
327GND              U25   -AH25       A01X+146432Y+096039X0177Y    R180 S1      
327GND              U25   -AH26       A01X+146062Y+096039X0177Y    R180 S1      
327GND              U25   -AH27       A01X+145692Y+096039X0177Y    R180 S1      
327GND              U25   -AH28       A01X+145322Y+096039X0177Y    R180 S1      
327GND              U25   -AH29       A01X+144952Y+096039X0177Y    R180 S1      
327GND              U25   -AH30       A01X+144582Y+096039X0177Y    R180 S1      
327GND              U25   -AH31       A01X+144212Y+096039X0177Y    R180 S1      
327GND              U25   -AH32       A01X+143842Y+096039X0177Y    R180 S1      
327GND              U25   -AH34       A01X+143102Y+096039X0177Y    R180 S1      
327GND              U25   -AH37       A01X+141991Y+096039X0177Y    R180 S1      
327GND              U25   -AH39       A01X+141251Y+096039X0177Y    R180 S1      
327GND              U25   -AH42       A01X+140141Y+096039X0177Y    R180 S1      
327GND              U25   -AH43       A01X+139771Y+096039X0177Y    R180 S1      
327GND              U25   -AH44       A01X+139401Y+096039X0177Y    R180 S1      
327GND              U25   -AH45       A01X+139031Y+096039X0177Y    R180 S1      
327GND              U25   -AH46       A01X+138661Y+096039X0177Y    R180 S1      
327GND              U25   -AH47       A01X+138290Y+096039X0177Y    R180 S1      
327GND              U25   -AH48       A01X+137920Y+096039X0177Y    R180 S1      
327GND              U25   -AH49       A01X+137550Y+096039X0177Y    R180 S1      
327GND              U25   -AH50       A01X+137180Y+096039X0177Y    R180 S1      
327GND              U25   -AH51       A01X+136810Y+096039X0177Y    R180 S1      
327GND              U25   -AH52       A01X+136440Y+096039X0177Y    R180 S1      
327GND              U25   -AH53       A01X+136070Y+096039X0177Y    R180 S1      
327GND              U25   -AH57       A01X+134590Y+096039X0177Y    R180 S1      
327GND              U25   -AH59       A01X+133850Y+096039X0177Y    R180 S1      
327GND              U25   -AH61       A01X+133109Y+096039X0177Y    R180 S1      
327GND              U25   -AH64       A01X+131999Y+096039X0177Y    R180 S1      
327GND              U25   -AH66       A01X+131259Y+096039X0177Y    R180 S1      
327GND              U25   -AH68       A01X+130519Y+096039X0177Y    R180 S1      
327GND              U25   -AH71       A01X+129409Y+096039X0177Y    R180 S1      
327GND              U25   -AH73       A01X+128668Y+096039X0177Y    R180 S1      
327GND              U25   -AJ1        A01X+155129Y+096358X0177Y    R180 S1      
327GND              U25   -AJ6        A01X+153279Y+096358X0177Y    R180 S1      
327GND              U25   -AJ8        A01X+152539Y+096358X0177Y    R180 S1      
327GND              U25   -AJ15       A01X+149948Y+096358X0177Y    R180 S1      
327GND              U25   -AJ20       A01X+148098Y+096358X0177Y    R180 S1      
327GND              U25   -AJ22       A01X+147358Y+096358X0177Y    R180 S1      
327GND              U25   -AJ25       A01X+146247Y+096358X0177Y    R180 S1      
327GND              U25   -AJ28       A01X+145137Y+096358X0177Y    R180 S1      
327GND              U25   -AJ31       A01X+144027Y+096358X0177Y    R180 S1      
327GND              U25   -AJ34       A01X+142916Y+096358X0177Y    R180 S1      
327GND              U25   -AJ35       A01X+142546Y+096358X0177Y    R180 S1      
327GND              U25   -AJ36       A01X+142176Y+096358X0177Y    R180 S1      
327GND              U25   -AJ40       A01X+141066Y+096358X0177Y    R180 S1      
327GND              U25   -AJ41       A01X+140696Y+096358X0177Y    R180 S1      
327GND              U25   -AJ42       A01X+140326Y+096358X0177Y    R180 S1      
327GND              U25   -AJ45       A01X+139216Y+096358X0177Y    R180 S1      
327GND              U25   -AJ48       A01X+138106Y+096358X0177Y    R180 S1      
327GND              U25   -AJ51       A01X+136995Y+096358X0177Y    R180 S1      
327GND              U25   -AJ54       A01X+135885Y+096358X0177Y    R180 S1      
327GND              U25   -AJ56       A01X+135145Y+096358X0177Y    R180 S1      
327GND              U25   -AJ61       A01X+133294Y+096358X0177Y    R180 S1      
327GND              U25   -AJ63       A01X+132554Y+096358X0177Y    R180 S1      
327GND              U25   -AJ68       A01X+130704Y+096358X0177Y    R180 S1      
327GND              U25   -AJ70       A01X+129964Y+096358X0177Y    R180 S1      
327GND              U25   -AJ75       A01X+128113Y+096358X0177Y    R180 S1      
327GND              U25   -AK3        A01X+154574Y+096677X0177Y    R180 S1      
327GND              U25   -AK5        A01X+153834Y+096677X0177Y    R180 S1      
327GND              U25   -AK8        A01X+152724Y+096677X0177Y    R180 S1      
327GND              U25   -AK10       A01X+151984Y+096677X0177Y    R180 S1      
327GND              U25   -AK12       A01X+151243Y+096677X0177Y    R180 S1      
327GND              U25   -AK15       A01X+150133Y+096677X0177Y    R180 S1      
327GND              U25   -AK17       A01X+149393Y+096677X0177Y    R180 S1      
327GND              U25   -AK19       A01X+148653Y+096677X0177Y    R180 S1      
327GND              U25   -AK22       A01X+147542Y+096677X0177Y    R180 S1      
327GND              U25   -AK25       A01X+146432Y+096677X0177Y    R180 S1      
327GND              U25   -AK28       A01X+145322Y+096677X0177Y    R180 S1      
327GND              U25   -AK31       A01X+144212Y+096677X0177Y    R180 S1      
327GND              U25   -AK34       A01X+143102Y+096677X0177Y    R180 S1      
327GND              U25   -AK37       A01X+141991Y+096677X0177Y    R180 S1      
327GND              U25   -AK39       A01X+141251Y+096677X0177Y    R180 S1      
327GND              U25   -AK42       A01X+140141Y+096677X0177Y    R180 S1      
327GND              U25   -AK45       A01X+139031Y+096677X0177Y    R180 S1      
327GND              U25   -AK48       A01X+137920Y+096677X0177Y    R180 S1      
327GND              U25   -AK51       A01X+136810Y+096677X0177Y    R180 S1      
327GND              U25   -AK54       A01X+135700Y+096677X0177Y    R180 S1      
327GND              U25   -AK57       A01X+134590Y+096677X0177Y    R180 S1      
327GND              U25   -AK59       A01X+133850Y+096677X0177Y    R180 S1      
327GND              U25   -AK61       A01X+133109Y+096677X0177Y    R180 S1      
327GND              U25   -AK64       A01X+131999Y+096677X0177Y    R180 S1      
327GND              U25   -AK66       A01X+131259Y+096677X0177Y    R180 S1      
327GND              U25   -AK68       A01X+130519Y+096677X0177Y    R180 S1      
327GND              U25   -AK71       A01X+129409Y+096677X0177Y    R180 S1      
327GND              U25   -AK73       A01X+128668Y+096677X0177Y    R180 S1      
327GND              U25   -AL1        A01X+155129Y+096996X0177Y    R180 S1      
327GND              U25   -AL4        A01X+154019Y+096996X0177Y    R180 S1      
327GND              U25   -AL6        A01X+153279Y+096996X0177Y    R180 S1      
327GND              U25   -AL8        A01X+152539Y+096996X0177Y    R180 S1      
327GND              U25   -AL11       A01X+151428Y+096996X0177Y    R180 S1      
327GND              U25   -AL13       A01X+150688Y+096996X0177Y    R180 S1      
327GND              U25   -AL15       A01X+149948Y+096996X0177Y    R180 S1      
327GND              U25   -AL18       A01X+148838Y+096996X0177Y    R180 S1      
327GND              U25   -AL20       A01X+148098Y+096996X0177Y    R180 S1      
327GND              U25   -AL22       A01X+147358Y+096996X0177Y    R180 S1      
327GND              U25   -AL25       A01X+146247Y+096996X0177Y    R180 S1      
327GND              U25   -AL28       A01X+145137Y+096996X0177Y    R180 S1      
327GND              U25   -AL31       A01X+144027Y+096996X0177Y    R180 S1      
327GND              U25   -AL34       A01X+142916Y+096996X0177Y    R180 S1      
327GND              U25   -AL42       A01X+140326Y+096996X0177Y    R180 S1      
327GND              U25   -AL45       A01X+139216Y+096996X0177Y    R180 S1      
327GND              U25   -AL48       A01X+138106Y+096996X0177Y    R180 S1      
327GND              U25   -AL51       A01X+136995Y+096996X0177Y    R180 S1      
327GND              U25   -AL54       A01X+135885Y+096996X0177Y    R180 S1      
327GND              U25   -AL56       A01X+135145Y+096996X0177Y    R180 S1      
327GND              U25   -AL58       A01X+134405Y+096996X0177Y    R180 S1      
327GND              U25   -AL61       A01X+133294Y+096996X0177Y    R180 S1      
327GND              U25   -AL63       A01X+132554Y+096996X0177Y    R180 S1      
327GND              U25   -AL65       A01X+131814Y+096996X0177Y    R180 S1      
327GND              U25   -AL68       A01X+130704Y+096996X0177Y    R180 S1      
327GND              U25   -AL70       A01X+129964Y+096996X0177Y    R180 S1      
327GND              U25   -AL72       A01X+129224Y+096996X0177Y    R180 S1      
327GND              U25   -AL75       A01X+128113Y+096996X0177Y    R180 S1      
327GND              U25   -AM3        A01X+154574Y+097315X0177Y    R180 S1      
327GND              U25   -AM8        A01X+152724Y+097315X0177Y    R180 S1      
327GND              U25   -AM10       A01X+151984Y+097315X0177Y    R180 S1      
327GND              U25   -AM15       A01X+150133Y+097315X0177Y    R180 S1      
327GND              U25   -AM17       A01X+149393Y+097315X0177Y    R180 S1      
327GND              U25   -AM23       A01X+147172Y+097315X0177Y    R180 S1      
327GND              U25   -AM24       A01X+146802Y+097315X0177Y    R180 S1      
327GND              U25   -AM25       A01X+146432Y+097315X0177Y    R180 S1      
327GND              U25   -AM26       A01X+146062Y+097315X0177Y    R180 S1      
327GND              U25   -AM27       A01X+145692Y+097315X0177Y    R180 S1      
327GND              U25   -AM28       A01X+145322Y+097315X0177Y    R180 S1      
327GND              U25   -AM29       A01X+144952Y+097315X0177Y    R180 S1      
327GND              U25   -AM30       A01X+144582Y+097315X0177Y    R180 S1      
327GND              U25   -AM31       A01X+144212Y+097315X0177Y    R180 S1      
327GND              U25   -AM32       A01X+143842Y+097315X0177Y    R180 S1      
327GND              U25   -AM33       A01X+143472Y+097315X0177Y    R180 S1      
327GND              U25   -AM34       A01X+143102Y+097315X0177Y    R180 S1      
327GND              U25   -AM39       A01X+141251Y+097315X0177Y    R180 S1      
327GND              U25   -AM42       A01X+140141Y+097315X0177Y    R180 S1      
327GND              U25   -AM43       A01X+139771Y+097315X0177Y    R180 S1      
327GND              U25   -AM44       A01X+139401Y+097315X0177Y    R180 S1      
327GND              U25   -AM45       A01X+139031Y+097315X0177Y    R180 S1      
327GND              U25   -AM46       A01X+138661Y+097315X0177Y    R180 S1      
327GND              U25   -AM47       A01X+138290Y+097315X0177Y    R180 S1      
327GND              U25   -AM48       A01X+137920Y+097315X0177Y    R180 S1      
327GND              U25   -AM49       A01X+137550Y+097315X0177Y    R180 S1      
327GND              U25   -AM50       A01X+137180Y+097315X0177Y    R180 S1      
327GND              U25   -AM51       A01X+136810Y+097315X0177Y    R180 S1      
327GND              U25   -AM52       A01X+136440Y+097315X0177Y    R180 S1      
327GND              U25   -AM53       A01X+136070Y+097315X0177Y    R180 S1      
327GND              U25   -AM59       A01X+133850Y+097315X0177Y    R180 S1      
327GND              U25   -AM61       A01X+133109Y+097315X0177Y    R180 S1      
327GND              U25   -AM66       A01X+131259Y+097315X0177Y    R180 S1      
327GND              U25   -AM68       A01X+130519Y+097315X0177Y    R180 S1      
327GND              U25   -AM73       A01X+128668Y+097315X0177Y    R180 S1      
327GND              U25   -AN1        A01X+155129Y+097634X0177Y    R180 S1      
327GND              U25   -AN4        A01X+154019Y+097634X0177Y    R180 S1      
327GND              U25   -AN6        A01X+153279Y+097634X0177Y    R180 S1      
327GND              U25   -AN8        A01X+152539Y+097634X0177Y    R180 S1      
327GND              U25   -AN11       A01X+151428Y+097634X0177Y    R180 S1      
327GND              U25   -AN13       A01X+150688Y+097634X0177Y    R180 S1      
327GND              U25   -AN15       A01X+149948Y+097634X0177Y    R180 S1      
327GND              U25   -AN18       A01X+148838Y+097634X0177Y    R180 S1      
327GND              U25   -AN22       A01X+147358Y+097634X0177Y    R180 S1      
327GND              U25   -AN25       A01X+146247Y+097634X0177Y    R180 S1      
327GND              U25   -AN28       A01X+145137Y+097634X0177Y    R180 S1      
327GND              U25   -AN31       A01X+144027Y+097634X0177Y    R180 S1      
327GND              U25   -AN34       A01X+142916Y+097634X0177Y    R180 S1      
327GND              U25   -AN35       A01X+142546Y+097634X0177Y    R180 S1      
327GND              U25   -AN36       A01X+142176Y+097634X0177Y    R180 S1      
327GND              U25   -AN40       A01X+141066Y+097634X0177Y    R180 S1      
327GND              U25   -AN41       A01X+140696Y+097634X0177Y    R180 S1      
327GND              U25   -AN42       A01X+140326Y+097634X0177Y    R180 S1      
327GND              U25   -AN45       A01X+139216Y+097634X0177Y    R180 S1      
327GND              U25   -AN48       A01X+138106Y+097634X0177Y    R180 S1      
327GND              U25   -AN51       A01X+136995Y+097634X0177Y    R180 S1      
327GND              U25   -AN54       A01X+135885Y+097634X0177Y    R180 S1      
327GND              U25   -AN56       A01X+135145Y+097634X0177Y    R180 S1      
327GND              U25   -AN58       A01X+134405Y+097634X0177Y    R180 S1      
327GND              U25   -AN61       A01X+133294Y+097634X0177Y    R180 S1      
327GND              U25   -AN63       A01X+132554Y+097634X0177Y    R180 S1      
327GND              U25   -AN65       A01X+131814Y+097634X0177Y    R180 S1      
327GND              U25   -AN68       A01X+130704Y+097634X0177Y    R180 S1      
327GND              U25   -AN70       A01X+129964Y+097634X0177Y    R180 S1      
327GND              U25   -AN72       A01X+129224Y+097634X0177Y    R180 S1      
327GND              U25   -AN75       A01X+128113Y+097634X0177Y    R180 S1      
327GND              U25   -AP3        A01X+154574Y+097953X0177Y    R180 S1      
327GND              U25   -AP5        A01X+153834Y+097953X0177Y    R180 S1      
327GND              U25   -AP8        A01X+152724Y+097953X0177Y    R180 S1      
327GND              U25   -AP10       A01X+151984Y+097953X0177Y    R180 S1      
327GND              U25   -AP12       A01X+151243Y+097953X0177Y    R180 S1      
327GND              U25   -AP15       A01X+150133Y+097953X0177Y    R180 S1      
327GND              U25   -AP17       A01X+149393Y+097953X0177Y    R180 S1      
327GND              U25   -AP19       A01X+148653Y+097953X0177Y    R180 S1      
327GND              U25   -AP22       A01X+147542Y+097953X0177Y    R180 S1      
327GND              U25   -AP25       A01X+146432Y+097953X0177Y    R180 S1      
327GND              U25   -AP28       A01X+145322Y+097953X0177Y    R180 S1      
327GND              U25   -AP31       A01X+144212Y+097953X0177Y    R180 S1      
327GND              U25   -AP34       A01X+143102Y+097953X0177Y    R180 S1      
327GND              U25   -AP37       A01X+141991Y+097953X0177Y    R180 S1      
327GND              U25   -AP39       A01X+141251Y+097953X0177Y    R180 S1      
327GND              U25   -AP42       A01X+140141Y+097953X0177Y    R180 S1      
327GND              U25   -AP45       A01X+139031Y+097953X0177Y    R180 S1      
327GND              U25   -AP48       A01X+137920Y+097953X0177Y    R180 S1      
327GND              U25   -AP51       A01X+136810Y+097953X0177Y    R180 S1      
327GND              U25   -AP54       A01X+135700Y+097953X0177Y    R180 S1      
327GND              U25   -AP57       A01X+134590Y+097953X0177Y    R180 S1      
327GND              U25   -AP59       A01X+133850Y+097953X0177Y    R180 S1      
327GND              U25   -AP61       A01X+133109Y+097953X0177Y    R180 S1      
327GND              U25   -AP64       A01X+131999Y+097953X0177Y    R180 S1      
327GND              U25   -AP66       A01X+131259Y+097953X0177Y    R180 S1      
327GND              U25   -AP68       A01X+130519Y+097953X0177Y    R180 S1      
327GND              U25   -AP71       A01X+129409Y+097953X0177Y    R180 S1      
327GND              U25   -AP73       A01X+128668Y+097953X0177Y    R180 S1      
327GND              U25   -AR1        A01X+155129Y+098272X0177Y    R180 S1      
327GND              U25   -AR5        A01X+153649Y+098272X0177Y    R180 S1      
327GND              U25   -AR6        A01X+153279Y+098272X0177Y    R180 S1      
327GND              U25   -AR8        A01X+152539Y+098272X0177Y    R180 S1      
327GND              U25   -AR9        A01X+152168Y+098272X0177Y    R180 S1      
327GND              U25   -AR12       A01X+151058Y+098272X0177Y    R180 S1      
327GND              U25   -AR13       A01X+150688Y+098272X0177Y    R180 S1      
327GND              U25   -AR15       A01X+149948Y+098272X0177Y    R180 S1      
327GND              U25   -AR16       A01X+149578Y+098272X0177Y    R180 S1      
327GND              U25   -AR19       A01X+148468Y+098272X0177Y    R180 S1      
327GND              U25   -AR20       A01X+148098Y+098272X0177Y    R180 S1      
327GND              U25   -AR22       A01X+147358Y+098272X0177Y    R180 S1      
327GND              U25   -AR24       A01X+146617Y+098272X0177Y    R180 S1      
327GND              U25   -AR26       A01X+145877Y+098272X0177Y    R180 S1      
327GND              U25   -AR28       A01X+145137Y+098272X0177Y    R180 S1      
327GND              U25   -AR30       A01X+144397Y+098272X0177Y    R180 S1      
327GND              U25   -AR32       A01X+143657Y+098272X0177Y    R180 S1      
327GND              U25   -AR34       A01X+142916Y+098272X0177Y    R180 S1      
327GND              U25   -AR36       A01X+142176Y+098272X0177Y    R180 S1      
327GND              U25   -AR41       A01X+140696Y+098272X0177Y    R180 S1      
327GND              U25   -AR43       A01X+139956Y+098272X0177Y    R180 S1      
327GND              U25   -AR45       A01X+139216Y+098272X0177Y    R180 S1      
327GND              U25   -AR47       A01X+138476Y+098272X0177Y    R180 S1      
327GND              U25   -AR49       A01X+137735Y+098272X0177Y    R180 S1      
327GND              U25   -AR51       A01X+136995Y+098272X0177Y    R180 S1      
327GND              U25   -AR53       A01X+136255Y+098272X0177Y    R180 S1      
327GND              U25   -AR56       A01X+135145Y+098272X0177Y    R180 S1      
327GND              U25   -AR57       A01X+134775Y+098272X0177Y    R180 S1      
327GND              U25   -AR60       A01X+133665Y+098272X0177Y    R180 S1      
327GND              U25   -AR61       A01X+133294Y+098272X0177Y    R180 S1      
327GND              U25   -AR63       A01X+132554Y+098272X0177Y    R180 S1      
327GND              U25   -AR64       A01X+132184Y+098272X0177Y    R180 S1      
327GND              U25   -AR67       A01X+131074Y+098272X0177Y    R180 S1      
327GND              U25   -AR68       A01X+130704Y+098272X0177Y    R180 S1      
327GND              U25   -AR70       A01X+129964Y+098272X0177Y    R180 S1      
327GND              U25   -AR71       A01X+129594Y+098272X0177Y    R180 S1      
327GND              U25   -AR75       A01X+128113Y+098272X0177Y    R180 S1      
327GND              U25   -AT3        A01X+154574Y+098591X0177Y    R180 S1      
327GND              U25   -AT4        A01X+154204Y+098591X0177Y    R180 S1      
327GND              U25   -AT5        A01X+153834Y+098591X0177Y    R180 S1      
327GND              U25   -AT6        A01X+153464Y+098591X0177Y    R180 S1      
327GND              U25   -AT8        A01X+152724Y+098591X0177Y    R180 S1      
327GND              U25   -AT9        A01X+152354Y+098591X0177Y    R180 S1      
327GND              U25   -AT10       A01X+151984Y+098591X0177Y    R180 S1      
327GND              U25   -AT12       A01X+151243Y+098591X0177Y    R180 S1      
327GND              U25   -AT13       A01X+150873Y+098591X0177Y    R180 S1      
327GND              U25   -AT15       A01X+150133Y+098591X0177Y    R180 S1      
327GND              U25   -AT16       A01X+149763Y+098591X0177Y    R180 S1      
327GND              U25   -AT17       A01X+149393Y+098591X0177Y    R180 S1      
327GND              U25   -AT19       A01X+148653Y+098591X0177Y    R180 S1      
327GND              U25   -AT20       A01X+148283Y+098591X0177Y    R180 S1      
327GND              U25   -AT23       A01X+147172Y+098591X0177Y    R180 S1      
327GND              U25   -AT25       A01X+146432Y+098591X0177Y    R180 S1      
327GND              U25   -AT27       A01X+145692Y+098591X0177Y    R180 S1      
327GND              U25   -AT29       A01X+144952Y+098591X0177Y    R180 S1      
327GND              U25   -AT31       A01X+144212Y+098591X0177Y    R180 S1      
327GND              U25   -AT33       A01X+143472Y+098591X0177Y    R180 S1      
327GND              U25   -AT35       A01X+142732Y+098591X0177Y    R180 S1      
327GND              U25   -AT37       A01X+141991Y+098591X0177Y    R180 S1      
327GND              U25   -AT40       A01X+140881Y+098591X0177Y    R180 S1      
327GND              U25   -AT42       A01X+140141Y+098591X0177Y    R180 S1      
327GND              U25   -AT44       A01X+139401Y+098591X0177Y    R180 S1      
327GND              U25   -AT46       A01X+138661Y+098591X0177Y    R180 S1      
327GND              U25   -AT48       A01X+137920Y+098591X0177Y    R180 S1      
327GND              U25   -AT50       A01X+137180Y+098591X0177Y    R180 S1      
327GND              U25   -AT52       A01X+136440Y+098591X0177Y    R180 S1      
327GND              U25   -AT54       A01X+135700Y+098591X0177Y    R180 S1      
327GND              U25   -AT56       A01X+134960Y+098591X0177Y    R180 S1      
327GND              U25   -AT57       A01X+134590Y+098591X0177Y    R180 S1      
327GND              U25   -AT59       A01X+133850Y+098591X0177Y    R180 S1      
327GND              U25   -AT60       A01X+133480Y+098591X0177Y    R180 S1      
327GND              U25   -AT61       A01X+133109Y+098591X0177Y    R180 S1      
327GND              U25   -AT63       A01X+132369Y+098591X0177Y    R180 S1      
327GND              U25   -AT64       A01X+131999Y+098591X0177Y    R180 S1      
327GND              U25   -AT66       A01X+131259Y+098591X0177Y    R180 S1      
327GND              U25   -AT67       A01X+130889Y+098591X0177Y    R180 S1      
327GND              U25   -AT68       A01X+130519Y+098591X0177Y    R180 S1      
327GND              U25   -AT70       A01X+129779Y+098591X0177Y    R180 S1      
327GND              U25   -AT71       A01X+129409Y+098591X0177Y    R180 S1      
327GND              U25   -AT72       A01X+129039Y+098591X0177Y    R180 S1      
327GND              U25   -AT73       A01X+128668Y+098591X0177Y    R180 S1      
327GND              U25   -AU1        A01X+155129Y+098910X0177Y    R180 S1      
327GND              U25   -AU3        A01X+154389Y+098910X0177Y    R180 S1      
327GND              U25   -AU4        A01X+154019Y+098910X0177Y    R180 S1      
327GND              U25   -AU6        A01X+153279Y+098910X0177Y    R180 S1      
327GND              U25   -AU8        A01X+152539Y+098910X0177Y    R180 S1      
327GND              U25   -AU11       A01X+151428Y+098910X0177Y    R180 S1      
327GND              U25   -AU13       A01X+150688Y+098910X0177Y    R180 S1      
327GND              U25   -AU15       A01X+149948Y+098910X0177Y    R180 S1      
327GND              U25   -AU18       A01X+148838Y+098910X0177Y    R180 S1      
327GND              U25   -AU20       A01X+148098Y+098910X0177Y    R180 S1      
327GND              U25   -AU22       A01X+147358Y+098910X0177Y    R180 S1      
327GND              U25   -AU24       A01X+146617Y+098910X0177Y    R180 S1      
327GND              U25   -AU26       A01X+145877Y+098910X0177Y    R180 S1      
327GND              U25   -AU28       A01X+145137Y+098910X0177Y    R180 S1      
327GND              U25   -AU30       A01X+144397Y+098910X0177Y    R180 S1      
327GND              U25   -AU32       A01X+143657Y+098910X0177Y    R180 S1      
327GND              U25   -AU34       A01X+142916Y+098910X0177Y    R180 S1      
327GND              U25   -AU36       A01X+142176Y+098910X0177Y    R180 S1      
327GND              U25   -AU41       A01X+140696Y+098910X0177Y    R180 S1      
327GND              U25   -AU43       A01X+139956Y+098910X0177Y    R180 S1      
327GND              U25   -AU45       A01X+139216Y+098910X0177Y    R180 S1      
327GND              U25   -AU47       A01X+138476Y+098910X0177Y    R180 S1      
327GND              U25   -AU49       A01X+137735Y+098910X0177Y    R180 S1      
327GND              U25   -AU51       A01X+136995Y+098910X0177Y    R180 S1      
327GND              U25   -AU53       A01X+136255Y+098910X0177Y    R180 S1      
327GND              U25   -AU56       A01X+135145Y+098910X0177Y    R180 S1      
327GND              U25   -AU58       A01X+134405Y+098910X0177Y    R180 S1      
327GND              U25   -AU61       A01X+133294Y+098910X0177Y    R180 S1      
327GND              U25   -AU63       A01X+132554Y+098910X0177Y    R180 S1      
327GND              U25   -AU65       A01X+131814Y+098910X0177Y    R180 S1      
327GND              U25   -AU68       A01X+130704Y+098910X0177Y    R180 S1      
327GND              U25   -AU70       A01X+129964Y+098910X0177Y    R180 S1      
327GND              U25   -AU72       A01X+129224Y+098910X0177Y    R180 S1      
327GND              U25   -AU73       A01X+128854Y+098910X0177Y    R180 S1      
327GND              U25   -AU75       A01X+128113Y+098910X0177Y    R180 S1      
327GND              U25   -AV3        A01X+154574Y+099228X0177Y    R180 S1      
327GND              U25   -AV8        A01X+152724Y+099228X0177Y    R180 S1      
327GND              U25   -AV10       A01X+151984Y+099228X0177Y    R180 S1      
327GND              U25   -AV15       A01X+150133Y+099228X0177Y    R180 S1      
327GND              U25   -AV17       A01X+149393Y+099228X0177Y    R180 S1      
327GND              U25   -AV23       A01X+147172Y+099228X0177Y    R180 S1      
327GND              U25   -AV25       A01X+146432Y+099228X0177Y    R180 S1      
327GND              U25   -AV27       A01X+145692Y+099228X0177Y    R180 S1      
327GND              U25   -AV29       A01X+144952Y+099228X0177Y    R180 S1      
327GND              U25   -AV31       A01X+144212Y+099228X0177Y    R180 S1      
327GND              U25   -AV33       A01X+143472Y+099228X0177Y    R180 S1      
327GND              U25   -AV35       A01X+142732Y+099228X0177Y    R180 S1      
327GND              U25   -AV37       A01X+141991Y+099228X0177Y    R180 S1      
327GND              U25   -AV40       A01X+140881Y+099228X0177Y    R180 S1      
327GND              U25   -AV42       A01X+140141Y+099228X0177Y    R180 S1      
327GND              U25   -AV44       A01X+139401Y+099228X0177Y    R180 S1      
327GND              U25   -AV46       A01X+138661Y+099228X0177Y    R180 S1      
327GND              U25   -AV48       A01X+137920Y+099228X0177Y    R180 S1      
327GND              U25   -AV50       A01X+137180Y+099228X0177Y    R180 S1      
327GND              U25   -AV52       A01X+136440Y+099228X0177Y    R180 S1      
327GND              U25   -AV54       A01X+135700Y+099228X0177Y    R180 S1      
327GND              U25   -AV59       A01X+133850Y+099228X0177Y    R180 S1      
327GND              U25   -AV61       A01X+133109Y+099228X0177Y    R180 S1      
327GND              U25   -AV66       A01X+131259Y+099228X0177Y    R180 S1      
327GND              U25   -AV68       A01X+130519Y+099228X0177Y    R180 S1      
327GND              U25   -AV73       A01X+128668Y+099228X0177Y    R180 S1      
327GND              U25   -AW1        A01X+155129Y+099547X0177Y    R180 S1      
327GND              U25   -AW4        A01X+154019Y+099547X0177Y    R180 S1      
327GND              U25   -AW6        A01X+153279Y+099547X0177Y    R180 S1      
327GND              U25   -AW8        A01X+152539Y+099547X0177Y    R180 S1      
327GND              U25   -AW11       A01X+151428Y+099547X0177Y    R180 S1      
327GND              U25   -AW13       A01X+150688Y+099547X0177Y    R180 S1      
327GND              U25   -AW15       A01X+149948Y+099547X0177Y    R180 S1      
327GND              U25   -AW18       A01X+148838Y+099547X0177Y    R180 S1      
327GND              U25   -AW20       A01X+148098Y+099547X0177Y    R180 S1      
327GND              U25   -AW22       A01X+147358Y+099547X0177Y    R180 S1      
327GND              U25   -AW24       A01X+146617Y+099547X0177Y    R180 S1      
327GND              U25   -AW26       A01X+145877Y+099547X0177Y    R180 S1      
327GND              U25   -AW28       A01X+145137Y+099547X0177Y    R180 S1      
327GND              U25   -AW49       A01X+137735Y+099547X0177Y    R180 S1      
327GND              U25   -AW51       A01X+136995Y+099547X0177Y    R180 S1      
327GND              U25   -AW53       A01X+136255Y+099547X0177Y    R180 S1      
327GND              U25   -AW56       A01X+135145Y+099547X0177Y    R180 S1      
327GND              U25   -AW58       A01X+134405Y+099547X0177Y    R180 S1      
327GND              U25   -AW61       A01X+133294Y+099547X0177Y    R180 S1      
327GND              U25   -AW63       A01X+132554Y+099547X0177Y    R180 S1      
327GND              U25   -AW65       A01X+131814Y+099547X0177Y    R180 S1      
327GND              U25   -AW68       A01X+130704Y+099547X0177Y    R180 S1      
327GND              U25   -AW70       A01X+129964Y+099547X0177Y    R180 S1      
327GND              U25   -AW72       A01X+129224Y+099547X0177Y    R180 S1      
327GND              U25   -AW75       A01X+128113Y+099547X0177Y    R180 S1      
327GND              U25   -AY3        A01X+154574Y+099866X0177Y    R180 S1      
327GND              U25   -AY5        A01X+153834Y+099866X0177Y    R180 S1      
327GND              U25   -AY8        A01X+152724Y+099866X0177Y    R180 S1      
327GND              U25   -AY10       A01X+151984Y+099866X0177Y    R180 S1      
327GND              U25   -AY12       A01X+151243Y+099866X0177Y    R180 S1      
327GND              U25   -AY15       A01X+150133Y+099866X0177Y    R180 S1      
327GND              U25   -AY17       A01X+149393Y+099866X0177Y    R180 S1      
327GND              U25   -AY19       A01X+148653Y+099866X0177Y    R180 S1      
327GND              U25   -AY23       A01X+147172Y+099866X0177Y    R180 S1      
327GND              U25   -AY25       A01X+146432Y+099866X0177Y    R180 S1      
327GND              U25   -AY27       A01X+145692Y+099866X0177Y    R180 S1      
327GND              U25   -AY48       A01X+137920Y+099866X0177Y    R180 S1      
327GND              U25   -AY50       A01X+137180Y+099866X0177Y    R180 S1      
327GND              U25   -AY52       A01X+136440Y+099866X0177Y    R180 S1      
327GND              U25   -AY54       A01X+135700Y+099866X0177Y    R180 S1      
327GND              U25   -AY57       A01X+134590Y+099866X0177Y    R180 S1      
327GND              U25   -AY59       A01X+133850Y+099866X0177Y    R180 S1      
327GND              U25   -AY61       A01X+133109Y+099866X0177Y    R180 S1      
327GND              U25   -AY64       A01X+131999Y+099866X0177Y    R180 S1      
327GND              U25   -AY66       A01X+131259Y+099866X0177Y    R180 S1      
327GND              U25   -AY68       A01X+130519Y+099866X0177Y    R180 S1      
327GND              U25   -AY71       A01X+129409Y+099866X0177Y    R180 S1      
327GND              U25   -AY73       A01X+128668Y+099866X0177Y    R180 S1      
327GND              U25   -BA1        A01X+155129Y+100185X0177Y    R180 S1      
327GND              U25   -BA6        A01X+153279Y+100185X0177Y    R180 S1      
327GND              U25   -BA8        A01X+152539Y+100185X0177Y    R180 S1      
327GND              U25   -BA13       A01X+150688Y+100185X0177Y    R180 S1      
327GND              U25   -BA15       A01X+149948Y+100185X0177Y    R180 S1      
327GND              U25   -BA20       A01X+148098Y+100185X0177Y    R180 S1      
327GND              U25   -BA22       A01X+147358Y+100185X0177Y    R180 S1      
327GND              U25   -BA24       A01X+146617Y+100185X0177Y    R180 S1      
327GND              U25   -BA26       A01X+145877Y+100185X0177Y    R180 S1      
327GND              U25   -BA28       A01X+145137Y+100185X0177Y    R180 S1      
327GND              U25   -BA49       A01X+137735Y+100185X0177Y    R180 S1      
327GND              U25   -BA51       A01X+136995Y+100185X0177Y    R180 S1      
327GND              U25   -BA53       A01X+136255Y+100185X0177Y    R180 S1      
327GND              U25   -BA56       A01X+135145Y+100185X0177Y    R180 S1      
327GND              U25   -BA61       A01X+133294Y+100185X0177Y    R180 S1      
327GND              U25   -BA63       A01X+132554Y+100185X0177Y    R180 S1      
327GND              U25   -BA68       A01X+130704Y+100185X0177Y    R180 S1      
327GND              U25   -BA70       A01X+129964Y+100185X0177Y    R180 S1      
327GND              U25   -BA75       A01X+128113Y+100185X0177Y    R180 S1      
327GND              U25   -BB3        A01X+154574Y+100504X0177Y    R180 S1      
327GND              U25   -BB5        A01X+153834Y+100504X0177Y    R180 S1      
327GND              U25   -BB8        A01X+152724Y+100504X0177Y    R180 S1      
327GND              U25   -BB10       A01X+151984Y+100504X0177Y    R180 S1      
327GND              U25   -BB12       A01X+151243Y+100504X0177Y    R180 S1      
327GND              U25   -BB15       A01X+150133Y+100504X0177Y    R180 S1      
327GND              U25   -BB17       A01X+149393Y+100504X0177Y    R180 S1      
327GND              U25   -BB19       A01X+148653Y+100504X0177Y    R180 S1      
327GND              U25   -BB23       A01X+147172Y+100504X0177Y    R180 S1      
327GND              U25   -BB25       A01X+146432Y+100504X0177Y    R180 S1      
327GND              U25   -BB27       A01X+145692Y+100504X0177Y    R180 S1      
327GND              U25   -BB48       A01X+137920Y+100504X0177Y    R180 S1      
327GND              U25   -BB50       A01X+137180Y+100504X0177Y    R180 S1      
327GND              U25   -BB52       A01X+136440Y+100504X0177Y    R180 S1      
327GND              U25   -BB54       A01X+135700Y+100504X0177Y    R180 S1      
327GND              U25   -BB57       A01X+134590Y+100504X0177Y    R180 S1      
327GND              U25   -BB59       A01X+133850Y+100504X0177Y    R180 S1      
327GND              U25   -BB61       A01X+133109Y+100504X0177Y    R180 S1      
327GND              U25   -BB64       A01X+131999Y+100504X0177Y    R180 S1      
327GND              U25   -BB66       A01X+131259Y+100504X0177Y    R180 S1      
327GND              U25   -BB68       A01X+130519Y+100504X0177Y    R180 S1      
327GND              U25   -BB71       A01X+129409Y+100504X0177Y    R180 S1      
327GND              U25   -BB73       A01X+128668Y+100504X0177Y    R180 S1      
327GND              U25   -BC1        A01X+155129Y+100823X0177Y    R180 S1      
327GND              U25   -BC4        A01X+154019Y+100823X0177Y    R180 S1      
327GND              U25   -BC6        A01X+153279Y+100823X0177Y    R180 S1      
327GND              U25   -BC8        A01X+152539Y+100823X0177Y    R180 S1      
327GND              U25   -BC11       A01X+151428Y+100823X0177Y    R180 S1      
327GND              U25   -BC13       A01X+150688Y+100823X0177Y    R180 S1      
327GND              U25   -BC15       A01X+149948Y+100823X0177Y    R180 S1      
327GND              U25   -BC18       A01X+148838Y+100823X0177Y    R180 S1      
327GND              U25   -BC20       A01X+148098Y+100823X0177Y    R180 S1      
327GND              U25   -BC22       A01X+147358Y+100823X0177Y    R180 S1      
327GND              U25   -BC24       A01X+146617Y+100823X0177Y    R180 S1      
327GND              U25   -BC26       A01X+145877Y+100823X0177Y    R180 S1      
327GND              U25   -BC28       A01X+145137Y+100823X0177Y    R180 S1      
327GND              U25   -BC49       A01X+137735Y+100823X0177Y    R180 S1      
327GND              U25   -BC50       A01X+137365Y+100823X0177Y    R180 S1      
327GND              U25   -BC51       A01X+136995Y+100823X0177Y    R180 S1      
327GND              U25   -BC53       A01X+136255Y+100823X0177Y    R180 S1      
327GND              U25   -BC56       A01X+135145Y+100823X0177Y    R180 S1      
327GND              U25   -BC58       A01X+134405Y+100823X0177Y    R180 S1      
327GND              U25   -BC61       A01X+133294Y+100823X0177Y    R180 S1      
327GND              U25   -BC63       A01X+132554Y+100823X0177Y    R180 S1      
327GND              U25   -BC65       A01X+131814Y+100823X0177Y    R180 S1      
327GND              U25   -BC68       A01X+130704Y+100823X0177Y    R180 S1      
327GND              U25   -BC70       A01X+129964Y+100823X0177Y    R180 S1      
327GND              U25   -BC72       A01X+129224Y+100823X0177Y    R180 S1      
327GND              U25   -BC75       A01X+128113Y+100823X0177Y    R180 S1      
327GND              U25   -BD3        A01X+154574Y+101142X0177Y    R180 S1      
327GND              U25   -BD8        A01X+152724Y+101142X0177Y    R180 S1      
327GND              U25   -BD10       A01X+151984Y+101142X0177Y    R180 S1      
327GND              U25   -BD15       A01X+150133Y+101142X0177Y    R180 S1      
327GND              U25   -BD17       A01X+149393Y+101142X0177Y    R180 S1      
327GND              U25   -BD23       A01X+147172Y+101142X0177Y    R180 S1      
327GND              U25   -BD25       A01X+146432Y+101142X0177Y    R180 S1      
327GND              U25   -BD27       A01X+145692Y+101142X0177Y    R180 S1      
327GND              U25   -BD49       A01X+137550Y+101142X0177Y    R180 S1      
327GND              U25   -BD51       A01X+136810Y+101142X0177Y    R180 S1      
327GND              U25   -BD53       A01X+136070Y+101142X0177Y    R180 S1      
327GND              U25   -BD57       A01X+134590Y+101142X0177Y    R180 S1      
327GND              U25   -BD59       A01X+133850Y+101142X0177Y    R180 S1      
327GND              U25   -BD61       A01X+133109Y+101142X0177Y    R180 S1      
327GND              U25   -BD64       A01X+131999Y+101142X0177Y    R180 S1      
327GND              U25   -BD66       A01X+131259Y+101142X0177Y    R180 S1      
327GND              U25   -BD68       A01X+130519Y+101142X0177Y    R180 S1      
327GND              U25   -BD71       A01X+129409Y+101142X0177Y    R180 S1      
327GND              U25   -BD73       A01X+128668Y+101142X0177Y    R180 S1      
327GND              U25   -BF3        A01X+154692Y+102701X0177Y    R180 S1      
327GND              U25   -BF5        A01X+153952Y+102701X0177Y    R180 S1      
327GND              U25   -BF8        A01X+152842Y+102701X0177Y    R180 S1      
327GND              U25   -BF10       A01X+152102Y+102701X0177Y    R180 S1      
327GND              U25   -BF12       A01X+151361Y+102701X0177Y    R180 S1      
327GND              U25   -BF15       A01X+150251Y+102701X0177Y    R180 S1      
327GND              U25   -BF17       A01X+149511Y+102701X0177Y    R180 S1      
327GND              U25   -BF19       A01X+148771Y+102701X0177Y    R180 S1      
327GND              U25   -BF22       A01X+147661Y+102701X0177Y    R180 S1      
327GND              U25   -BF24       A01X+146920Y+102701X0177Y    R180 S1      
327GND              U25   -BF26       A01X+146180Y+102701X0177Y    R180 S1      
327GND              U25   -BF28       A01X+145440Y+102701X0177Y    R180 S1      
327GND              U25   -BF49       A01X+137668Y+102701X0177Y    R180 S1      
327GND              U25   -BF50       A01X+137298Y+102701X0177Y    R180 S1      
327GND              U25   -BF52       A01X+136558Y+102701X0177Y    R180 S1      
327GND              U25   -BF54       A01X+135818Y+102701X0177Y    R180 S1      
327GND              U25   -BF59       A01X+133968Y+102701X0177Y    R180 S1      
327GND              U25   -BF61       A01X+133228Y+102701X0177Y    R180 S1      
327GND              U25   -BF66       A01X+131377Y+102701X0177Y    R180 S1      
327GND              U25   -BF68       A01X+130637Y+102701X0177Y    R180 S1      
327GND              U25   -BF73       A01X+128787Y+102701X0177Y    R180 S1      
327GND              U25   -BG1        A01X+155247Y+103020X0177Y    R180 S1      
327GND              U25   -BG4        A01X+154137Y+103020X0177Y    R180 S1      
327GND              U25   -BG6        A01X+153397Y+103020X0177Y    R180 S1      
327GND              U25   -BG8        A01X+152657Y+103020X0177Y    R180 S1      
327GND              U25   -BG11       A01X+151546Y+103020X0177Y    R180 S1      
327GND              U25   -BG13       A01X+150806Y+103020X0177Y    R180 S1      
327GND              U25   -BG15       A01X+150066Y+103020X0177Y    R180 S1      
327GND              U25   -BG18       A01X+148956Y+103020X0177Y    R180 S1      
327GND              U25   -BG20       A01X+148216Y+103020X0177Y    R180 S1      
327GND              U25   -BG23       A01X+147106Y+103020X0177Y    R180 S1      
327GND              U25   -BG25       A01X+146365Y+103020X0177Y    R180 S1      
327GND              U25   -BG27       A01X+145625Y+103020X0177Y    R180 S1      
327GND              U25   -BG49       A01X+137854Y+103020X0177Y    R180 S1      
327GND              U25   -BG51       A01X+137113Y+103020X0177Y    R180 S1      
327GND              U25   -BG53       A01X+136373Y+103020X0177Y    R180 S1      
327GND              U25   -BG56       A01X+135263Y+103020X0177Y    R180 S1      
327GND              U25   -BG58       A01X+134523Y+103020X0177Y    R180 S1      
327GND              U25   -BG61       A01X+133413Y+103020X0177Y    R180 S1      
327GND              U25   -BG63       A01X+132672Y+103020X0177Y    R180 S1      
327GND              U25   -BG65       A01X+131932Y+103020X0177Y    R180 S1      
327GND              U25   -BG68       A01X+130822Y+103020X0177Y    R180 S1      
327GND              U25   -BG70       A01X+130082Y+103020X0177Y    R180 S1      
327GND              U25   -BG72       A01X+129342Y+103020X0177Y    R180 S1      
327GND              U25   -BG75       A01X+128232Y+103020X0177Y    R180 S1      
327GND              U25   -BH3        A01X+154692Y+103339X0177Y    R180 S1      
327GND              U25   -BH5        A01X+153952Y+103339X0177Y    R180 S1      
327GND              U25   -BH8        A01X+152842Y+103339X0177Y    R180 S1      
327GND              U25   -BH10       A01X+152102Y+103339X0177Y    R180 S1      
327GND              U25   -BH12       A01X+151361Y+103339X0177Y    R180 S1      
327GND              U25   -BH15       A01X+150251Y+103339X0177Y    R180 S1      
327GND              U25   -BH17       A01X+149511Y+103339X0177Y    R180 S1      
327GND              U25   -BH19       A01X+148771Y+103339X0177Y    R180 S1      
327GND              U25   -BH22       A01X+147661Y+103339X0177Y    R180 S1      
327GND              U25   -BH24       A01X+146920Y+103339X0177Y    R180 S1      
327GND              U25   -BH26       A01X+146180Y+103339X0177Y    R180 S1      
327GND              U25   -BH28       A01X+145440Y+103339X0177Y    R180 S1      
327GND              U25   -BH49       A01X+137668Y+103339X0177Y    R180 S1      
327GND              U25   -BH50       A01X+137298Y+103339X0177Y    R180 S1      
327GND              U25   -BH52       A01X+136558Y+103339X0177Y    R180 S1      
327GND              U25   -BH54       A01X+135818Y+103339X0177Y    R180 S1      
327GND              U25   -BH57       A01X+134708Y+103339X0177Y    R180 S1      
327GND              U25   -BH59       A01X+133968Y+103339X0177Y    R180 S1      
327GND              U25   -BH61       A01X+133228Y+103339X0177Y    R180 S1      
327GND              U25   -BH64       A01X+132117Y+103339X0177Y    R180 S1      
327GND              U25   -BH66       A01X+131377Y+103339X0177Y    R180 S1      
327GND              U25   -BH68       A01X+130637Y+103339X0177Y    R180 S1      
327GND              U25   -BH71       A01X+129527Y+103339X0177Y    R180 S1      
327GND              U25   -BH73       A01X+128787Y+103339X0177Y    R180 S1      
327GND              U25   -BJ1        A01X+155247Y+103658X0177Y    R180 S1      
327GND              U25   -BJ6        A01X+153397Y+103658X0177Y    R180 S1      
327GND              U25   -BJ8        A01X+152657Y+103658X0177Y    R180 S1      
327GND              U25   -BJ13       A01X+150806Y+103658X0177Y    R180 S1      
327GND              U25   -BJ15       A01X+150066Y+103658X0177Y    R180 S1      
327GND              U25   -BJ20       A01X+148216Y+103658X0177Y    R180 S1      
327GND              U25   -BJ22       A01X+147476Y+103658X0177Y    R180 S1      
327GND              U25   -BJ24       A01X+146735Y+103658X0177Y    R180 S1      
327GND              U25   -BJ26       A01X+145995Y+103658X0177Y    R180 S1      
327GND              U25   -BJ28       A01X+145255Y+103658X0177Y    R180 S1      
327GND              U25   -BJ49       A01X+137854Y+103658X0177Y    R180 S1      
327GND              U25   -BJ51       A01X+137113Y+103658X0177Y    R180 S1      
327GND              U25   -BJ53       A01X+136373Y+103658X0177Y    R180 S1      
327GND              U25   -BJ56       A01X+135263Y+103658X0177Y    R180 S1      
327GND              U25   -BJ61       A01X+133413Y+103658X0177Y    R180 S1      
327GND              U25   -BJ63       A01X+132672Y+103658X0177Y    R180 S1      
327GND              U25   -BJ68       A01X+130822Y+103658X0177Y    R180 S1      
327GND              U25   -BJ70       A01X+130082Y+103658X0177Y    R180 S1      
327GND              U25   -BJ75       A01X+128232Y+103658X0177Y    R180 S1      
327GND              U25   -BK3        A01X+154692Y+103976X0177Y    R180 S1      
327GND              U25   -BK5        A01X+153952Y+103976X0177Y    R180 S1      
327GND              U25   -BK8        A01X+152842Y+103976X0177Y    R180 S1      
327GND              U25   -BK10       A01X+152102Y+103976X0177Y    R180 S1      
327GND              U25   -BK12       A01X+151361Y+103976X0177Y    R180 S1      
327GND              U25   -BK15       A01X+150251Y+103976X0177Y    R180 S1      
327GND              U25   -BK17       A01X+149511Y+103976X0177Y    R180 S1      
327GND              U25   -BK19       A01X+148771Y+103976X0177Y    R180 S1      
327GND              U25   -BK23       A01X+147290Y+103976X0177Y    R180 S1      
327GND              U25   -BK25       A01X+146550Y+103976X0177Y    R180 S1      
327GND              U25   -BK27       A01X+145810Y+103976X0177Y    R180 S1      
327GND              U25   -BK48       A01X+138039Y+103976X0177Y    R180 S1      
327GND              U25   -BK50       A01X+137298Y+103976X0177Y    R180 S1      
327GND              U25   -BK52       A01X+136558Y+103976X0177Y    R180 S1      
327GND              U25   -BK54       A01X+135818Y+103976X0177Y    R180 S1      
327GND              U25   -BK57       A01X+134708Y+103976X0177Y    R180 S1      
327GND              U25   -BK59       A01X+133968Y+103976X0177Y    R180 S1      
327GND              U25   -BK61       A01X+133228Y+103976X0177Y    R180 S1      
327GND              U25   -BK64       A01X+132117Y+103976X0177Y    R180 S1      
327GND              U25   -BK66       A01X+131377Y+103976X0177Y    R180 S1      
327GND              U25   -BK68       A01X+130637Y+103976X0177Y    R180 S1      
327GND              U25   -BK71       A01X+129527Y+103976X0177Y    R180 S1      
327GND              U25   -BK73       A01X+128787Y+103976X0177Y    R180 S1      
327GND              U25   -BL1        A01X+155247Y+104295X0177Y    R180 S1      
327GND              U25   -BL4        A01X+154137Y+104295X0177Y    R180 S1      
327GND              U25   -BL6        A01X+153397Y+104295X0177Y    R180 S1      
327GND              U25   -BL8        A01X+152657Y+104295X0177Y    R180 S1      
327GND              U25   -BL11       A01X+151546Y+104295X0177Y    R180 S1      
327GND              U25   -BL13       A01X+150806Y+104295X0177Y    R180 S1      
327GND              U25   -BL15       A01X+150066Y+104295X0177Y    R180 S1      
327GND              U25   -BL18       A01X+148956Y+104295X0177Y    R180 S1      
327GND              U25   -BL20       A01X+148216Y+104295X0177Y    R180 S1      
327GND              U25   -BL22       A01X+147476Y+104295X0177Y    R180 S1      
327GND              U25   -BL24       A01X+146735Y+104295X0177Y    R180 S1      
327GND              U25   -BL26       A01X+145995Y+104295X0177Y    R180 S1      
327GND              U25   -BL28       A01X+145255Y+104295X0177Y    R180 S1      
327GND              U25   -BL49       A01X+137854Y+104295X0177Y    R180 S1      
327GND              U25   -BL51       A01X+137113Y+104295X0177Y    R180 S1      
327GND              U25   -BL53       A01X+136373Y+104295X0177Y    R180 S1      
327GND              U25   -BL56       A01X+135263Y+104295X0177Y    R180 S1      
327GND              U25   -BL58       A01X+134523Y+104295X0177Y    R180 S1      
327GND              U25   -BL61       A01X+133413Y+104295X0177Y    R180 S1      
327GND              U25   -BL63       A01X+132672Y+104295X0177Y    R180 S1      
327GND              U25   -BL65       A01X+131932Y+104295X0177Y    R180 S1      
327GND              U25   -BL68       A01X+130822Y+104295X0177Y    R180 S1      
327GND              U25   -BL70       A01X+130082Y+104295X0177Y    R180 S1      
327GND              U25   -BL72       A01X+129342Y+104295X0177Y    R180 S1      
327GND              U25   -BL75       A01X+128232Y+104295X0177Y    R180 S1      
327GND              U25   -BM3        A01X+154692Y+104614X0177Y    R180 S1      
327GND              U25   -BM8        A01X+152842Y+104614X0177Y    R180 S1      
327GND              U25   -BM10       A01X+152102Y+104614X0177Y    R180 S1      
327GND              U25   -BM15       A01X+150251Y+104614X0177Y    R180 S1      
327GND              U25   -BM17       A01X+149511Y+104614X0177Y    R180 S1      
327GND              U25   -BM23       A01X+147290Y+104614X0177Y    R180 S1      
327GND              U25   -BM25       A01X+146550Y+104614X0177Y    R180 S1      
327GND              U25   -BM27       A01X+145810Y+104614X0177Y    R180 S1      
327GND              U25   -BM29       A01X+145070Y+104614X0177Y    R180 S1      
327GND              U25   -BM31       A01X+144330Y+104614X0177Y    R180 S1      
327GND              U25   -BM33       A01X+143590Y+104614X0177Y    R180 S1      
327GND              U25   -BM35       A01X+142850Y+104614X0177Y    R180 S1      
327GND              U25   -BM37       A01X+142109Y+104614X0177Y    R180 S1      
327GND              U25   -BM40       A01X+140999Y+104614X0177Y    R180 S1      
327GND              U25   -BM42       A01X+140259Y+104614X0177Y    R180 S1      
327GND              U25   -BM44       A01X+139519Y+104614X0177Y    R180 S1      
327GND              U25   -BM46       A01X+138779Y+104614X0177Y    R180 S1      
327GND              U25   -BM48       A01X+138039Y+104614X0177Y    R180 S1      
327GND              U25   -BM50       A01X+137298Y+104614X0177Y    R180 S1      
327GND              U25   -BM52       A01X+136558Y+104614X0177Y    R180 S1      
327GND              U25   -BM54       A01X+135818Y+104614X0177Y    R180 S1      
327GND              U25   -BM59       A01X+133968Y+104614X0177Y    R180 S1      
327GND              U25   -BM61       A01X+133228Y+104614X0177Y    R180 S1      
327GND              U25   -BM66       A01X+131377Y+104614X0177Y    R180 S1      
327GND              U25   -BM68       A01X+130637Y+104614X0177Y    R180 S1      
327GND              U25   -BM73       A01X+128787Y+104614X0177Y    R180 S1      
327GND              U25   -BN1        A01X+155247Y+104933X0177Y    R180 S1      
327GND              U25   -BN4        A01X+154137Y+104933X0177Y    R180 S1      
327GND              U25   -BN6        A01X+153397Y+104933X0177Y    R180 S1      
327GND              U25   -BN8        A01X+152657Y+104933X0177Y    R180 S1      
327GND              U25   -BN11       A01X+151546Y+104933X0177Y    R180 S1      
327GND              U25   -BN13       A01X+150806Y+104933X0177Y    R180 S1      
327GND              U25   -BN15       A01X+150066Y+104933X0177Y    R180 S1      
327GND              U25   -BN18       A01X+148956Y+104933X0177Y    R180 S1      
327GND              U25   -BN20       A01X+148216Y+104933X0177Y    R180 S1      
327GND              U25   -BN22       A01X+147476Y+104933X0177Y    R180 S1      
327GND              U25   -BN24       A01X+146735Y+104933X0177Y    R180 S1      
327GND              U25   -BN26       A01X+145995Y+104933X0177Y    R180 S1      
327GND              U25   -BN28       A01X+145255Y+104933X0177Y    R180 S1      
327GND              U25   -BN30       A01X+144515Y+104933X0177Y    R180 S1      
327GND              U25   -BN32       A01X+143775Y+104933X0177Y    R180 S1      
327GND              U25   -BN34       A01X+143035Y+104933X0177Y    R180 S1      
327GND              U25   -BN36       A01X+142294Y+104933X0177Y    R180 S1      
327GND              U25   -BN41       A01X+140814Y+104933X0177Y    R180 S1      
327GND              U25   -BN43       A01X+140074Y+104933X0177Y    R180 S1      
327GND              U25   -BN45       A01X+139334Y+104933X0177Y    R180 S1      
327GND              U25   -BN47       A01X+138594Y+104933X0177Y    R180 S1      
327GND              U25   -BN49       A01X+137854Y+104933X0177Y    R180 S1      
327GND              U25   -BN51       A01X+137113Y+104933X0177Y    R180 S1      
327GND              U25   -BN53       A01X+136373Y+104933X0177Y    R180 S1      
327GND              U25   -BN56       A01X+135263Y+104933X0177Y    R180 S1      
327GND              U25   -BN58       A01X+134523Y+104933X0177Y    R180 S1      
327GND              U25   -BN61       A01X+133413Y+104933X0177Y    R180 S1      
327GND              U25   -BN63       A01X+132672Y+104933X0177Y    R180 S1      
327GND              U25   -BN65       A01X+131932Y+104933X0177Y    R180 S1      
327GND              U25   -BN68       A01X+130822Y+104933X0177Y    R180 S1      
327GND              U25   -BN70       A01X+130082Y+104933X0177Y    R180 S1      
327GND              U25   -BN72       A01X+129342Y+104933X0177Y    R180 S1      
327GND              U25   -BN75       A01X+128232Y+104933X0177Y    R180 S1      
327GND              U25   -BP3        A01X+154692Y+105252X0177Y    R180 S1      
327GND              U25   -BP5        A01X+153952Y+105252X0177Y    R180 S1      
327GND              U25   -BP8        A01X+152842Y+105252X0177Y    R180 S1      
327GND              U25   -BP10       A01X+152102Y+105252X0177Y    R180 S1      
327GND              U25   -BP12       A01X+151361Y+105252X0177Y    R180 S1      
327GND              U25   -BP15       A01X+150251Y+105252X0177Y    R180 S1      
327GND              U25   -BP17       A01X+149511Y+105252X0177Y    R180 S1      
327GND              U25   -BP19       A01X+148771Y+105252X0177Y    R180 S1      
327GND              U25   -BP23       A01X+147290Y+105252X0177Y    R180 S1      
327GND              U25   -BP25       A01X+146550Y+105252X0177Y    R180 S1      
327GND              U25   -BP27       A01X+145810Y+105252X0177Y    R180 S1      
327GND              U25   -BP29       A01X+145070Y+105252X0177Y    R180 S1      
327GND              U25   -BP31       A01X+144330Y+105252X0177Y    R180 S1      
327GND              U25   -BP33       A01X+143590Y+105252X0177Y    R180 S1      
327GND              U25   -BP35       A01X+142850Y+105252X0177Y    R180 S1      
327GND              U25   -BP37       A01X+142109Y+105252X0177Y    R180 S1      
327GND              U25   -BP40       A01X+140999Y+105252X0177Y    R180 S1      
327GND              U25   -BP42       A01X+140259Y+105252X0177Y    R180 S1      
327GND              U25   -BP44       A01X+139519Y+105252X0177Y    R180 S1      
327GND              U25   -BP46       A01X+138779Y+105252X0177Y    R180 S1      
327GND              U25   -BP48       A01X+138039Y+105252X0177Y    R180 S1      
327GND              U25   -BP50       A01X+137298Y+105252X0177Y    R180 S1      
327GND              U25   -BP52       A01X+136558Y+105252X0177Y    R180 S1      
327GND              U25   -BP54       A01X+135818Y+105252X0177Y    R180 S1      
327GND              U25   -BP57       A01X+134708Y+105252X0177Y    R180 S1      
327GND              U25   -BP59       A01X+133968Y+105252X0177Y    R180 S1      
327GND              U25   -BP61       A01X+133228Y+105252X0177Y    R180 S1      
327GND              U25   -BP64       A01X+132117Y+105252X0177Y    R180 S1      
327GND              U25   -BP66       A01X+131377Y+105252X0177Y    R180 S1      
327GND              U25   -BP68       A01X+130637Y+105252X0177Y    R180 S1      
327GND              U25   -BP71       A01X+129527Y+105252X0177Y    R180 S1      
327GND              U25   -BP73       A01X+128787Y+105252X0177Y    R180 S1      
327GND              U25   -BR1        A01X+155247Y+105571X0177Y    R180 S1      
327GND              U25   -BR3        A01X+154507Y+105571X0177Y    R180 S1      
327GND              U25   -BR6        A01X+153397Y+105571X0177Y    R180 S1      
327GND              U25   -BR7        A01X+153027Y+105571X0177Y    R180 S1      
327GND              U25   -BR8        A01X+152657Y+105571X0177Y    R180 S1      
327GND              U25   -BR10       A01X+151916Y+105571X0177Y    R180 S1      
327GND              U25   -BR13       A01X+150806Y+105571X0177Y    R180 S1      
327GND              U25   -BR14       A01X+150436Y+105571X0177Y    R180 S1      
327GND              U25   -BR15       A01X+150066Y+105571X0177Y    R180 S1      
327GND              U25   -BR17       A01X+149326Y+105571X0177Y    R180 S1      
327GND              U25   -BR20       A01X+148216Y+105571X0177Y    R180 S1      
327GND              U25   -BR21       A01X+147846Y+105571X0177Y    R180 S1      
327GND              U25   -BR22       A01X+147476Y+105571X0177Y    R180 S1      
327GND              U25   -BR24       A01X+146735Y+105571X0177Y    R180 S1      
327GND              U25   -BR26       A01X+145995Y+105571X0177Y    R180 S1      
327GND              U25   -BR28       A01X+145255Y+105571X0177Y    R180 S1      
327GND              U25   -BR30       A01X+144515Y+105571X0177Y    R180 S1      
327GND              U25   -BR32       A01X+143775Y+105571X0177Y    R180 S1      
327GND              U25   -BR34       A01X+143035Y+105571X0177Y    R180 S1      
327GND              U25   -BR36       A01X+142294Y+105571X0177Y    R180 S1      
327GND              U25   -BR41       A01X+140814Y+105571X0177Y    R180 S1      
327GND              U25   -BR43       A01X+140074Y+105571X0177Y    R180 S1      
327GND              U25   -BR45       A01X+139334Y+105571X0177Y    R180 S1      
327GND              U25   -BR47       A01X+138594Y+105571X0177Y    R180 S1      
327GND              U25   -BR49       A01X+137854Y+105571X0177Y    R180 S1      
327GND              U25   -BR51       A01X+137113Y+105571X0177Y    R180 S1      
327GND              U25   -BR55       A01X+135633Y+105571X0177Y    R180 S1      
327GND              U25   -BR56       A01X+135263Y+105571X0177Y    R180 S1      
327GND              U25   -BR59       A01X+134153Y+105571X0177Y    R180 S1      
327GND              U25   -BR61       A01X+133413Y+105571X0177Y    R180 S1      
327GND              U25   -BR62       A01X+133042Y+105571X0177Y    R180 S1      
327GND              U25   -BR63       A01X+132672Y+105571X0177Y    R180 S1      
327GND              U25   -BR66       A01X+131562Y+105571X0177Y    R180 S1      
327GND              U25   -BR68       A01X+130822Y+105571X0177Y    R180 S1      
327GND              U25   -BR69       A01X+130452Y+105571X0177Y    R180 S1      
327GND              U25   -BR70       A01X+130082Y+105571X0177Y    R180 S1      
327GND              U25   -BR73       A01X+128972Y+105571X0177Y    R180 S1      
327GND              U25   -BR75       A01X+128232Y+105571X0177Y    R180 S1      
327GND              U25   -BT3        A01X+154692Y+105890X0177Y    R180 S1      
327GND              U25   -BT4        A01X+154322Y+105890X0177Y    R180 S1      
327GND              U25   -BT5        A01X+153952Y+105890X0177Y    R180 S1      
327GND              U25   -BT7        A01X+153212Y+105890X0177Y    R180 S1      
327GND              U25   -BT8        A01X+152842Y+105890X0177Y    R180 S1      
327GND              U25   -BT10       A01X+152102Y+105890X0177Y    R180 S1      
327GND              U25   -BT11       A01X+151732Y+105890X0177Y    R180 S1      
327GND              U25   -BT12       A01X+151361Y+105890X0177Y    R180 S1      
327GND              U25   -BT14       A01X+150621Y+105890X0177Y    R180 S1      
327GND              U25   -BT15       A01X+150251Y+105890X0177Y    R180 S1      
327GND              U25   -BT17       A01X+149511Y+105890X0177Y    R180 S1      
327GND              U25   -BT18       A01X+149141Y+105890X0177Y    R180 S1      
327GND              U25   -BT19       A01X+148771Y+105890X0177Y    R180 S1      
327GND              U25   -BT21       A01X+148031Y+105890X0177Y    R180 S1      
327GND              U25   -BT22       A01X+147661Y+105890X0177Y    R180 S1      
327GND              U25   -BT25       A01X+146550Y+105890X0177Y    R180 S1      
327GND              U25   -BT28       A01X+145440Y+105890X0177Y    R180 S1      
327GND              U25   -BT31       A01X+144330Y+105890X0177Y    R180 S1      
327GND              U25   -BT34       A01X+143220Y+105890X0177Y    R180 S1      
327GND              U25   -BT37       A01X+142109Y+105890X0177Y    R180 S1      
327GND              U25   -BT39       A01X+141369Y+105890X0177Y    R180 S1      
327GND              U25   -BT42       A01X+140259Y+105890X0177Y    R180 S1      
327GND              U25   -BT45       A01X+139149Y+105890X0177Y    R180 S1      
327GND              U25   -BT48       A01X+138039Y+105890X0177Y    R180 S1      
327GND              U25   -BT51       A01X+136928Y+105890X0177Y    R180 S1      
327GND              U25   -BT54       A01X+135818Y+105890X0177Y    R180 S1      
327GND              U25   -BT55       A01X+135448Y+105890X0177Y    R180 S1      
327GND              U25   -BT57       A01X+134708Y+105890X0177Y    R180 S1      
327GND              U25   -BT58       A01X+134338Y+105890X0177Y    R180 S1      
327GND              U25   -BT59       A01X+133968Y+105890X0177Y    R180 S1      
327GND              U25   -BT61       A01X+133228Y+105890X0177Y    R180 S1      
327GND              U25   -BT62       A01X+132858Y+105890X0177Y    R180 S1      
327GND              U25   -BT64       A01X+132117Y+105890X0177Y    R180 S1      
327GND              U25   -BT65       A01X+131747Y+105890X0177Y    R180 S1      
327GND              U25   -BT66       A01X+131377Y+105890X0177Y    R180 S1      
327GND              U25   -BT68       A01X+130637Y+105890X0177Y    R180 S1      
327GND              U25   -BT69       A01X+130267Y+105890X0177Y    R180 S1      
327GND              U25   -BT71       A01X+129527Y+105890X0177Y    R180 S1      
327GND              U25   -BT72       A01X+129157Y+105890X0177Y    R180 S1      
327GND              U25   -BT73       A01X+128787Y+105890X0177Y    R180 S1      
327GND              U25   -BU1        A01X+155247Y+106209X0177Y    R180 S1      
327GND              U25   -BU4        A01X+154137Y+106209X0177Y    R180 S1      
327GND              U25   -BU6        A01X+153397Y+106209X0177Y    R180 S1      
327GND              U25   -BU8        A01X+152657Y+106209X0177Y    R180 S1      
327GND              U25   -BU11       A01X+151546Y+106209X0177Y    R180 S1      
327GND              U25   -BU13       A01X+150806Y+106209X0177Y    R180 S1      
327GND              U25   -BU15       A01X+150066Y+106209X0177Y    R180 S1      
327GND              U25   -BU18       A01X+148956Y+106209X0177Y    R180 S1      
327GND              U25   -BU20       A01X+148216Y+106209X0177Y    R180 S1      
327GND              U25   -BU22       A01X+147476Y+106209X0177Y    R180 S1      
327GND              U25   -BU25       A01X+146365Y+106209X0177Y    R180 S1      
327GND              U25   -BU28       A01X+145255Y+106209X0177Y    R180 S1      
327GND              U25   -BU31       A01X+144145Y+106209X0177Y    R180 S1      
327GND              U25   -BU34       A01X+143035Y+106209X0177Y    R180 S1      
327GND              U25   -BU35       A01X+142665Y+106209X0177Y    R180 S1      
327GND              U25   -BU36       A01X+142294Y+106209X0177Y    R180 S1      
327GND              U25   -BU40       A01X+141184Y+106209X0177Y    R180 S1      
327GND              U25   -BU41       A01X+140814Y+106209X0177Y    R180 S1      
327GND              U25   -BU42       A01X+140444Y+106209X0177Y    R180 S1      
327GND              U25   -BU45       A01X+139334Y+106209X0177Y    R180 S1      
327GND              U25   -BU48       A01X+138224Y+106209X0177Y    R180 S1      
327GND              U25   -BU51       A01X+137113Y+106209X0177Y    R180 S1      
327GND              U25   -BU54       A01X+136003Y+106209X0177Y    R180 S1      
327GND              U25   -BU56       A01X+135263Y+106209X0177Y    R180 S1      
327GND              U25   -BU58       A01X+134523Y+106209X0177Y    R180 S1      
327GND              U25   -BU61       A01X+133413Y+106209X0177Y    R180 S1      
327GND              U25   -BU63       A01X+132672Y+106209X0177Y    R180 S1      
327GND              U25   -BU65       A01X+131932Y+106209X0177Y    R180 S1      
327GND              U25   -BU68       A01X+130822Y+106209X0177Y    R180 S1      
327GND              U25   -BU70       A01X+130082Y+106209X0177Y    R180 S1      
327GND              U25   -BU72       A01X+129342Y+106209X0177Y    R180 S1      
327GND              U25   -BU75       A01X+128232Y+106209X0177Y    R180 S1      
327GND              U25   -BV3        A01X+154692Y+106528X0177Y    R180 S1      
327GND              U25   -BV8        A01X+152842Y+106528X0177Y    R180 S1      
327GND              U25   -BV10       A01X+152102Y+106528X0177Y    R180 S1      
327GND              U25   -BV15       A01X+150251Y+106528X0177Y    R180 S1      
327GND              U25   -BV17       A01X+149511Y+106528X0177Y    R180 S1      
327GND              U25   -BV23       A01X+147290Y+106528X0177Y    R180 S1      
327GND              U25   -BV24       A01X+146920Y+106528X0177Y    R180 S1      
327GND              U25   -BV25       A01X+146550Y+106528X0177Y    R180 S1      
327GND              U25   -BV26       A01X+146180Y+106528X0177Y    R180 S1      
327GND              U25   -BV27       A01X+145810Y+106528X0177Y    R180 S1      
327GND              U25   -BV28       A01X+145440Y+106528X0177Y    R180 S1      
327GND              U25   -BV29       A01X+145070Y+106528X0177Y    R180 S1      
327GND              U25   -BV30       A01X+144700Y+106528X0177Y    R180 S1      
327GND              U25   -BV31       A01X+144330Y+106528X0177Y    R180 S1      
327GND              U25   -BV32       A01X+143960Y+106528X0177Y    R180 S1      
327GND              U25   -BV33       A01X+143590Y+106528X0177Y    R180 S1      
327GND              U25   -BV34       A01X+143220Y+106528X0177Y    R180 S1      
327GND              U25   -BV37       A01X+142109Y+106528X0177Y    R180 S1      
327GND              U25   -BV39       A01X+141369Y+106528X0177Y    R180 S1      
327GND              U25   -BV43       A01X+139889Y+106528X0177Y    R180 S1      
327GND              U25   -BV44       A01X+139519Y+106528X0177Y    R180 S1      
327GND              U25   -BV45       A01X+139149Y+106528X0177Y    R180 S1      
327GND              U25   -BV46       A01X+138779Y+106528X0177Y    R180 S1      
327GND              U25   -BV47       A01X+138409Y+106528X0177Y    R180 S1      
327GND              U25   -BV48       A01X+138039Y+106528X0177Y    R180 S1      
327GND              U25   -BV49       A01X+137668Y+106528X0177Y    R180 S1      
327GND              U25   -BV50       A01X+137298Y+106528X0177Y    R180 S1      
327GND              U25   -BV51       A01X+136928Y+106528X0177Y    R180 S1      
327GND              U25   -BV52       A01X+136558Y+106528X0177Y    R180 S1      
327GND              U25   -BV53       A01X+136188Y+106528X0177Y    R180 S1      
327GND              U25   -BV59       A01X+133968Y+106528X0177Y    R180 S1      
327GND              U25   -BV61       A01X+133228Y+106528X0177Y    R180 S1      
327GND              U25   -BV66       A01X+131377Y+106528X0177Y    R180 S1      
327GND              U25   -BV68       A01X+130637Y+106528X0177Y    R180 S1      
327GND              U25   -BV73       A01X+128787Y+106528X0177Y    R180 S1      
327GND              U25   -BW1        A01X+155247Y+106846X0177Y    R180 S1      
327GND              U25   -BW4        A01X+154137Y+106846X0177Y    R180 S1      
327GND              U25   -BW6        A01X+153397Y+106846X0177Y    R180 S1      
327GND              U25   -BW8        A01X+152657Y+106846X0177Y    R180 S1      
327GND              U25   -BW11       A01X+151546Y+106846X0177Y    R180 S1      
327GND              U25   -BW13       A01X+150806Y+106846X0177Y    R180 S1      
327GND              U25   -BW15       A01X+150066Y+106846X0177Y    R180 S1      
327GND              U25   -BW18       A01X+148956Y+106846X0177Y    R180 S1      
327GND              U25   -BW20       A01X+148216Y+106846X0177Y    R180 S1      
327GND              U25   -BW22       A01X+147476Y+106846X0177Y    R180 S1      
327GND              U25   -BW28       A01X+145255Y+106846X0177Y    R180 S1      
327GND              U25   -BW31       A01X+144145Y+106846X0177Y    R180 S1      
327GND              U25   -BW34       A01X+143035Y+106846X0177Y    R180 S1      
327GND              U25   -BW42       A01X+140444Y+106846X0177Y    R180 S1      
327GND              U25   -BW45       A01X+139334Y+106846X0177Y    R180 S1      
327GND              U25   -BW48       A01X+138224Y+106846X0177Y    R180 S1      
327GND              U25   -BW51       A01X+137113Y+106846X0177Y    R180 S1      
327GND              U25   -BW54       A01X+136003Y+106846X0177Y    R180 S1      
327GND              U25   -BW56       A01X+135263Y+106846X0177Y    R180 S1      
327GND              U25   -BW58       A01X+134523Y+106846X0177Y    R180 S1      
327GND              U25   -BW61       A01X+133413Y+106846X0177Y    R180 S1      
327GND              U25   -BW63       A01X+132672Y+106846X0177Y    R180 S1      
327GND              U25   -BW65       A01X+131932Y+106846X0177Y    R180 S1      
327GND              U25   -BW68       A01X+130822Y+106846X0177Y    R180 S1      
327GND              U25   -BW70       A01X+130082Y+106846X0177Y    R180 S1      
327GND              U25   -BW72       A01X+129342Y+106846X0177Y    R180 S1      
327GND              U25   -BW75       A01X+128232Y+106846X0177Y    R180 S1      
327GND              U25   -BY3        A01X+154692Y+107165X0177Y    R180 S1      
327GND              U25   -BY5        A01X+153952Y+107165X0177Y    R180 S1      
327GND              U25   -BY8        A01X+152842Y+107165X0177Y    R180 S1      
327GND              U25   -BY10       A01X+152102Y+107165X0177Y    R180 S1      
327GND              U25   -BY12       A01X+151361Y+107165X0177Y    R180 S1      
327GND              U25   -BY15       A01X+150251Y+107165X0177Y    R180 S1      
327GND              U25   -BY17       A01X+149511Y+107165X0177Y    R180 S1      
327GND              U25   -BY19       A01X+148771Y+107165X0177Y    R180 S1      
327GND              U25   -BY22       A01X+147661Y+107165X0177Y    R180 S1      
327GND              U25   -BY25       A01X+146550Y+107165X0177Y    R180 S1      
327GND              U25   -BY28       A01X+145440Y+107165X0177Y    R180 S1      
327GND              U25   -BY31       A01X+144330Y+107165X0177Y    R180 S1      
327GND              U25   -BY34       A01X+143220Y+107165X0177Y    R180 S1      
327GND              U25   -BY37       A01X+142109Y+107165X0177Y    R180 S1      
327GND              U25   -BY39       A01X+141369Y+107165X0177Y    R180 S1      
327GND              U25   -BY42       A01X+140259Y+107165X0177Y    R180 S1      
327GND              U25   -BY45       A01X+139149Y+107165X0177Y    R180 S1      
327GND              U25   -BY48       A01X+138039Y+107165X0177Y    R180 S1      
327GND              U25   -BY51       A01X+136928Y+107165X0177Y    R180 S1      
327GND              U25   -BY54       A01X+135818Y+107165X0177Y    R180 S1      
327GND              U25   -BY57       A01X+134708Y+107165X0177Y    R180 S1      
327GND              U25   -BY59       A01X+133968Y+107165X0177Y    R180 S1      
327GND              U25   -BY61       A01X+133228Y+107165X0177Y    R180 S1      
327GND              U25   -BY64       A01X+132117Y+107165X0177Y    R180 S1      
327GND              U25   -BY66       A01X+131377Y+107165X0177Y    R180 S1      
327GND              U25   -BY68       A01X+130637Y+107165X0177Y    R180 S1      
327GND              U25   -BY71       A01X+129527Y+107165X0177Y    R180 S1      
327GND              U25   -BY73       A01X+128787Y+107165X0177Y    R180 S1      
327GND              U25   -CA1        A01X+155247Y+107484X0177Y    R180 S1      
327GND              U25   -CA6        A01X+153397Y+107484X0177Y    R180 S1      
327GND              U25   -CA8        A01X+152657Y+107484X0177Y    R180 S1      
327GND              U25   -CA13       A01X+150806Y+107484X0177Y    R180 S1      
327GND              U25   -CA15       A01X+150066Y+107484X0177Y    R180 S1      
327GND              U25   -CA20       A01X+148216Y+107484X0177Y    R180 S1      
327GND              U25   -CA22       A01X+147476Y+107484X0177Y    R180 S1      
327GND              U25   -CA25       A01X+146365Y+107484X0177Y    R180 S1      
327GND              U25   -CA28       A01X+145255Y+107484X0177Y    R180 S1      
327GND              U25   -CA31       A01X+144145Y+107484X0177Y    R180 S1      
327GND              U25   -CA34       A01X+143035Y+107484X0177Y    R180 S1      
327GND              U25   -CA35       A01X+142665Y+107484X0177Y    R180 S1      
327GND              U25   -CA36       A01X+142294Y+107484X0177Y    R180 S1      
327GND              U25   -CA40       A01X+141184Y+107484X0177Y    R180 S1      
327GND              U25   -CA41       A01X+140814Y+107484X0177Y    R180 S1      
327GND              U25   -CA42       A01X+140444Y+107484X0177Y    R180 S1      
327GND              U25   -CA45       A01X+139334Y+107484X0177Y    R180 S1      
327GND              U25   -CA48       A01X+138224Y+107484X0177Y    R180 S1      
327GND              U25   -CA51       A01X+137113Y+107484X0177Y    R180 S1      
327GND              U25   -CA54       A01X+136003Y+107484X0177Y    R180 S1      
327GND              U25   -CA56       A01X+135263Y+107484X0177Y    R180 S1      
327GND              U25   -CA61       A01X+133413Y+107484X0177Y    R180 S1      
327GND              U25   -CA63       A01X+132672Y+107484X0177Y    R180 S1      
327GND              U25   -CA68       A01X+130822Y+107484X0177Y    R180 S1      
327GND              U25   -CA70       A01X+130082Y+107484X0177Y    R180 S1      
327GND              U25   -CA75       A01X+128232Y+107484X0177Y    R180 S1      
327GND              U25   -CB3        A01X+154692Y+107803X0177Y    R180 S1      
327GND              U25   -CB5        A01X+153952Y+107803X0177Y    R180 S1      
327GND              U25   -CB8        A01X+152842Y+107803X0177Y    R180 S1      
327GND              U25   -CB10       A01X+152102Y+107803X0177Y    R180 S1      
327GND              U25   -CB12       A01X+151361Y+107803X0177Y    R180 S1      
327GND              U25   -CB15       A01X+150251Y+107803X0177Y    R180 S1      
327GND              U25   -CB17       A01X+149511Y+107803X0177Y    R180 S1      
327GND              U25   -CB19       A01X+148771Y+107803X0177Y    R180 S1      
327GND              U25   -CB23       A01X+147290Y+107803X0177Y    R180 S1      
327GND              U25   -CB24       A01X+146920Y+107803X0177Y    R180 S1      
327GND              U25   -CB25       A01X+146550Y+107803X0177Y    R180 S1      
327GND              U25   -CB26       A01X+146180Y+107803X0177Y    R180 S1      
327GND              U25   -CB27       A01X+145810Y+107803X0177Y    R180 S1      
327GND              U25   -CB28       A01X+145440Y+107803X0177Y    R180 S1      
327GND              U25   -CB29       A01X+145070Y+107803X0177Y    R180 S1      
327GND              U25   -CB30       A01X+144700Y+107803X0177Y    R180 S1      
327GND              U25   -CB31       A01X+144330Y+107803X0177Y    R180 S1      
327GND              U25   -CB32       A01X+143960Y+107803X0177Y    R180 S1      
327GND              U25   -CB33       A01X+143590Y+107803X0177Y    R180 S1      
327GND              U25   -CB34       A01X+143220Y+107803X0177Y    R180 S1      
327GND              U25   -CB37       A01X+142109Y+107803X0177Y    R180 S1      
327GND              U25   -CB39       A01X+141369Y+107803X0177Y    R180 S1      
327GND              U25   -CB42       A01X+140259Y+107803X0177Y    R180 S1      
327GND              U25   -CB43       A01X+139889Y+107803X0177Y    R180 S1      
327GND              U25   -CB45       A01X+139149Y+107803X0177Y    R180 S1      
327GND              U25   -CB46       A01X+138779Y+107803X0177Y    R180 S1      
327GND              U25   -CB47       A01X+138409Y+107803X0177Y    R180 S1      
327GND              U25   -CB48       A01X+138039Y+107803X0177Y    R180 S1      
327GND              U25   -CB49       A01X+137668Y+107803X0177Y    R180 S1      
327GND              U25   -CB50       A01X+137298Y+107803X0177Y    R180 S1      
327GND              U25   -CB51       A01X+136928Y+107803X0177Y    R180 S1      
327GND              U25   -CB52       A01X+136558Y+107803X0177Y    R180 S1      
327GND              U25   -CB53       A01X+136188Y+107803X0177Y    R180 S1      
327GND              U25   -CB57       A01X+134708Y+107803X0177Y    R180 S1      
327GND              U25   -CB59       A01X+133968Y+107803X0177Y    R180 S1      
327GND              U25   -CB61       A01X+133228Y+107803X0177Y    R180 S1      
327GND              U25   -CB64       A01X+132117Y+107803X0177Y    R180 S1      
327GND              U25   -CB66       A01X+131377Y+107803X0177Y    R180 S1      
327GND              U25   -CB68       A01X+130637Y+107803X0177Y    R180 S1      
327GND              U25   -CB71       A01X+129527Y+107803X0177Y    R180 S1      
327GND              U25   -CB73       A01X+128787Y+107803X0177Y    R180 S1      
327GND              U25   -CC1        A01X+155247Y+108122X0177Y    R180 S1      
327GND              U25   -CC4        A01X+154137Y+108122X0177Y    R180 S1      
327GND              U25   -CC6        A01X+153397Y+108122X0177Y    R180 S1      
327GND              U25   -CC8        A01X+152657Y+108122X0177Y    R180 S1      
327GND              U25   -CC11       A01X+151546Y+108122X0177Y    R180 S1      
327GND              U25   -CC13       A01X+150806Y+108122X0177Y    R180 S1      
327GND              U25   -CC15       A01X+150066Y+108122X0177Y    R180 S1      
327GND              U25   -CC18       A01X+148956Y+108122X0177Y    R180 S1      
327GND              U25   -CC20       A01X+148216Y+108122X0177Y    R180 S1      
327GND              U25   -CC25       A01X+146365Y+108122X0177Y    R180 S1      
327GND              U25   -CC28       A01X+145255Y+108122X0177Y    R180 S1      
327GND              U25   -CC31       A01X+144145Y+108122X0177Y    R180 S1      
327GND              U25   -CC34       A01X+143035Y+108122X0177Y    R180 S1      
327GND              U25   -CC42       A01X+140444Y+108122X0177Y    R180 S1      
327GND              U25   -CC45       A01X+139334Y+108122X0177Y    R180 S1      
327GND              U25   -CC48       A01X+138224Y+108122X0177Y    R180 S1      
327GND              U25   -CC51       A01X+137113Y+108122X0177Y    R180 S1      
327GND              U25   -CC54       A01X+136003Y+108122X0177Y    R180 S1      
327GND              U25   -CC56       A01X+135263Y+108122X0177Y    R180 S1      
327GND              U25   -CC58       A01X+134523Y+108122X0177Y    R180 S1      
327GND              U25   -CC61       A01X+133413Y+108122X0177Y    R180 S1      
327GND              U25   -CC63       A01X+132672Y+108122X0177Y    R180 S1      
327GND              U25   -CC65       A01X+131932Y+108122X0177Y    R180 S1      
327GND              U25   -CC68       A01X+130822Y+108122X0177Y    R180 S1      
327GND              U25   -CC70       A01X+130082Y+108122X0177Y    R180 S1      
327GND              U25   -CC72       A01X+129342Y+108122X0177Y    R180 S1      
327GND              U25   -CC75       A01X+128232Y+108122X0177Y    R180 S1      
327GND              U25   -CD3        A01X+154692Y+108441X0177Y    R180 S1      
327GND              U25   -CD8        A01X+152842Y+108441X0177Y    R180 S1      
327GND              U25   -CD10       A01X+152102Y+108441X0177Y    R180 S1      
327GND              U25   -CD15       A01X+150251Y+108441X0177Y    R180 S1      
327GND              U25   -CD17       A01X+149511Y+108441X0177Y    R180 S1      
327GND              U25   -CD22       A01X+147661Y+108441X0177Y    R180 S1      
327GND              U25   -CD25       A01X+146550Y+108441X0177Y    R180 S1      
327GND              U25   -CD28       A01X+145440Y+108441X0177Y    R180 S1      
327GND              U25   -CD31       A01X+144330Y+108441X0177Y    R180 S1      
327GND              U25   -CD34       A01X+143220Y+108441X0177Y    R180 S1      
327GND              U25   -CD37       A01X+142109Y+108441X0177Y    R180 S1      
327GND              U25   -CD39       A01X+141369Y+108441X0177Y    R180 S1      
327GND              U25   -CD42       A01X+140259Y+108441X0177Y    R180 S1      
327GND              U25   -CD45       A01X+139149Y+108441X0177Y    R180 S1      
327GND              U25   -CD48       A01X+138039Y+108441X0177Y    R180 S1      
327GND              U25   -CD51       A01X+136928Y+108441X0177Y    R180 S1      
327GND              U25   -CD54       A01X+135818Y+108441X0177Y    R180 S1      
327GND              U25   -CD59       A01X+133968Y+108441X0177Y    R180 S1      
327GND              U25   -CD61       A01X+133228Y+108441X0177Y    R180 S1      
327GND              U25   -CD66       A01X+131377Y+108441X0177Y    R180 S1      
327GND              U25   -CD68       A01X+130637Y+108441X0177Y    R180 S1      
327GND              U25   -CD73       A01X+128787Y+108441X0177Y    R180 S1      
327GND              U25   -CE1        A01X+155247Y+108760X0177Y    R180 S1      
327GND              U25   -CE4        A01X+154137Y+108760X0177Y    R180 S1      
327GND              U25   -CE6        A01X+153397Y+108760X0177Y    R180 S1      
327GND              U25   -CE8        A01X+152657Y+108760X0177Y    R180 S1      
327GND              U25   -CE11       A01X+151546Y+108760X0177Y    R180 S1      
327GND              U25   -CE13       A01X+150806Y+108760X0177Y    R180 S1      
327GND              U25   -CE15       A01X+150066Y+108760X0177Y    R180 S1      
327GND              U25   -CE18       A01X+148956Y+108760X0177Y    R180 S1      
327GND              U25   -CE20       A01X+148216Y+108760X0177Y    R180 S1      
327GND              U25   -CE22       A01X+147476Y+108760X0177Y    R180 S1      
327GND              U25   -CE25       A01X+146365Y+108760X0177Y    R180 S1      
327GND              U25   -CE28       A01X+145255Y+108760X0177Y    R180 S1      
327GND              U25   -CE31       A01X+144145Y+108760X0177Y    R180 S1      
327GND              U25   -CE34       A01X+143035Y+108760X0177Y    R180 S1      
327GND              U25   -CE35       A01X+142665Y+108760X0177Y    R180 S1      
327GND              U25   -CE36       A01X+142294Y+108760X0177Y    R180 S1      
327GND              U25   -CE40       A01X+141184Y+108760X0177Y    R180 S1      
327GND              U25   -CE41       A01X+140814Y+108760X0177Y    R180 S1      
327GND              U25   -CE42       A01X+140444Y+108760X0177Y    R180 S1      
327GND              U25   -CE45       A01X+139334Y+108760X0177Y    R180 S1      
327GND              U25   -CE48       A01X+138224Y+108760X0177Y    R180 S1      
327GND              U25   -CE51       A01X+137113Y+108760X0177Y    R180 S1      
327GND              U25   -CE54       A01X+136003Y+108760X0177Y    R180 S1      
327GND              U25   -CE56       A01X+135263Y+108760X0177Y    R180 S1      
327GND              U25   -CE58       A01X+134523Y+108760X0177Y    R180 S1      
327GND              U25   -CE61       A01X+133413Y+108760X0177Y    R180 S1      
327GND              U25   -CE63       A01X+132672Y+108760X0177Y    R180 S1      
327GND              U25   -CE65       A01X+131932Y+108760X0177Y    R180 S1      
327GND              U25   -CE68       A01X+130822Y+108760X0177Y    R180 S1      
327GND              U25   -CE70       A01X+130082Y+108760X0177Y    R180 S1      
327GND              U25   -CE72       A01X+129342Y+108760X0177Y    R180 S1      
327GND              U25   -CE75       A01X+128232Y+108760X0177Y    R180 S1      
327GND              U25   -CF3        A01X+154692Y+109079X0177Y    R180 S1      
327GND              U25   -CF5        A01X+153952Y+109079X0177Y    R180 S1      
327GND              U25   -CF8        A01X+152842Y+109079X0177Y    R180 S1      
327GND              U25   -CF10       A01X+152102Y+109079X0177Y    R180 S1      
327GND              U25   -CF12       A01X+151361Y+109079X0177Y    R180 S1      
327GND              U25   -CF15       A01X+150251Y+109079X0177Y    R180 S1      
327GND              U25   -CF17       A01X+149511Y+109079X0177Y    R180 S1      
327GND              U25   -CF19       A01X+148771Y+109079X0177Y    R180 S1      
327GND              U25   -CF23       A01X+147290Y+109079X0177Y    R180 S1      
327GND              U25   -CF24       A01X+146920Y+109079X0177Y    R180 S1      
327GND              U25   -CF25       A01X+146550Y+109079X0177Y    R180 S1      
327GND              U25   -CF26       A01X+146180Y+109079X0177Y    R180 S1      
327GND              U25   -CF27       A01X+145810Y+109079X0177Y    R180 S1      
327GND              U25   -CF28       A01X+145440Y+109079X0177Y    R180 S1      
327GND              U25   -CF29       A01X+145070Y+109079X0177Y    R180 S1      
327GND              U25   -CF30       A01X+144700Y+109079X0177Y    R180 S1      
327GND              U25   -CF31       A01X+144330Y+109079X0177Y    R180 S1      
327GND              U25   -CF32       A01X+143960Y+109079X0177Y    R180 S1      
327GND              U25   -CF33       A01X+143590Y+109079X0177Y    R180 S1      
327GND              U25   -CF34       A01X+143220Y+109079X0177Y    R180 S1      
327GND              U25   -CF37       A01X+142109Y+109079X0177Y    R180 S1      
327GND              U25   -CF39       A01X+141369Y+109079X0177Y    R180 S1      
327GND              U25   -CF42       A01X+140259Y+109079X0177Y    R180 S1      
327GND              U25   -CF43       A01X+139889Y+109079X0177Y    R180 S1      
327GND              U25   -CF44       A01X+139519Y+109079X0177Y    R180 S1      
327GND              U25   -CF45       A01X+139149Y+109079X0177Y    R180 S1      
327GND              U25   -CF47       A01X+138409Y+109079X0177Y    R180 S1      
327GND              U25   -CF48       A01X+138039Y+109079X0177Y    R180 S1      
327GND              U25   -CF49       A01X+137668Y+109079X0177Y    R180 S1      
327GND              U25   -CF50       A01X+137298Y+109079X0177Y    R180 S1      
327GND              U25   -CF51       A01X+136928Y+109079X0177Y    R180 S1      
327GND              U25   -CF52       A01X+136558Y+109079X0177Y    R180 S1      
327GND              U25   -CF53       A01X+136188Y+109079X0177Y    R180 S1      
327GND              U25   -CF57       A01X+134708Y+109079X0177Y    R180 S1      
327GND              U25   -CF59       A01X+133968Y+109079X0177Y    R180 S1      
327GND              U25   -CF61       A01X+133228Y+109079X0177Y    R180 S1      
327GND              U25   -CF64       A01X+132117Y+109079X0177Y    R180 S1      
327GND              U25   -CF66       A01X+131377Y+109079X0177Y    R180 S1      
327GND              U25   -CF68       A01X+130637Y+109079X0177Y    R180 S1      
327GND              U25   -CF71       A01X+129527Y+109079X0177Y    R180 S1      
327GND              U25   -CF73       A01X+128787Y+109079X0177Y    R180 S1      
327GND              U25   -CG1        A01X+155247Y+109398X0177Y    R180 S1      
327GND              U25   -CG6        A01X+153397Y+109398X0177Y    R180 S1      
327GND              U25   -CG8        A01X+152657Y+109398X0177Y    R180 S1      
327GND              U25   -CG13       A01X+150806Y+109398X0177Y    R180 S1      
327GND              U25   -CG15       A01X+150066Y+109398X0177Y    R180 S1      
327GND              U25   -CG20       A01X+148216Y+109398X0177Y    R180 S1      
327GND              U25   -CG22       A01X+147476Y+109398X0177Y    R180 S1      
327GND              U25   -CG25       A01X+146365Y+109398X0177Y    R180 S1      
327GND              U25   -CG28       A01X+145255Y+109398X0177Y    R180 S1      
327GND              U25   -CG31       A01X+144145Y+109398X0177Y    R180 S1      
327GND              U25   -CG34       A01X+143035Y+109398X0177Y    R180 S1      
327GND              U25   -CG45       A01X+139334Y+109398X0177Y    R180 S1      
327GND              U25   -CG48       A01X+138224Y+109398X0177Y    R180 S1      
327GND              U25   -CG51       A01X+137113Y+109398X0177Y    R180 S1      
327GND              U25   -CG54       A01X+136003Y+109398X0177Y    R180 S1      
327GND              U25   -CG56       A01X+135263Y+109398X0177Y    R180 S1      
327GND              U25   -CG61       A01X+133413Y+109398X0177Y    R180 S1      
327GND              U25   -CG63       A01X+132672Y+109398X0177Y    R180 S1      
327GND              U25   -CG68       A01X+130822Y+109398X0177Y    R180 S1      
327GND              U25   -CG70       A01X+130082Y+109398X0177Y    R180 S1      
327GND              U25   -CG75       A01X+128232Y+109398X0177Y    R180 S1      
327GND              U25   -CH3        A01X+154692Y+109717X0177Y    R180 S1      
327GND              U25   -CH5        A01X+153952Y+109717X0177Y    R180 S1      
327GND              U25   -CH8        A01X+152842Y+109717X0177Y    R180 S1      
327GND              U25   -CH10       A01X+152102Y+109717X0177Y    R180 S1      
327GND              U25   -CH12       A01X+151361Y+109717X0177Y    R180 S1      
327GND              U25   -CH15       A01X+150251Y+109717X0177Y    R180 S1      
327GND              U25   -CH17       A01X+149511Y+109717X0177Y    R180 S1      
327GND              U25   -CH19       A01X+148771Y+109717X0177Y    R180 S1      
327GND              U25   -CH22       A01X+147661Y+109717X0177Y    R180 S1      
327GND              U25   -CH25       A01X+146550Y+109717X0177Y    R180 S1      
327GND              U25   -CH28       A01X+145440Y+109717X0177Y    R180 S1      
327GND              U25   -CH31       A01X+144330Y+109717X0177Y    R180 S1      
327GND              U25   -CH34       A01X+143220Y+109717X0177Y    R180 S1      
327GND              U25   -CH37       A01X+142109Y+109717X0177Y    R180 S1      
327GND              U25   -CH39       A01X+141369Y+109717X0177Y    R180 S1      
327GND              U25   -CH42       A01X+140259Y+109717X0177Y    R180 S1      
327GND              U25   -CH45       A01X+139149Y+109717X0177Y    R180 S1      
327GND              U25   -CH48       A01X+138039Y+109717X0177Y    R180 S1      
327GND              U25   -CH51       A01X+136928Y+109717X0177Y    R180 S1      
327GND              U25   -CH54       A01X+135818Y+109717X0177Y    R180 S1      
327GND              U25   -CH57       A01X+134708Y+109717X0177Y    R180 S1      
327GND              U25   -CH59       A01X+133968Y+109717X0177Y    R180 S1      
327GND              U25   -CH61       A01X+133228Y+109717X0177Y    R180 S1      
327GND              U25   -CH64       A01X+132117Y+109717X0177Y    R180 S1      
327GND              U25   -CH66       A01X+131377Y+109717X0177Y    R180 S1      
327GND              U25   -CH68       A01X+130637Y+109717X0177Y    R180 S1      
327GND              U25   -CH71       A01X+129527Y+109717X0177Y    R180 S1      
327GND              U25   -CH73       A01X+128787Y+109717X0177Y    R180 S1      
327GND              U25   -CJ1        A01X+155247Y+110036X0177Y    R180 S1      
327GND              U25   -CJ4        A01X+154137Y+110036X0177Y    R180 S1      
327GND              U25   -CJ6        A01X+153397Y+110036X0177Y    R180 S1      
327GND              U25   -CJ8        A01X+152657Y+110036X0177Y    R180 S1      
327GND              U25   -CJ11       A01X+151546Y+110036X0177Y    R180 S1      
327GND              U25   -CJ13       A01X+150806Y+110036X0177Y    R180 S1      
327GND              U25   -CJ15       A01X+150066Y+110036X0177Y    R180 S1      
327GND              U25   -CJ18       A01X+148956Y+110036X0177Y    R180 S1      
327GND              U25   -CJ20       A01X+148216Y+110036X0177Y    R180 S1      
327GND              U25   -CJ23       A01X+147106Y+110036X0177Y    R180 S1      
327GND              U25   -CJ31       A01X+144145Y+110036X0177Y    R180 S1      
327GND              U25   -CJ34       A01X+143035Y+110036X0177Y    R180 S1      
327GND              U25   -CJ35       A01X+142665Y+110036X0177Y    R180 S1      
327GND              U25   -CJ36       A01X+142294Y+110036X0177Y    R180 S1      
327GND              U25   -CJ40       A01X+141184Y+110036X0177Y    R180 S1      
327GND              U25   -CJ41       A01X+140814Y+110036X0177Y    R180 S1      
327GND              U25   -CJ42       A01X+140444Y+110036X0177Y    R180 S1      
327GND              U25   -CJ45       A01X+139334Y+110036X0177Y    R180 S1      
327GND              U25   -CJ56       A01X+135263Y+110036X0177Y    R180 S1      
327GND              U25   -CJ58       A01X+134523Y+110036X0177Y    R180 S1      
327GND              U25   -CJ61       A01X+133413Y+110036X0177Y    R180 S1      
327GND              U25   -CJ63       A01X+132672Y+110036X0177Y    R180 S1      
327GND              U25   -CJ65       A01X+131932Y+110036X0177Y    R180 S1      
327GND              U25   -CJ68       A01X+130822Y+110036X0177Y    R180 S1      
327GND              U25   -CJ70       A01X+130082Y+110036X0177Y    R180 S1      
327GND              U25   -CJ72       A01X+129342Y+110036X0177Y    R180 S1      
327GND              U25   -CJ75       A01X+128232Y+110036X0177Y    R180 S1      
327GND              U25   -CK3        A01X+154692Y+110354X0177Y    R180 S1      
327GND              U25   -CK8        A01X+152842Y+110354X0177Y    R180 S1      
327GND              U25   -CK15       A01X+150251Y+110354X0177Y    R180 S1      
327GND              U25   -CK17       A01X+149511Y+110354X0177Y    R180 S1      
327GND              U25   -CK22       A01X+147661Y+110354X0177Y    R180 S1      
327GND              U25   -CK23       A01X+147290Y+110354X0177Y    R180 S1      
327GND              U25   -CK24       A01X+146920Y+110354X0177Y    R180 S1      
327GND              U25   -CK25       A01X+146550Y+110354X0177Y    R180 S1      
327GND              U25   -CK26       A01X+146180Y+110354X0177Y    R180 S1      
327GND              U25   -CK27       A01X+145810Y+110354X0177Y    R180 S1      
327GND              U25   -CK28       A01X+145440Y+110354X0177Y    R180 S1      
327GND              U25   -CK32       A01X+143960Y+110354X0177Y    R180 S1      
327GND              U25   -CK33       A01X+143590Y+110354X0177Y    R180 S1      
327GND              U25   -CK34       A01X+143220Y+110354X0177Y    R180 S1      
327GND              U25   -CK37       A01X+142109Y+110354X0177Y    R180 S1      
327GND              U25   -CK39       A01X+141369Y+110354X0177Y    R180 S1      
327GND              U25   -CK42       A01X+140259Y+110354X0177Y    R180 S1      
327GND              U25   -CK43       A01X+139889Y+110354X0177Y    R180 S1      
327GND              U25   -CK44       A01X+139519Y+110354X0177Y    R180 S1      
327GND              U25   -CK45       A01X+139149Y+110354X0177Y    R180 S1      
327GND              U25   -CK48       A01X+138039Y+110354X0177Y    R180 S1      
327GND              U25   -CK49       A01X+137668Y+110354X0177Y    R180 S1      
327GND              U25   -CK50       A01X+137298Y+110354X0177Y    R180 S1      
327GND              U25   -CK51       A01X+136928Y+110354X0177Y    R180 S1      
327GND              U25   -CK52       A01X+136558Y+110354X0177Y    R180 S1      
327GND              U25   -CK53       A01X+136188Y+110354X0177Y    R180 S1      
327GND              U25   -CK54       A01X+135818Y+110354X0177Y    R180 S1      
327GND              U25   -CK59       A01X+133968Y+110354X0177Y    R180 S1      
327GND              U25   -CK61       A01X+133228Y+110354X0177Y    R180 S1      
327GND              U25   -CK66       A01X+131377Y+110354X0177Y    R180 S1      
327GND              U25   -CK68       A01X+130637Y+110354X0177Y    R180 S1      
327GND              U25   -CK73       A01X+128787Y+110354X0177Y    R180 S1      
327GND              U25   -CL1        A01X+155247Y+110673X0177Y    R180 S1      
327GND              U25   -CL4        A01X+154137Y+110673X0177Y    R180 S1      
327GND              U25   -CL6        A01X+153397Y+110673X0177Y    R180 S1      
327GND              U25   -CL8        A01X+152657Y+110673X0177Y    R180 S1      
327GND              U25   -CL11       A01X+151546Y+110673X0177Y    R180 S1      
327GND              U25   -CL13       A01X+150806Y+110673X0177Y    R180 S1      
327GND              U25   -CL15       A01X+150066Y+110673X0177Y    R180 S1      
327GND              U25   -CL18       A01X+148956Y+110673X0177Y    R180 S1      
327GND              U25   -CL20       A01X+148216Y+110673X0177Y    R180 S1      
327GND              U25   -CL22       A01X+147476Y+110673X0177Y    R180 S1      
327GND              U25   -CL25       A01X+146365Y+110673X0177Y    R180 S1      
327GND              U25   -CL28       A01X+145255Y+110673X0177Y    R180 S1      
327GND              U25   -CL31       A01X+144145Y+110673X0177Y    R180 S1      
327GND              U25   -CL34       A01X+143035Y+110673X0177Y    R180 S1      
327GND              U25   -CL35       A01X+142665Y+110673X0177Y    R180 S1      
327GND              U25   -CL36       A01X+142294Y+110673X0177Y    R180 S1      
327GND              U25   -CL40       A01X+141184Y+110673X0177Y    R180 S1      
327GND              U25   -CL41       A01X+140814Y+110673X0177Y    R180 S1      
327GND              U25   -CL42       A01X+140444Y+110673X0177Y    R180 S1      
327GND              U25   -CL45       A01X+139334Y+110673X0177Y    R180 S1      
327GND              U25   -CL48       A01X+138224Y+110673X0177Y    R180 S1      
327GND              U25   -CL51       A01X+137113Y+110673X0177Y    R180 S1      
327GND              U25   -CL54       A01X+136003Y+110673X0177Y    R180 S1      
327GND              U25   -CL56       A01X+135263Y+110673X0177Y    R180 S1      
327GND              U25   -CL58       A01X+134523Y+110673X0177Y    R180 S1      
327GND              U25   -CL61       A01X+133413Y+110673X0177Y    R180 S1      
327GND              U25   -CL63       A01X+132672Y+110673X0177Y    R180 S1      
327GND              U25   -CL65       A01X+131932Y+110673X0177Y    R180 S1      
327GND              U25   -CL68       A01X+130822Y+110673X0177Y    R180 S1      
327GND              U25   -CL70       A01X+130082Y+110673X0177Y    R180 S1      
327GND              U25   -CL72       A01X+129342Y+110673X0177Y    R180 S1      
327GND              U25   -CL75       A01X+128232Y+110673X0177Y    R180 S1      
327GND              U25   -CM3        A01X+154692Y+110992X0177Y    R180 S1      
327GND              U25   -CM5        A01X+153952Y+110992X0177Y    R180 S1      
327GND              U25   -CM8        A01X+152842Y+110992X0177Y    R180 S1      
327GND              U25   -CM10       A01X+152102Y+110992X0177Y    R180 S1      
327GND              U25   -CM12       A01X+151361Y+110992X0177Y    R180 S1      
327GND              U25   -CM15       A01X+150251Y+110992X0177Y    R180 S1      
327GND              U25   -CM17       A01X+149511Y+110992X0177Y    R180 S1      
327GND              U25   -CM19       A01X+148771Y+110992X0177Y    R180 S1      
327GND              U25   -CM23       A01X+147290Y+110992X0177Y    R180 S1      
327GND              U25   -CM24       A01X+146920Y+110992X0177Y    R180 S1      
327GND              U25   -CM25       A01X+146550Y+110992X0177Y    R180 S1      
327GND              U25   -CM26       A01X+146180Y+110992X0177Y    R180 S1      
327GND              U25   -CM27       A01X+145810Y+110992X0177Y    R180 S1      
327GND              U25   -CM28       A01X+145440Y+110992X0177Y    R180 S1      
327GND              U25   -CM29       A01X+145070Y+110992X0177Y    R180 S1      
327GND              U25   -CM30       A01X+144700Y+110992X0177Y    R180 S1      
327GND              U25   -CM31       A01X+144330Y+110992X0177Y    R180 S1      
327GND              U25   -CM32       A01X+143960Y+110992X0177Y    R180 S1      
327GND              U25   -CM33       A01X+143590Y+110992X0177Y    R180 S1      
327GND              U25   -CM34       A01X+143220Y+110992X0177Y    R180 S1      
327GND              U25   -CM37       A01X+142109Y+110992X0177Y    R180 S1      
327GND              U25   -CM39       A01X+141369Y+110992X0177Y    R180 S1      
327GND              U25   -CM42       A01X+140259Y+110992X0177Y    R180 S1      
327GND              U25   -CM43       A01X+139889Y+110992X0177Y    R180 S1      
327GND              U25   -CM44       A01X+139519Y+110992X0177Y    R180 S1      
327GND              U25   -CM45       A01X+139149Y+110992X0177Y    R180 S1      
327GND              U25   -CM46       A01X+138779Y+110992X0177Y    R180 S1      
327GND              U25   -CM47       A01X+138409Y+110992X0177Y    R180 S1      
327GND              U25   -CM48       A01X+138039Y+110992X0177Y    R180 S1      
327GND              U25   -CM49       A01X+137668Y+110992X0177Y    R180 S1      
327GND              U25   -CM51       A01X+136928Y+110992X0177Y    R180 S1      
327GND              U25   -CM52       A01X+136558Y+110992X0177Y    R180 S1      
327GND              U25   -CM53       A01X+136188Y+110992X0177Y    R180 S1      
327GND              U25   -CM57       A01X+134708Y+110992X0177Y    R180 S1      
327GND              U25   -CM59       A01X+133968Y+110992X0177Y    R180 S1      
327GND              U25   -CM61       A01X+133228Y+110992X0177Y    R180 S1      
327GND              U25   -CM64       A01X+132117Y+110992X0177Y    R180 S1      
327GND              U25   -CM66       A01X+131377Y+110992X0177Y    R180 S1      
327GND              U25   -CM68       A01X+130637Y+110992X0177Y    R180 S1      
327GND              U25   -CM71       A01X+129527Y+110992X0177Y    R180 S1      
327GND              U25   -CM73       A01X+128787Y+110992X0177Y    R180 S1      
327GND              U25   -CN1        A01X+155247Y+111311X0177Y    R180 S1      
327GND              U25   -CN6        A01X+153397Y+111311X0177Y    R180 S1      
327GND              U25   -CN8        A01X+152657Y+111311X0177Y    R180 S1      
327GND              U25   -CN13       A01X+150806Y+111311X0177Y    R180 S1      
327GND              U25   -CN15       A01X+150066Y+111311X0177Y    R180 S1      
327GND              U25   -CN20       A01X+148216Y+111311X0177Y    R180 S1      
327GND              U25   -CN22       A01X+147476Y+111311X0177Y    R180 S1      
327GND              U25   -CN25       A01X+146365Y+111311X0177Y    R180 S1      
327GND              U25   -CN28       A01X+145255Y+111311X0177Y    R180 S1      
327GND              U25   -CN31       A01X+144145Y+111311X0177Y    R180 S1      
327GND              U25   -CN34       A01X+143035Y+111311X0177Y    R180 S1      
327GND              U25   -CN42       A01X+140444Y+111311X0177Y    R180 S1      
327GND              U25   -CN45       A01X+139334Y+111311X0177Y    R180 S1      
327GND              U25   -CN48       A01X+138224Y+111311X0177Y    R180 S1      
327GND              U25   -CN51       A01X+137113Y+111311X0177Y    R180 S1      
327GND              U25   -CN56       A01X+135263Y+111311X0177Y    R180 S1      
327GND              U25   -CN61       A01X+133413Y+111311X0177Y    R180 S1      
327GND              U25   -CN63       A01X+132672Y+111311X0177Y    R180 S1      
327GND              U25   -CN68       A01X+130822Y+111311X0177Y    R180 S1      
327GND              U25   -CN70       A01X+130082Y+111311X0177Y    R180 S1      
327GND              U25   -CN75       A01X+128232Y+111311X0177Y    R180 S1      
327GND              U25   -CP3        A01X+154692Y+111630X0177Y    R180 S1      
327GND              U25   -CP5        A01X+153952Y+111630X0177Y    R180 S1      
327GND              U25   -CP8        A01X+152842Y+111630X0177Y    R180 S1      
327GND              U25   -CP10       A01X+152102Y+111630X0177Y    R180 S1      
327GND              U25   -CP12       A01X+151361Y+111630X0177Y    R180 S1      
327GND              U25   -CP15       A01X+150251Y+111630X0177Y    R180 S1      
327GND              U25   -CP17       A01X+149511Y+111630X0177Y    R180 S1      
327GND              U25   -CP19       A01X+148771Y+111630X0177Y    R180 S1      
327GND              U25   -CP22       A01X+147661Y+111630X0177Y    R180 S1      
327GND              U25   -CP25       A01X+146550Y+111630X0177Y    R180 S1      
327GND              U25   -CP28       A01X+145440Y+111630X0177Y    R180 S1      
327GND              U25   -CP31       A01X+144330Y+111630X0177Y    R180 S1      
327GND              U25   -CP34       A01X+143220Y+111630X0177Y    R180 S1      
327GND              U25   -CP37       A01X+142109Y+111630X0177Y    R180 S1      
327GND              U25   -CP39       A01X+141369Y+111630X0177Y    R180 S1      
327GND              U25   -CP42       A01X+140259Y+111630X0177Y    R180 S1      
327GND              U25   -CP45       A01X+139149Y+111630X0177Y    R180 S1      
327GND              U25   -CP48       A01X+138039Y+111630X0177Y    R180 S1      
327GND              U25   -CP51       A01X+136928Y+111630X0177Y    R180 S1      
327GND              U25   -CP54       A01X+135818Y+111630X0177Y    R180 S1      
327GND              U25   -CP57       A01X+134708Y+111630X0177Y    R180 S1      
327GND              U25   -CP59       A01X+133968Y+111630X0177Y    R180 S1      
327GND              U25   -CP61       A01X+133228Y+111630X0177Y    R180 S1      
327GND              U25   -CP64       A01X+132117Y+111630X0177Y    R180 S1      
327GND              U25   -CP66       A01X+131377Y+111630X0177Y    R180 S1      
327GND              U25   -CP68       A01X+130637Y+111630X0177Y    R180 S1      
327GND              U25   -CP71       A01X+129527Y+111630X0177Y    R180 S1      
327GND              U25   -CP73       A01X+128787Y+111630X0177Y    R180 S1      
327GND              U25   -CR1        A01X+155247Y+111949X0177Y    R180 S1      
327GND              U25   -CR4        A01X+154137Y+111949X0177Y    R180 S1      
327GND              U25   -CR6        A01X+153397Y+111949X0177Y    R180 S1      
327GND              U25   -CR8        A01X+152657Y+111949X0177Y    R180 S1      
327GND              U25   -CR11       A01X+151546Y+111949X0177Y    R180 S1      
327GND              U25   -CR13       A01X+150806Y+111949X0177Y    R180 S1      
327GND              U25   -CR15       A01X+150066Y+111949X0177Y    R180 S1      
327GND              U25   -CR18       A01X+148956Y+111949X0177Y    R180 S1      
327GND              U25   -CR20       A01X+148216Y+111949X0177Y    R180 S1      
327GND              U25   -CR22       A01X+147476Y+111949X0177Y    R180 S1      
327GND              U25   -CR25       A01X+146365Y+111949X0177Y    R180 S1      
327GND              U25   -CR28       A01X+145255Y+111949X0177Y    R180 S1      
327GND              U25   -CR31       A01X+144145Y+111949X0177Y    R180 S1      
327GND              U25   -CR34       A01X+143035Y+111949X0177Y    R180 S1      
327GND              U25   -CR35       A01X+142665Y+111949X0177Y    R180 S1      
327GND              U25   -CR36       A01X+142294Y+111949X0177Y    R180 S1      
327GND              U25   -CR40       A01X+141184Y+111949X0177Y    R180 S1      
327GND              U25   -CR41       A01X+140814Y+111949X0177Y    R180 S1      
327GND              U25   -CR42       A01X+140444Y+111949X0177Y    R180 S1      
327GND              U25   -CR45       A01X+139334Y+111949X0177Y    R180 S1      
327GND              U25   -CR48       A01X+138224Y+111949X0177Y    R180 S1      
327GND              U25   -CR51       A01X+137113Y+111949X0177Y    R180 S1      
327GND              U25   -CR54       A01X+136003Y+111949X0177Y    R180 S1      
327GND              U25   -CR56       A01X+135263Y+111949X0177Y    R180 S1      
327GND              U25   -CR58       A01X+134523Y+111949X0177Y    R180 S1      
327GND              U25   -CR61       A01X+133413Y+111949X0177Y    R180 S1      
327GND              U25   -CR63       A01X+132672Y+111949X0177Y    R180 S1      
327GND              U25   -CR65       A01X+131932Y+111949X0177Y    R180 S1      
327GND              U25   -CR68       A01X+130822Y+111949X0177Y    R180 S1      
327GND              U25   -CR70       A01X+130082Y+111949X0177Y    R180 S1      
327GND              U25   -CR72       A01X+129342Y+111949X0177Y    R180 S1      
327GND              U25   -CR75       A01X+128232Y+111949X0177Y    R180 S1      
327GND              U25   -CT3        A01X+154692Y+112268X0177Y    R180 S1      
327GND              U25   -CT8        A01X+152842Y+112268X0177Y    R180 S1      
327GND              U25   -CT10       A01X+152102Y+112268X0177Y    R180 S1      
327GND              U25   -CT15       A01X+150251Y+112268X0177Y    R180 S1      
327GND              U25   -CT17       A01X+149511Y+112268X0177Y    R180 S1      
327GND              U25   -CT23       A01X+147290Y+112268X0177Y    R180 S1      
327GND              U25   -CT24       A01X+146920Y+112268X0177Y    R180 S1      
327GND              U25   -CT25       A01X+146550Y+112268X0177Y    R180 S1      
327GND              U25   -CT26       A01X+146180Y+112268X0177Y    R180 S1      
327GND              U25   -CT27       A01X+145810Y+112268X0177Y    R180 S1      
327GND              U25   -CT28       A01X+145440Y+112268X0177Y    R180 S1      
327GND              U25   -CT29       A01X+145070Y+112268X0177Y    R180 S1      
327GND              U25   -CT30       A01X+144700Y+112268X0177Y    R180 S1      
327GND              U25   -CT31       A01X+144330Y+112268X0177Y    R180 S1      
327GND              U25   -CT32       A01X+143960Y+112268X0177Y    R180 S1      
327GND              U25   -CT33       A01X+143590Y+112268X0177Y    R180 S1      
327GND              U25   -CT34       A01X+143220Y+112268X0177Y    R180 S1      
327GND              U25   -CT37       A01X+142109Y+112268X0177Y    R180 S1      
327GND              U25   -CT39       A01X+141369Y+112268X0177Y    R180 S1      
327GND              U25   -CT42       A01X+140259Y+112268X0177Y    R180 S1      
327GND              U25   -CT43       A01X+139889Y+112268X0177Y    R180 S1      
327GND              U25   -CT44       A01X+139519Y+112268X0177Y    R180 S1      
327GND              U25   -CT45       A01X+139149Y+112268X0177Y    R180 S1      
327GND              U25   -CT46       A01X+138779Y+112268X0177Y    R180 S1      
327GND              U25   -CT47       A01X+138409Y+112268X0177Y    R180 S1      
327GND              U25   -CT48       A01X+138039Y+112268X0177Y    R180 S1      
327GND              U25   -CT49       A01X+137668Y+112268X0177Y    R180 S1      
327GND              U25   -CT50       A01X+137298Y+112268X0177Y    R180 S1      
327GND              U25   -CT51       A01X+136928Y+112268X0177Y    R180 S1      
327GND              U25   -CT53       A01X+136188Y+112268X0177Y    R180 S1      
327GND              U25   -CT59       A01X+133968Y+112268X0177Y    R180 S1      
327GND              U25   -CT61       A01X+133228Y+112268X0177Y    R180 S1      
327GND              U25   -CT66       A01X+131377Y+112268X0177Y    R180 S1      
327GND              U25   -CT68       A01X+130637Y+112268X0177Y    R180 S1      
327GND              U25   -CT73       A01X+128787Y+112268X0177Y    R180 S1      
327GND              U25   -CU1        A01X+155247Y+112587X0177Y    R180 S1      
327GND              U25   -CU4        A01X+154137Y+112587X0177Y    R180 S1      
327GND              U25   -CU6        A01X+153397Y+112587X0177Y    R180 S1      
327GND              U25   -CU8        A01X+152657Y+112587X0177Y    R180 S1      
327GND              U25   -CU11       A01X+151546Y+112587X0177Y    R180 S1      
327GND              U25   -CU13       A01X+150806Y+112587X0177Y    R180 S1      
327GND              U25   -CU15       A01X+150066Y+112587X0177Y    R180 S1      
327GND              U25   -CU18       A01X+148956Y+112587X0177Y    R180 S1      
327GND              U25   -CU20       A01X+148216Y+112587X0177Y    R180 S1      
327GND              U25   -CU22       A01X+147476Y+112587X0177Y    R180 S1      
327GND              U25   -CU25       A01X+146365Y+112587X0177Y    R180 S1      
327GND              U25   -CU28       A01X+145255Y+112587X0177Y    R180 S1      
327GND              U25   -CU31       A01X+144145Y+112587X0177Y    R180 S1      
327GND              U25   -CU34       A01X+143035Y+112587X0177Y    R180 S1      
327GND              U25   -CU42       A01X+140444Y+112587X0177Y    R180 S1      
327GND              U25   -CU45       A01X+139334Y+112587X0177Y    R180 S1      
327GND              U25   -CU48       A01X+138224Y+112587X0177Y    R180 S1      
327GND              U25   -CU51       A01X+137113Y+112587X0177Y    R180 S1      
327GND              U25   -CU54       A01X+136003Y+112587X0177Y    R180 S1      
327GND              U25   -CU56       A01X+135263Y+112587X0177Y    R180 S1      
327GND              U25   -CU61       A01X+133413Y+112587X0177Y    R180 S1      
327GND              U25   -CU63       A01X+132672Y+112587X0177Y    R180 S1      
327GND              U25   -CU65       A01X+131932Y+112587X0177Y    R180 S1      
327GND              U25   -CU68       A01X+130822Y+112587X0177Y    R180 S1      
327GND              U25   -CU70       A01X+130082Y+112587X0177Y    R180 S1      
327GND              U25   -CU72       A01X+129342Y+112587X0177Y    R180 S1      
327GND              U25   -CU75       A01X+128232Y+112587X0177Y    R180 S1      
327GND              U25   -CV3        A01X+154692Y+112906X0177Y    R180 S1      
327GND              U25   -CV5        A01X+153952Y+112906X0177Y    R180 S1      
327GND              U25   -CV8        A01X+152842Y+112906X0177Y    R180 S1      
327GND              U25   -CV12       A01X+151361Y+112906X0177Y    R180 S1      
327GND              U25   -CV17       A01X+149511Y+112906X0177Y    R180 S1      
327GND              U25   -CV22       A01X+147661Y+112906X0177Y    R180 S1      
327GND              U25   -CV25       A01X+146550Y+112906X0177Y    R180 S1      
327GND              U25   -CV28       A01X+145440Y+112906X0177Y    R180 S1      
327GND              U25   -CV31       A01X+144330Y+112906X0177Y    R180 S1      
327GND              U25   -CV37       A01X+142109Y+112906X0177Y    R180 S1      
327GND              U25   -CV39       A01X+141369Y+112906X0177Y    R180 S1      
327GND              U25   -CV45       A01X+139149Y+112906X0177Y    R180 S1      
327GND              U25   -CV48       A01X+138039Y+112906X0177Y    R180 S1      
327GND              U25   -CV54       A01X+135818Y+112906X0177Y    R180 S1      
327GND              U25   -CV57       A01X+134708Y+112906X0177Y    R180 S1      
327GND              U25   -CV59       A01X+133968Y+112906X0177Y    R180 S1      
327GND              U25   -CV64       A01X+132117Y+112906X0177Y    R180 S1      
327GND              U25   -CV68       A01X+130637Y+112906X0177Y    R180 S1      
327GND              U25   -CV71       A01X+129527Y+112906X0177Y    R180 S1      
327GND              U25   -CV73       A01X+128787Y+112906X0177Y    R180 S1      
327GND              U25   -CW1        A01X+155247Y+113224X0177Y    R180 S1      
327GND              U25   -CW6        A01X+153397Y+113224X0177Y    R180 S1      
327GND              U25   -CW8        A01X+152657Y+113224X0177Y    R180 S1      
327GND              U25   -CW13       A01X+150806Y+113224X0177Y    R180 S1      
327GND              U25   -CW20       A01X+148216Y+113224X0177Y    R180 S1      
327GND              U25   -CW22       A01X+147476Y+113224X0177Y    R180 S1      
327GND              U25   -CW25       A01X+146365Y+113224X0177Y    R180 S1      
327GND              U25   -CW28       A01X+145255Y+113224X0177Y    R180 S1      
327GND              U25   -CW31       A01X+144145Y+113224X0177Y    R180 S1      
327GND              U25   -CW34       A01X+143035Y+113224X0177Y    R180 S1      
327GND              U25   -CW35       A01X+142665Y+113224X0177Y    R180 S1      
327GND              U25   -CW36       A01X+142294Y+113224X0177Y    R180 S1      
327GND              U25   -CW40       A01X+141184Y+113224X0177Y    R180 S1      
327GND              U25   -CW41       A01X+140814Y+113224X0177Y    R180 S1      
327GND              U25   -CW42       A01X+140444Y+113224X0177Y    R180 S1      
327GND              U25   -CW45       A01X+139334Y+113224X0177Y    R180 S1      
327GND              U25   -CW48       A01X+138224Y+113224X0177Y    R180 S1      
327GND              U25   -CW51       A01X+137113Y+113224X0177Y    R180 S1      
327GND              U25   -CW54       A01X+136003Y+113224X0177Y    R180 S1      
327GND              U25   -CW56       A01X+135263Y+113224X0177Y    R180 S1      
327GND              U25   -CW61       A01X+133413Y+113224X0177Y    R180 S1      
327GND              U25   -CW63       A01X+132672Y+113224X0177Y    R180 S1      
327GND              U25   -CW68       A01X+130822Y+113224X0177Y    R180 S1      
327GND              U25   -CW70       A01X+130082Y+113224X0177Y    R180 S1      
327GND              U25   -CW75       A01X+128232Y+113224X0177Y    R180 S1      
327GND              U25   -CY3        A01X+154692Y+113543X0177Y    R180 S1      
327GND              U25   -CY5        A01X+153952Y+113543X0177Y    R180 S1      
327GND              U25   -CY8        A01X+152842Y+113543X0177Y    R180 S1      
327GND              U25   -CY10       A01X+152102Y+113543X0177Y    R180 S1      
327GND              U25   -CY12       A01X+151361Y+113543X0177Y    R180 S1      
327GND              U25   -CY15       A01X+150251Y+113543X0177Y    R180 S1      
327GND              U25   -CY17       A01X+149511Y+113543X0177Y    R180 S1      
327GND              U25   -CY19       A01X+148771Y+113543X0177Y    R180 S1      
327GND              U25   -CY23       A01X+147290Y+113543X0177Y    R180 S1      
327GND              U25   -CY24       A01X+146920Y+113543X0177Y    R180 S1      
327GND              U25   -CY25       A01X+146550Y+113543X0177Y    R180 S1      
327GND              U25   -CY26       A01X+146180Y+113543X0177Y    R180 S1      
327GND              U25   -CY27       A01X+145810Y+113543X0177Y    R180 S1      
327GND              U25   -CY28       A01X+145440Y+113543X0177Y    R180 S1      
327GND              U25   -CY29       A01X+145070Y+113543X0177Y    R180 S1      
327GND              U25   -CY30       A01X+144700Y+113543X0177Y    R180 S1      
327GND              U25   -CY31       A01X+144330Y+113543X0177Y    R180 S1      
327GND              U25   -CY32       A01X+143960Y+113543X0177Y    R180 S1      
327GND              U25   -CY33       A01X+143590Y+113543X0177Y    R180 S1      
327GND              U25   -CY34       A01X+143220Y+113543X0177Y    R180 S1      
327GND              U25   -CY37       A01X+142109Y+113543X0177Y    R180 S1      
327GND              U25   -CY39       A01X+141369Y+113543X0177Y    R180 S1      
327GND              U25   -CY42       A01X+140259Y+113543X0177Y    R180 S1      
327GND              U25   -CY43       A01X+139889Y+113543X0177Y    R180 S1      
327GND              U25   -CY44       A01X+139519Y+113543X0177Y    R180 S1      
327GND              U25   -CY45       A01X+139149Y+113543X0177Y    R180 S1      
327GND              U25   -CY46       A01X+138779Y+113543X0177Y    R180 S1      
327GND              U25   -CY47       A01X+138409Y+113543X0177Y    R180 S1      
327GND              U25   -CY48       A01X+138039Y+113543X0177Y    R180 S1      
327GND              U25   -CY49       A01X+137668Y+113543X0177Y    R180 S1      
327GND              U25   -CY50       A01X+137298Y+113543X0177Y    R180 S1      
327GND              U25   -CY51       A01X+136928Y+113543X0177Y    R180 S1      
327GND              U25   -CY52       A01X+136558Y+113543X0177Y    R180 S1      
327GND              U25   -CY53       A01X+136188Y+113543X0177Y    R180 S1      
327GND              U25   -CY59       A01X+133968Y+113543X0177Y    R180 S1      
327GND              U25   -CY61       A01X+133228Y+113543X0177Y    R180 S1      
327GND              U25   -CY64       A01X+132117Y+113543X0177Y    R180 S1      
327GND              U25   -CY66       A01X+131377Y+113543X0177Y    R180 S1      
327GND              U25   -CY68       A01X+130637Y+113543X0177Y    R180 S1      
327GND              U25   -CY71       A01X+129527Y+113543X0177Y    R180 S1      
327GND              U25   -CY73       A01X+128787Y+113543X0177Y    R180 S1      
327GND              U25   -DA1        A01X+155247Y+113862X0177Y    R180 S1      
327GND              U25   -DA4        A01X+154137Y+113862X0177Y    R180 S1      
327GND              U25   -DA6        A01X+153397Y+113862X0177Y    R180 S1      
327GND              U25   -DA8        A01X+152657Y+113862X0177Y    R180 S1      
327GND              U25   -DA11       A01X+151546Y+113862X0177Y    R180 S1      
327GND              U25   -DA13       A01X+150806Y+113862X0177Y    R180 S1      
327GND              U25   -DA15       A01X+150066Y+113862X0177Y    R180 S1      
327GND              U25   -DA18       A01X+148956Y+113862X0177Y    R180 S1      
327GND              U25   -DA20       A01X+148216Y+113862X0177Y    R180 S1      
327GND              U25   -DA22       A01X+147476Y+113862X0177Y    R180 S1      
327GND              U25   -DA25       A01X+146365Y+113862X0177Y    R180 S1      
327GND              U25   -DA28       A01X+145255Y+113862X0177Y    R180 S1      
327GND              U25   -DA31       A01X+144145Y+113862X0177Y    R180 S1      
327GND              U25   -DA34       A01X+143035Y+113862X0177Y    R180 S1      
327GND              U25   -DA42       A01X+140444Y+113862X0177Y    R180 S1      
327GND              U25   -DA45       A01X+139334Y+113862X0177Y    R180 S1      
327GND              U25   -DA48       A01X+138224Y+113862X0177Y    R180 S1      
327GND              U25   -DA51       A01X+137113Y+113862X0177Y    R180 S1      
327GND              U25   -DA54       A01X+136003Y+113862X0177Y    R180 S1      
327GND              U25   -DA58       A01X+134523Y+113862X0177Y    R180 S1      
327GND              U25   -DA61       A01X+133413Y+113862X0177Y    R180 S1      
327GND              U25   -DA63       A01X+132672Y+113862X0177Y    R180 S1      
327GND              U25   -DA65       A01X+131932Y+113862X0177Y    R180 S1      
327GND              U25   -DA68       A01X+130822Y+113862X0177Y    R180 S1      
327GND              U25   -DA70       A01X+130082Y+113862X0177Y    R180 S1      
327GND              U25   -AA42       A01X+140326Y+093807X0177Y    R180 S1      
327GND              U25   -AA72       A01X+129224Y+093807X0177Y    R180 S1      
327GND              U25   -AD31       A01X+144212Y+094764X0177Y    R180 S1      
327GND              U25   -AE4        A01X+154019Y+095083X0177Y    R180 S1      
327GND              U25   -AH33       A01X+143472Y+096039X0177Y    R180 S1      
327GND              U25   -AJ13       A01X+150688Y+096358X0177Y    R180 S1      
327GND              U25   -AM37       A01X+141991Y+097315X0177Y    R180 S1      
327GND              U25   -AN20       A01X+148098Y+097634X0177Y    R180 S1      
327GND              U25   -BV42       A01X+140259Y+106528X0177Y    R180 S1      
327GND              U25   -BW25       A01X+146365Y+106846X0177Y    R180 S1      
327GND              U25   -CB44       A01X+139519Y+107803X0177Y    R180 S1      
327GND              U25   -CC22       A01X+147476Y+108122X0177Y    R180 S1      
327GND              U25   -CF46       A01X+138779Y+109079X0177Y    R180 S1      
327GND              U25   -CG42       A01X+140444Y+109398X0177Y    R180 S1      
327GND              U25   -CK10       A01X+152102Y+110354X0177Y    R180 S1      
327GND              U25   -CK31       A01X+144330Y+110354X0177Y    R180 S1      
327GND              U25   -CM50       A01X+137298Y+110992X0177Y    R180 S1      
327GND              U25   -CN54       A01X+136003Y+111311X0177Y    R180 S1      
327GND              U25   -CT52       A01X+136558Y+112268X0177Y    R180 S1      
327GND              U25   -CU58       A01X+134523Y+112587X0177Y    R180 S1      
327GND              U25   -CY57       A01X+134708Y+113543X0177Y    R180 S1      
327GND              U25   -DA56       A01X+135263Y+113862X0177Y    R180 S1      
327GND              U25   -DA72       A01X+129342Y+113862X0177Y    R180 S1      
327GND              U25   -DA75       A01X+128232Y+113862X0177Y    R180 S1      
327GND              U25   -DB3        A01X+154692Y+114181X0177Y    R180 S1      
327GND              U25   -DB8        A01X+152842Y+114181X0177Y    R180 S1      
327GND              U25   -DB10       A01X+152102Y+114181X0177Y    R180 S1      
327GND              U25   -DB15       A01X+150251Y+114181X0177Y    R180 S1      
327GND              U25   -DB17       A01X+149511Y+114181X0177Y    R180 S1      
327GND              U25   -DB22       A01X+147661Y+114181X0177Y    R180 S1      
327GND              U25   -DB25       A01X+146550Y+114181X0177Y    R180 S1      
327GND              U25   -DB28       A01X+145440Y+114181X0177Y    R180 S1      
327GND              U25   -DB31       A01X+144330Y+114181X0177Y    R180 S1      
327GND              U25   -DB34       A01X+143220Y+114181X0177Y    R180 S1      
327GND              U25   -DB37       A01X+142109Y+114181X0177Y    R180 S1      
327GND              U25   -DB39       A01X+141369Y+114181X0177Y    R180 S1      
327GND              U25   -DB42       A01X+140259Y+114181X0177Y    R180 S1      
327GND              U25   -DB45       A01X+139149Y+114181X0177Y    R180 S1      
327GND              U25   -DB48       A01X+138039Y+114181X0177Y    R180 S1      
327GND              U25   -DB51       A01X+136928Y+114181X0177Y    R180 S1      
327GND              U25   -DB54       A01X+135818Y+114181X0177Y    R180 S1      
327GND              U25   -DB59       A01X+133968Y+114181X0177Y    R180 S1      
327GND              U25   -DB61       A01X+133228Y+114181X0177Y    R180 S1      
327GND              U25   -DB66       A01X+131377Y+114181X0177Y    R180 S1      
327GND              U25   -DB68       A01X+130637Y+114181X0177Y    R180 S1      
327GND              U25   -DB73       A01X+128787Y+114181X0177Y    R180 S1      
327GND              U25   -DC1        A01X+155247Y+114500X0177Y    R180 S1      
327GND              U25   -DC4        A01X+154137Y+114500X0177Y    R180 S1      
327GND              U25   -DC6        A01X+153397Y+114500X0177Y    R180 S1      
327GND              U25   -DC8        A01X+152657Y+114500X0177Y    R180 S1      
327GND              U25   -DC11       A01X+151546Y+114500X0177Y    R180 S1      
327GND              U25   -DC13       A01X+150806Y+114500X0177Y    R180 S1      
327GND              U25   -DC15       A01X+150066Y+114500X0177Y    R180 S1      
327GND              U25   -DC18       A01X+148956Y+114500X0177Y    R180 S1      
327GND              U25   -DC20       A01X+148216Y+114500X0177Y    R180 S1      
327GND              U25   -DC22       A01X+147476Y+114500X0177Y    R180 S1      
327GND              U25   -DC25       A01X+146365Y+114500X0177Y    R180 S1      
327GND              U25   -DC28       A01X+145255Y+114500X0177Y    R180 S1      
327GND              U25   -DC31       A01X+144145Y+114500X0177Y    R180 S1      
327GND              U25   -DC34       A01X+143035Y+114500X0177Y    R180 S1      
327GND              U25   -DC42       A01X+140444Y+114500X0177Y    R180 S1      
327GND              U25   -DC45       A01X+139334Y+114500X0177Y    R180 S1      
327GND              U25   -DC48       A01X+138224Y+114500X0177Y    R180 S1      
327GND              U25   -DC51       A01X+137113Y+114500X0177Y    R180 S1      
327GND              U25   -DC54       A01X+136003Y+114500X0177Y    R180 S1      
327GND              U25   -DC56       A01X+135263Y+114500X0177Y    R180 S1      
327GND              U25   -DC58       A01X+134523Y+114500X0177Y    R180 S1      
327GND              U25   -DC61       A01X+133413Y+114500X0177Y    R180 S1      
327GND              U25   -DC63       A01X+132672Y+114500X0177Y    R180 S1      
327GND              U25   -DC65       A01X+131932Y+114500X0177Y    R180 S1      
327GND              U25   -DC68       A01X+130822Y+114500X0177Y    R180 S1      
327GND              U25   -DC70       A01X+130082Y+114500X0177Y    R180 S1      
327GND              U25   -DC72       A01X+129342Y+114500X0177Y    R180 S1      
327GND              U25   -DC75       A01X+128232Y+114500X0177Y    R180 S1      
327GND              U25   -DD3        A01X+154692Y+114819X0177Y    R180 S1      
327GND              U25   -DD5        A01X+153952Y+114819X0177Y    R180 S1      
327GND              U25   -DD8        A01X+152842Y+114819X0177Y    R180 S1      
327GND              U25   -DD10       A01X+152102Y+114819X0177Y    R180 S1      
327GND              U25   -DD12       A01X+151361Y+114819X0177Y    R180 S1      
327GND              U25   -DD15       A01X+150251Y+114819X0177Y    R180 S1      
327GND              U25   -DD17       A01X+149511Y+114819X0177Y    R180 S1      
327GND              U25   -DD19       A01X+148771Y+114819X0177Y    R180 S1      
327GND              U25   -DD23       A01X+147290Y+114819X0177Y    R180 S1      
327GND              U25   -DD24       A01X+146920Y+114819X0177Y    R180 S1      
327GND              U25   -DD26       A01X+146180Y+114819X0177Y    R180 S1      
327GND              U25   -DD27       A01X+145810Y+114819X0177Y    R180 S1      
327GND              U25   -DD29       A01X+145070Y+114819X0177Y    R180 S1      
327GND              U25   -DD30       A01X+144700Y+114819X0177Y    R180 S1      
327GND              U25   -DD32       A01X+143960Y+114819X0177Y    R180 S1      
327GND              U25   -DD33       A01X+143590Y+114819X0177Y    R180 S1      
327GND              U25   -DD35       A01X+142850Y+114819X0177Y    R180 S1      
327GND              U25   -DD36       A01X+142480Y+114819X0177Y    R180 S1      
327GND              U25   -DD37       A01X+142109Y+114819X0177Y    R180 S1      
327GND              U25   -DD39       A01X+141369Y+114819X0177Y    R180 S1      
327GND              U25   -DD40       A01X+140999Y+114819X0177Y    R180 S1      
327GND              U25   -DD41       A01X+140629Y+114819X0177Y    R180 S1      
327GND              U25   -DD43       A01X+139889Y+114819X0177Y    R180 S1      
327GND              U25   -DD44       A01X+139519Y+114819X0177Y    R180 S1      
327GND              U25   -DD46       A01X+138779Y+114819X0177Y    R180 S1      
327GND              U25   -DD47       A01X+138409Y+114819X0177Y    R180 S1      
327GND              U25   -DD49       A01X+137668Y+114819X0177Y    R180 S1      
327GND              U25   -DD50       A01X+137298Y+114819X0177Y    R180 S1      
327GND              U25   -DD52       A01X+136558Y+114819X0177Y    R180 S1      
327GND              U25   -DD53       A01X+136188Y+114819X0177Y    R180 S1      
327GND              U25   -DD57       A01X+134708Y+114819X0177Y    R180 S1      
327GND              U25   -DD59       A01X+133968Y+114819X0177Y    R180 S1      
327GND              U25   -DD61       A01X+133228Y+114819X0177Y    R180 S1      
327GND              U25   -DD64       A01X+132117Y+114819X0177Y    R180 S1      
327GND              U25   -DD66       A01X+131377Y+114819X0177Y    R180 S1      
327GND              U25   -DD68       A01X+130637Y+114819X0177Y    R180 S1      
327GND              U25   -DD71       A01X+129527Y+114819X0177Y    R180 S1      
327GND              U25   -DD73       A01X+128787Y+114819X0177Y    R180 S1      
327GND              U25   -DE1        A01X+155247Y+115138X0177Y    R180 S1      
327GND              U25   -DE6        A01X+153397Y+115138X0177Y    R180 S1      
327GND              U25   -DE8        A01X+152657Y+115138X0177Y    R180 S1      
327GND              U25   -DE13       A01X+150806Y+115138X0177Y    R180 S1      
327GND              U25   -DE15       A01X+150066Y+115138X0177Y    R180 S1      
327GND              U25   -DE20       A01X+148216Y+115138X0177Y    R180 S1      
327GND              U25   -DE23       A01X+147106Y+115138X0177Y    R180 S1      
327GND              U25   -DE26       A01X+145995Y+115138X0177Y    R180 S1      
327GND              U25   -DE29       A01X+144885Y+115138X0177Y    R180 S1      
327GND              U25   -DE33       A01X+143405Y+115138X0177Y    R180 S1      
327GND              U25   -DE56       A01X+135263Y+115138X0177Y    R180 S1      
327GND              U25   -DE61       A01X+133413Y+115138X0177Y    R180 S1      
327GND              U25   -DE63       A01X+132672Y+115138X0177Y    R180 S1      
327GND              U25   -DE68       A01X+130822Y+115138X0177Y    R180 S1      
327GND              U25   -DE70       A01X+130082Y+115138X0177Y    R180 S1      
327GND              U25   -DE75       A01X+128232Y+115138X0177Y    R180 S1      
327GND              U25   -DF3        A01X+154692Y+115457X0177Y    R180 S1      
327GND              U25   -DF4        A01X+154322Y+115457X0177Y    R180 S1      
327GND              U25   -DF5        A01X+153952Y+115457X0177Y    R180 S1      
327GND              U25   -DF6        A01X+153582Y+115457X0177Y    R180 S1      
327GND              U25   -DF8        A01X+152842Y+115457X0177Y    R180 S1      
327GND              U25   -DF10       A01X+152102Y+115457X0177Y    R180 S1      
327GND              U25   -DF11       A01X+151732Y+115457X0177Y    R180 S1      
327GND              U25   -DF12       A01X+151361Y+115457X0177Y    R180 S1      
327GND              U25   -DF13       A01X+150991Y+115457X0177Y    R180 S1      
327GND              U25   -DF15       A01X+150251Y+115457X0177Y    R180 S1      
327GND              U25   -DF17       A01X+149511Y+115457X0177Y    R180 S1      
327GND              U25   -DF18       A01X+149141Y+115457X0177Y    R180 S1      
327GND              U25   -DF19       A01X+148771Y+115457X0177Y    R180 S1      
327GND              U25   -DF20       A01X+148401Y+115457X0177Y    R180 S1      
327GND              U25   -DF22       A01X+147661Y+115457X0177Y    R180 S1      
327GND              U25   -DF23       A01X+147290Y+115457X0177Y    R180 S1      
327GND              U25   -DF26       A01X+146180Y+115457X0177Y    R180 S1      
327GND              U25   -DF29       A01X+145070Y+115457X0177Y    R180 S1      
327GND              U25   -DF32       A01X+143960Y+115457X0177Y    R180 S1      
327GND              U25   -DF35       A01X+142850Y+115457X0177Y    R180 S1      
327GND              U25   -DF37       A01X+142109Y+115457X0177Y    R180 S1      
327GND              U25   -DF39       A01X+141369Y+115457X0177Y    R180 S1      
327GND              U25   -DF42       A01X+140259Y+115457X0177Y    R180 S1      
327GND              U25   -DF43       A01X+139889Y+115457X0177Y    R180 S1      
327GND              U25   -DF44       A01X+139519Y+115457X0177Y    R180 S1      
327GND              U25   -DF45       A01X+139149Y+115457X0177Y    R180 S1      
327GND              U25   -DF46       A01X+138779Y+115457X0177Y    R180 S1      
327GND              U25   -DF47       A01X+138409Y+115457X0177Y    R180 S1      
327GND              U25   -DF48       A01X+138039Y+115457X0177Y    R180 S1      
327GND              U25   -DF49       A01X+137668Y+115457X0177Y    R180 S1      
327GND              U25   -DF50       A01X+137298Y+115457X0177Y    R180 S1      
327GND              U25   -DF51       A01X+136928Y+115457X0177Y    R180 S1      
327GND              U25   -DF52       A01X+136558Y+115457X0177Y    R180 S1      
327GND              U25   -DF53       A01X+136188Y+115457X0177Y    R180 S1      
327GND              U25   -DF54       A01X+135818Y+115457X0177Y    R180 S1      
327GND              U25   -DF56       A01X+135078Y+115457X0177Y    R180 S1      
327GND              U25   -DF57       A01X+134708Y+115457X0177Y    R180 S1      
327GND              U25   -DF58       A01X+134338Y+115457X0177Y    R180 S1      
327GND              U25   -DF59       A01X+133968Y+115457X0177Y    R180 S1      
327GND              U25   -DF61       A01X+133228Y+115457X0177Y    R180 S1      
327GND              U25   -DF63       A01X+132487Y+115457X0177Y    R180 S1      
327GND              U25   -DF64       A01X+132117Y+115457X0177Y    R180 S1      
327GND              U25   -DF65       A01X+131747Y+115457X0177Y    R180 S1      
327GND              U25   -DF66       A01X+131377Y+115457X0177Y    R180 S1      
327GND              U25   -DF68       A01X+130637Y+115457X0177Y    R180 S1      
327GND              U25   -DF70       A01X+129897Y+115457X0177Y    R180 S1      
327GND              U25   -DF71       A01X+129527Y+115457X0177Y    R180 S1      
327GND              U25   -DF72       A01X+129157Y+115457X0177Y    R180 S1      
327GND              U25   -DF73       A01X+128787Y+115457X0177Y    R180 S1      
327GND              U25   -DG1        A01X+155247Y+115776X0177Y    R180 S1      
327GND              U25   -DG2        A01X+154877Y+115776X0177Y    R180 S1      
327GND              U25   -DG6        A01X+153397Y+115776X0177Y    R180 S1      
327GND              U25   -DG7        A01X+153027Y+115776X0177Y    R180 S1      
327GND              U25   -DG8        A01X+152657Y+115776X0177Y    R180 S1      
327GND              U25   -DG9        A01X+152287Y+115776X0177Y    R180 S1      
327GND              U25   -DG13       A01X+150806Y+115776X0177Y    R180 S1      
327GND              U25   -DG14       A01X+150436Y+115776X0177Y    R180 S1      
327GND              U25   -DG15       A01X+150066Y+115776X0177Y    R180 S1      
327GND              U25   -DG16       A01X+149696Y+115776X0177Y    R180 S1      
327GND              U25   -DG18       A01X+148956Y+115776X0177Y    R180 S1      
327GND              U25   -DG20       A01X+148216Y+115776X0177Y    R180 S1      
327GND              U25   -DG21       A01X+147846Y+115776X0177Y    R180 S1      
327GND              U25   -DG24       A01X+146735Y+115776X0177Y    R180 S1      
327GND              U25   -DG27       A01X+145625Y+115776X0177Y    R180 S1      
327GND              U25   -DG30       A01X+144515Y+115776X0177Y    R180 S1      
327GND              U25   -DG33       A01X+143405Y+115776X0177Y    R180 S1      
327GND              U25   -DG41       A01X+140814Y+115776X0177Y    R180 S1      
327GND              U25   -DG43       A01X+140074Y+115776X0177Y    R180 S1      
327GND              U25   -DG46       A01X+138964Y+115776X0177Y    R180 S1      
327GND              U25   -DG49       A01X+137854Y+115776X0177Y    R180 S1      
327GND              U25   -DG52       A01X+136743Y+115776X0177Y    R180 S1      
327GND              U25   -DG55       A01X+135633Y+115776X0177Y    R180 S1      
327GND              U25   -DG56       A01X+135263Y+115776X0177Y    R180 S1      
327GND              U25   -DG59       A01X+134153Y+115776X0177Y    R180 S1      
327GND              U25   -DG60       A01X+133783Y+115776X0177Y    R180 S1      
327GND              U25   -DG61       A01X+133413Y+115776X0177Y    R180 S1      
327GND              U25   -DG62       A01X+133042Y+115776X0177Y    R180 S1      
327GND              U25   -DG63       A01X+132672Y+115776X0177Y    R180 S1      
327GND              U25   -DG65       A01X+131932Y+115776X0177Y    R180 S1      
327GND              U25   -DG66       A01X+131562Y+115776X0177Y    R180 S1      
327GND              U25   -DG67       A01X+131192Y+115776X0177Y    R180 S1      
327GND              U25   -DG68       A01X+130822Y+115776X0177Y    R180 S1      
327GND              U25   -DG69       A01X+130452Y+115776X0177Y    R180 S1      
327GND              U25   -DG70       A01X+130082Y+115776X0177Y    R180 S1      
327GND              U25   -DG74       A01X+128602Y+115776X0177Y    R180 S1      
327GND              U25   -DG75       A01X+128232Y+115776X0177Y    R180 S1      
327GND              U25   -DH5        A01X+153952Y+116094X0177Y    R180 S1      
327GND              U25   -DH11       A01X+151732Y+116094X0177Y    R180 S1      
327GND              U25   -DH18       A01X+149141Y+116094X0177Y    R180 S1      
327GND              U25   -DH37       A01X+142109Y+116094X0177Y    R180 S1      
327GND              U25   -DH39       A01X+141369Y+116094X0177Y    R180 S1      
327GND              U25   -DH43       A01X+139889Y+116094X0177Y    R180 S1      
327GND              U25   -DH46       A01X+138779Y+116094X0177Y    R180 S1      
327GND              U25   -DH49       A01X+137668Y+116094X0177Y    R180 S1      
327GND              U25   -DH52       A01X+136558Y+116094X0177Y    R180 S1      
327GND              U25   -DH55       A01X+135448Y+116094X0177Y    R180 S1      
327GND              U25   -DH59       A01X+133968Y+116094X0177Y    R180 S1      
327GND              U25   -DH61       A01X+133228Y+116094X0177Y    R180 S1      
327GND              U25   -DH63       A01X+132487Y+116094X0177Y    R180 S1      
327GND              U25   -DH64       A01X+132117Y+116094X0177Y    R180 S1      
327GND              U25   -DH66       A01X+131377Y+116094X0177Y    R180 S1      
327GND              U25   -DH68       A01X+130637Y+116094X0177Y    R180 S1      
327GND              U25   -DH70       A01X+129897Y+116094X0177Y    R180 S1      
327GND              U25   -DJ7        A01X+153027Y+116413X0177Y    R180 S1      
327GND              U25   -DJ15       A01X+150066Y+116413X0177Y    R180 S1      
327GND              U25   -DJ19       A01X+148586Y+116413X0177Y    R180 S1      
327GND              U25   -DJ43       A01X+140074Y+116413X0177Y    R180 S1      
327GND              U25   -DJ49       A01X+137854Y+116413X0177Y    R180 S1      
327GND              U25   -DJ59       A01X+134153Y+116413X0177Y    R180 S1      
327GND              U25   -DJ61       A01X+133413Y+116413X0177Y    R180 S1      
327GND              U25   -DJ63       A01X+132672Y+116413X0177Y    R180 S1      
327GND              U25   -DJ66       A01X+131562Y+116413X0177Y    R180 S1      
327GND              U25   -DJ68       A01X+130822Y+116413X0177Y    R180 S1      
327GND              U25   -DJ73       A01X+128972Y+116413X0177Y    R180 S1      
327GND              U25   -K23        A01X+147172Y+090299X0177Y    R180 S1      
327GND              U25   -K59        A01X+133850Y+090299X0177Y    R180 S1      
327GND              U25   -P25        A01X+146432Y+091575X0177Y    R180 S1      
327GND              U25   -P68        A01X+130519Y+091575X0177Y    R180 S1      
327GND              U25   -V27        A01X+145692Y+092850X0177Y    R180 S1      
327GND              U25   -V68        A01X+130519Y+092850X0177Y    R180 S1      
327GND              U26   -DH8        A01X+055228Y+116095X0177Y    R180 S1      
327GND              U26   -A3         A01X+056775Y+087429X0177Y    R180 S1      
327GND              U26   -A9         A01X+054554Y+087429X0177Y    R180 S1      
327GND              U26   -A15        A01X+052334Y+087429X0177Y    R180 S1      
327GND              U26   -A21        A01X+050113Y+087429X0177Y    R180 S1      
327GND              U26   -A27        A01X+047893Y+087429X0177Y    R180 S1      
327GND              U26   -A43        A01X+042342Y+087429X0177Y    R180 S1      
327GND              U26   -A44        A01X+041972Y+087429X0177Y    R180 S1      
327GND              U26   -A47        A01X+040861Y+087429X0177Y    R180 S1      
327GND              U26   -A49        A01X+040121Y+087429X0177Y    R180 S1      
327GND              U26   -A53        A01X+038641Y+087429X0177Y    R180 S1      
327GND              U26   -A61        A01X+035680Y+087429X0177Y    R180 S1      
327GND              U26   -A67        A01X+033460Y+087429X0177Y    R180 S1      
327GND              U26   -A72        A01X+031609Y+087429X0177Y    R180 S1      
327GND              U26   -A73        A01X+031239Y+087429X0177Y    R180 S1      
327GND              U26   -B7         A01X+055480Y+087748X0177Y    R180 S1      
327GND              U26   -B8         A01X+055109Y+087748X0177Y    R180 S1      
327GND              U26   -B10        A01X+054369Y+087748X0177Y    R180 S1      
327GND              U26   -B11        A01X+053999Y+087748X0177Y    R180 S1      
327GND              U26   -B13        A01X+053259Y+087748X0177Y    R180 S1      
327GND              U26   -B18        A01X+051409Y+087748X0177Y    R180 S1      
327GND              U26   -B24        A01X+049188Y+087748X0177Y    R180 S1      
327GND              U26   -B27        A01X+048078Y+087748X0177Y    R180 S1      
327GND              U26   -B30        A01X+046968Y+087748X0177Y    R180 S1      
327GND              U26   -B33        A01X+045857Y+087748X0177Y    R180 S1      
327GND              U26   -B37        A01X+044377Y+087748X0177Y    R180 S1      
327GND              U26   -B39        A01X+043637Y+087748X0177Y    R180 S1      
327GND              U26   -B43        A01X+042157Y+087748X0177Y    R180 S1      
327GND              U26   -B46        A01X+041046Y+087748X0177Y    R180 S1      
327GND              U26   -B49        A01X+039936Y+087748X0177Y    R180 S1      
327GND              U26   -B52        A01X+038826Y+087748X0177Y    R180 S1      
327GND              U26   -B55        A01X+037716Y+087748X0177Y    R180 S1      
327GND              U26   -B59        A01X+036235Y+087748X0177Y    R180 S1      
327GND              U26   -B62        A01X+035125Y+087748X0177Y    R180 S1      
327GND              U26   -B65        A01X+034015Y+087748X0177Y    R180 S1      
327GND              U26   -B68        A01X+032905Y+087748X0177Y    R180 S1      
327GND              U26   -B70        A01X+032164Y+087748X0177Y    R180 S1      
327GND              U26   -C1         A01X+057515Y+088067X0177Y    R180 S1      
327GND              U26   -C5         A01X+056035Y+088067X0177Y    R180 S1      
327GND              U26   -C8         A01X+054924Y+088067X0177Y    R180 S1      
327GND              U26   -C10        A01X+054184Y+088067X0177Y    R180 S1      
327GND              U26   -C11        A01X+053814Y+088067X0177Y    R180 S1      
327GND              U26   -C13        A01X+053074Y+088067X0177Y    R180 S1      
327GND              U26   -C15        A01X+052334Y+088067X0177Y    R180 S1      
327GND              U26   -C21        A01X+050113Y+088067X0177Y    R180 S1      
327GND              U26   -C24        A01X+049003Y+088067X0177Y    R180 S1      
327GND              U26   -C27        A01X+047893Y+088067X0177Y    R180 S1      
327GND              U26   -C30        A01X+046783Y+088067X0177Y    R180 S1      
327GND              U26   -C36        A01X+044562Y+088067X0177Y    R180 S1      
327GND              U26   -C40        A01X+043452Y+088067X0177Y    R180 S1      
327GND              U26   -C43        A01X+042342Y+088067X0177Y    R180 S1      
327GND              U26   -C46        A01X+041232Y+088067X0177Y    R180 S1      
327GND              U26   -C49        A01X+040121Y+088067X0177Y    R180 S1      
327GND              U26   -C52        A01X+039011Y+088067X0177Y    R180 S1      
327GND              U26   -C55        A01X+037901Y+088067X0177Y    R180 S1      
327GND              U26   -C56        A01X+037531Y+088067X0177Y    R180 S1      
327GND              U26   -C57        A01X+037161Y+088067X0177Y    R180 S1      
327GND              U26   -C61        A01X+035680Y+088067X0177Y    R180 S1      
327GND              U26   -C64        A01X+034570Y+088067X0177Y    R180 S1      
327GND              U26   -C67        A01X+033460Y+088067X0177Y    R180 S1      
327GND              U26   -C69        A01X+032720Y+088067X0177Y    R180 S1      
327GND              U26   -C71        A01X+031980Y+088067X0177Y    R180 S1      
327GND              U26   -C73        A01X+031239Y+088067X0177Y    R180 S1      
327GND              U26   -C75        A01X+030499Y+088067X0177Y    R180 S1      
327GND              U26   -D2         A01X+057330Y+088386X0177Y    R180 S1      
327GND              U26   -D3         A01X+056960Y+088386X0177Y    R180 S1      
327GND              U26   -D5         A01X+056220Y+088386X0177Y    R180 S1      
327GND              U26   -D6         A01X+055850Y+088386X0177Y    R180 S1      
327GND              U26   -D9         A01X+054739Y+088386X0177Y    R180 S1      
327GND              U26   -D10        A01X+054369Y+088386X0177Y    R180 S1      
327GND              U26   -D12        A01X+053629Y+088386X0177Y    R180 S1      
327GND              U26   -D13        A01X+053259Y+088386X0177Y    R180 S1      
327GND              U26   -D16        A01X+052149Y+088386X0177Y    R180 S1      
327GND              U26   -D17        A01X+051779Y+088386X0177Y    R180 S1      
327GND              U26   -D19        A01X+051038Y+088386X0177Y    R180 S1      
327GND              U26   -D20        A01X+050668Y+088386X0177Y    R180 S1      
327GND              U26   -D21        A01X+050298Y+088386X0177Y    R180 S1      
327GND              U26   -D24        A01X+049188Y+088386X0177Y    R180 S1      
327GND              U26   -D25        A01X+048818Y+088386X0177Y    R180 S1      
327GND              U26   -D26        A01X+048448Y+088386X0177Y    R180 S1      
327GND              U26   -D27        A01X+048078Y+088386X0177Y    R180 S1      
327GND              U26   -D28        A01X+047708Y+088386X0177Y    R180 S1      
327GND              U26   -D29        A01X+047338Y+088386X0177Y    R180 S1      
327GND              U26   -D30        A01X+046968Y+088386X0177Y    R180 S1      
327GND              U26   -D31        A01X+046598Y+088386X0177Y    R180 S1      
327GND              U26   -D35        A01X+045117Y+088386X0177Y    R180 S1      
327GND              U26   -D37        A01X+044377Y+088386X0177Y    R180 S1      
327GND              U26   -D39        A01X+043637Y+088386X0177Y    R180 S1      
327GND              U26   -D40 M      A01X+043267Y+088386X0177Y    R180 S1      
327GND              U26   -D41        A01X+042897Y+088386X0177Y    R180 S1      
327GND              U26   -D42        A01X+042527Y+088386X0177Y    R180 S1      
327GND              U26   -D43        A01X+042157Y+088386X0177Y    R180 S1      
327GND              U26   -D44        A01X+041787Y+088386X0177Y    R180 S1      
327GND              U26   -D45        A01X+041416Y+088386X0177Y    R180 S1      
327GND              U26   -D46        A01X+041046Y+088386X0177Y    R180 S1      
327GND              U26   -D47        A01X+040676Y+088386X0177Y    R180 S1      
327GND              U26   -D48        A01X+040306Y+088386X0177Y    R180 S1      
327GND              U26   -D49        A01X+039936Y+088386X0177Y    R180 S1      
327GND              U26   -D50        A01X+039566Y+088386X0177Y    R180 S1      
327GND              U26   -D51        A01X+039196Y+088386X0177Y    R180 S1      
327GND              U26   -D52        A01X+038826Y+088386X0177Y    R180 S1      
327GND              U26   -D53        A01X+038456Y+088386X0177Y    R180 S1      
327GND              U26   -D54        A01X+038086Y+088386X0177Y    R180 S1      
327GND              U26   -D57        A01X+036976Y+088386X0177Y    R180 S1      
327GND              U26   -D59        A01X+036235Y+088386X0177Y    R180 S1      
327GND              U26   -D60        A01X+035865Y+088386X0177Y    R180 S1      
327GND              U26   -D61        A01X+035495Y+088386X0177Y    R180 S1      
327GND              U26   -D63        A01X+034755Y+088386X0177Y    R180 S1      
327GND              U26   -D64        A01X+034385Y+088386X0177Y    R180 S1      
327GND              U26   -D66        A01X+033645Y+088386X0177Y    R180 S1      
327GND              U26   -D67        A01X+033275Y+088386X0177Y    R180 S1      
327GND              U26   -D70        A01X+032164Y+088386X0177Y    R180 S1      
327GND              U26   -D71        A01X+031794Y+088386X0177Y    R180 S1      
327GND              U26   -D73        A01X+031054Y+088386X0177Y    R180 S1      
327GND              U26   -D74        A01X+030684Y+088386X0177Y    R180 S1      
327GND              U26   -E1         A01X+057515Y+088705X0177Y    R180 S1      
327GND              U26   -E3         A01X+056775Y+088705X0177Y    R180 S1      
327GND              U26   -E6         A01X+055664Y+088705X0177Y    R180 S1      
327GND              U26   -E7         A01X+055294Y+088705X0177Y    R180 S1      
327GND              U26   -E8         A01X+054924Y+088705X0177Y    R180 S1      
327GND              U26   -E10        A01X+054184Y+088705X0177Y    R180 S1      
327GND              U26   -E13        A01X+053074Y+088705X0177Y    R180 S1      
327GND              U26   -E14        A01X+052704Y+088705X0177Y    R180 S1      
327GND              U26   -E15        A01X+052334Y+088705X0177Y    R180 S1      
327GND              U26   -E17        A01X+051594Y+088705X0177Y    R180 S1      
327GND              U26   -E18        A01X+051224Y+088705X0177Y    R180 S1      
327GND              U26   -E20        A01X+050483Y+088705X0177Y    R180 S1      
327GND              U26   -E21        A01X+050113Y+088705X0177Y    R180 S1      
327GND              U26   -E52        A01X+039011Y+088705X0177Y    R180 S1      
327GND              U26   -E53        A01X+038641Y+088705X0177Y    R180 S1      
327GND              U26   -E55        A01X+037901Y+088705X0177Y    R180 S1      
327GND              U26   -E56        A01X+037531Y+088705X0177Y    R180 S1      
327GND              U26   -E58        A01X+036790Y+088705X0177Y    R180 S1      
327GND              U26   -E59        A01X+036420Y+088705X0177Y    R180 S1      
327GND              U26   -E61        A01X+035680Y+088705X0177Y    R180 S1      
327GND              U26   -E62        A01X+035310Y+088705X0177Y    R180 S1      
327GND              U26   -E63        A01X+034940Y+088705X0177Y    R180 S1      
327GND              U26   -E65        A01X+034200Y+088705X0177Y    R180 S1      
327GND              U26   -E66        A01X+033830Y+088705X0177Y    R180 S1      
327GND              U26   -E68        A01X+033090Y+088705X0177Y    R180 S1      
327GND              U26   -E69        A01X+032720Y+088705X0177Y    R180 S1      
327GND              U26   -E70        A01X+032350Y+088705X0177Y    R180 S1      
327GND              U26   -E72        A01X+031609Y+088705X0177Y    R180 S1      
327GND              U26   -E73        A01X+031239Y+088705X0177Y    R180 S1      
327GND              U26   -E75        A01X+030499Y+088705X0177Y    R180 S1      
327GND              U26   -F3         A01X+056960Y+089024X0177Y    R180 S1      
327GND              U26   -F5         A01X+056220Y+089024X0177Y    R180 S1      
327GND              U26   -F8         A01X+055109Y+089024X0177Y    R180 S1      
327GND              U26   -F10        A01X+054369Y+089024X0177Y    R180 S1      
327GND              U26   -F12        A01X+053629Y+089024X0177Y    R180 S1      
327GND              U26   -F15        A01X+052519Y+089024X0177Y    R180 S1      
327GND              U26   -F17        A01X+051779Y+089024X0177Y    R180 S1      
327GND              U26   -F19        A01X+051038Y+089024X0177Y    R180 S1      
327GND              U26   -F23        A01X+049558Y+089024X0177Y    R180 S1      
327GND              U26   -F24        A01X+049188Y+089024X0177Y    R180 S1      
327GND              U26   -F26        A01X+048448Y+089024X0177Y    R180 S1      
327GND              U26   -F27        A01X+048078Y+089024X0177Y    R180 S1      
327GND              U26   -F29        A01X+047338Y+089024X0177Y    R180 S1      
327GND              U26   -F30        A01X+046968Y+089024X0177Y    R180 S1      
327GND              U26   -F32        A01X+046228Y+089024X0177Y    R180 S1      
327GND              U26   -F33        A01X+045857Y+089024X0177Y    R180 S1      
327GND              U26   -F35        A01X+045117Y+089024X0177Y    R180 S1      
327GND              U26   -F36        A01X+044747Y+089024X0177Y    R180 S1      
327GND              U26   -F37        A01X+044377Y+089024X0177Y    R180 S1      
327GND              U26   -F39        A01X+043637Y+089024X0177Y    R180 S1      
327GND              U26   -F40        A01X+043267Y+089024X0177Y    R180 S1      
327GND              U26   -F41        A01X+042897Y+089024X0177Y    R180 S1      
327GND              U26   -F43        A01X+042157Y+089024X0177Y    R180 S1      
327GND              U26   -F44        A01X+041787Y+089024X0177Y    R180 S1      
327GND              U26   -F46        A01X+041046Y+089024X0177Y    R180 S1      
327GND              U26   -F47        A01X+040676Y+089024X0177Y    R180 S1      
327GND              U26   -F49        A01X+039936Y+089024X0177Y    R180 S1      
327GND              U26   -F50        A01X+039566Y+089024X0177Y    R180 S1      
327GND              U26   -F52        A01X+038826Y+089024X0177Y    R180 S1      
327GND              U26   -F53        A01X+038456Y+089024X0177Y    R180 S1      
327GND              U26   -F57        A01X+036976Y+089024X0177Y    R180 S1      
327GND              U26   -F59        A01X+036235Y+089024X0177Y    R180 S1      
327GND              U26   -F61        A01X+035495Y+089024X0177Y    R180 S1      
327GND              U26   -F64        A01X+034385Y+089024X0177Y    R180 S1      
327GND              U26   -F66        A01X+033645Y+089024X0177Y    R180 S1      
327GND              U26   -F68        A01X+032905Y+089024X0177Y    R180 S1      
327GND              U26   -F71        A01X+031794Y+089024X0177Y    R180 S1      
327GND              U26   -F73        A01X+031054Y+089024X0177Y    R180 S1      
327GND              U26   -G1         A01X+057515Y+089343X0177Y    R180 S1      
327GND              U26   -G4         A01X+056405Y+089343X0177Y    R180 S1      
327GND              U26   -G6         A01X+055664Y+089343X0177Y    R180 S1      
327GND              U26   -G8         A01X+054924Y+089343X0177Y    R180 S1      
327GND              U26   -G11        A01X+053814Y+089343X0177Y    R180 S1      
327GND              U26   -G13        A01X+053074Y+089343X0177Y    R180 S1      
327GND              U26   -G15        A01X+052334Y+089343X0177Y    R180 S1      
327GND              U26   -G18        A01X+051224Y+089343X0177Y    R180 S1      
327GND              U26   -G20        A01X+050483Y+089343X0177Y    R180 S1      
327GND              U26   -G22        A01X+049743Y+089343X0177Y    R180 S1      
327GND              U26   -G25        A01X+048633Y+089343X0177Y    R180 S1      
327GND              U26   -G28        A01X+047523Y+089343X0177Y    R180 S1      
327GND              U26   -G31        A01X+046413Y+089343X0177Y    R180 S1      
327GND              U26   -G34        A01X+045302Y+089343X0177Y    R180 S1      
327GND              U26   -G42        A01X+042712Y+089343X0177Y    R180 S1      
327GND              U26   -G45        A01X+041602Y+089343X0177Y    R180 S1      
327GND              U26   -G48        A01X+040491Y+089343X0177Y    R180 S1      
327GND              U26   -G51        A01X+039381Y+089343X0177Y    R180 S1      
327GND              U26   -G54        A01X+038271Y+089343X0177Y    R180 S1      
327GND              U26   -G56        A01X+037531Y+089343X0177Y    R180 S1      
327GND              U26   -G58        A01X+036790Y+089343X0177Y    R180 S1      
327GND              U26   -G61        A01X+035680Y+089343X0177Y    R180 S1      
327GND              U26   -G63        A01X+034940Y+089343X0177Y    R180 S1      
327GND              U26   -G65        A01X+034200Y+089343X0177Y    R180 S1      
327GND              U26   -G68        A01X+033090Y+089343X0177Y    R180 S1      
327GND              U26   -G70        A01X+032350Y+089343X0177Y    R180 S1      
327GND              U26   -G72        A01X+031609Y+089343X0177Y    R180 S1      
327GND              U26   -G75        A01X+030499Y+089343X0177Y    R180 S1      
327GND              U26   -H3         A01X+056960Y+089662X0177Y    R180 S1      
327GND              U26   -H8         A01X+055109Y+089662X0177Y    R180 S1      
327GND              U26   -H10        A01X+054369Y+089662X0177Y    R180 S1      
327GND              U26   -H15        A01X+052519Y+089662X0177Y    R180 S1      
327GND              U26   -H17        A01X+051779Y+089662X0177Y    R180 S1      
327GND              U26   -H22        A01X+049928Y+089662X0177Y    R180 S1      
327GND              U26   -H25        A01X+048818Y+089662X0177Y    R180 S1      
327GND              U26   -H28        A01X+047708Y+089662X0177Y    R180 S1      
327GND              U26   -H31        A01X+046598Y+089662X0177Y    R180 S1      
327GND              U26   -H34        A01X+045487Y+089662X0177Y    R180 S1      
327GND              U26   -H37        A01X+044377Y+089662X0177Y    R180 S1      
327GND              U26   -H39        A01X+043637Y+089662X0177Y    R180 S1      
327GND              U26   -H42        A01X+042527Y+089662X0177Y    R180 S1      
327GND              U26   -H45        A01X+041416Y+089662X0177Y    R180 S1      
327GND              U26   -H48        A01X+040306Y+089662X0177Y    R180 S1      
327GND              U26   -H51        A01X+039196Y+089662X0177Y    R180 S1      
327GND              U26   -H54        A01X+038086Y+089662X0177Y    R180 S1      
327GND              U26   -H59        A01X+036235Y+089662X0177Y    R180 S1      
327GND              U26   -H61        A01X+035495Y+089662X0177Y    R180 S1      
327GND              U26   -H66        A01X+033645Y+089662X0177Y    R180 S1      
327GND              U26   -H68        A01X+032905Y+089662X0177Y    R180 S1      
327GND              U26   -H73        A01X+031054Y+089662X0177Y    R180 S1      
327GND              U26   -J1         A01X+057515Y+089980X0177Y    R180 S1      
327GND              U26   -J4         A01X+056405Y+089980X0177Y    R180 S1      
327GND              U26   -J6         A01X+055664Y+089980X0177Y    R180 S1      
327GND              U26   -J8         A01X+054924Y+089980X0177Y    R180 S1      
327GND              U26   -J11        A01X+053814Y+089980X0177Y    R180 S1      
327GND              U26   -J13        A01X+053074Y+089980X0177Y    R180 S1      
327GND              U26   -AW63       A01X+034940Y+099547X0177Y    R180 S1      
327GND              U26   -AW65       A01X+034200Y+099547X0177Y    R180 S1      
327GND              U26   -AW68       A01X+033090Y+099547X0177Y    R180 S1      
327GND              U26   -AW70       A01X+032350Y+099547X0177Y    R180 S1      
327GND              U26   -AW72       A01X+031609Y+099547X0177Y    R180 S1      
327GND              U26   -AW75       A01X+030499Y+099547X0177Y    R180 S1      
327GND              U26   -AY3        A01X+056960Y+099866X0177Y    R180 S1      
327GND              U26   -AY5        A01X+056220Y+099866X0177Y    R180 S1      
327GND              U26   -AY8        A01X+055109Y+099866X0177Y    R180 S1      
327GND              U26   -AY10       A01X+054369Y+099866X0177Y    R180 S1      
327GND              U26   -AY12       A01X+053629Y+099866X0177Y    R180 S1      
327GND              U26   -AY15       A01X+052519Y+099866X0177Y    R180 S1      
327GND              U26   -AY17       A01X+051779Y+099866X0177Y    R180 S1      
327GND              U26   -AY19       A01X+051038Y+099866X0177Y    R180 S1      
327GND              U26   -AY23       A01X+049558Y+099866X0177Y    R180 S1      
327GND              U26   -AY25       A01X+048818Y+099866X0177Y    R180 S1      
327GND              U26   -AY27       A01X+048078Y+099866X0177Y    R180 S1      
327GND              U26   -AY48       A01X+040306Y+099866X0177Y    R180 S1      
327GND              U26   -AY50       A01X+039566Y+099866X0177Y    R180 S1      
327GND              U26   -AY52       A01X+038826Y+099866X0177Y    R180 S1      
327GND              U26   -AY54       A01X+038086Y+099866X0177Y    R180 S1      
327GND              U26   -AY57       A01X+036976Y+099866X0177Y    R180 S1      
327GND              U26   -AY59       A01X+036235Y+099866X0177Y    R180 S1      
327GND              U26   -AY61       A01X+035495Y+099866X0177Y    R180 S1      
327GND              U26   -AY64       A01X+034385Y+099866X0177Y    R180 S1      
327GND              U26   -AY66       A01X+033645Y+099866X0177Y    R180 S1      
327GND              U26   -AY68       A01X+032905Y+099866X0177Y    R180 S1      
327GND              U26   -AY71       A01X+031794Y+099866X0177Y    R180 S1      
327GND              U26   -AY73       A01X+031054Y+099866X0177Y    R180 S1      
327GND              U26   -BA1        A01X+057515Y+100185X0177Y    R180 S1      
327GND              U26   -BA6        A01X+055664Y+100185X0177Y    R180 S1      
327GND              U26   -BA8        A01X+054924Y+100185X0177Y    R180 S1      
327GND              U26   -BA13       A01X+053074Y+100185X0177Y    R180 S1      
327GND              U26   -BA15       A01X+052334Y+100185X0177Y    R180 S1      
327GND              U26   -BA20       A01X+050483Y+100185X0177Y    R180 S1      
327GND              U26   -BA22       A01X+049743Y+100185X0177Y    R180 S1      
327GND              U26   -BA24       A01X+049003Y+100185X0177Y    R180 S1      
327GND              U26   -BA26       A01X+048263Y+100185X0177Y    R180 S1      
327GND              U26   -BA28       A01X+047523Y+100185X0177Y    R180 S1      
327GND              U26   -BA49       A01X+040121Y+100185X0177Y    R180 S1      
327GND              U26   -BA51       A01X+039381Y+100185X0177Y    R180 S1      
327GND              U26   -BA53       A01X+038641Y+100185X0177Y    R180 S1      
327GND              U26   -BA56       A01X+037531Y+100185X0177Y    R180 S1      
327GND              U26   -BA61       A01X+035680Y+100185X0177Y    R180 S1      
327GND              U26   -BA63       A01X+034940Y+100185X0177Y    R180 S1      
327GND              U26   -BA68       A01X+033090Y+100185X0177Y    R180 S1      
327GND              U26   -BA70       A01X+032350Y+100185X0177Y    R180 S1      
327GND              U26   -BA75       A01X+030499Y+100185X0177Y    R180 S1      
327GND              U26   -BB3        A01X+056960Y+100504X0177Y    R180 S1      
327GND              U26   -BB5        A01X+056220Y+100504X0177Y    R180 S1      
327GND              U26   -BB8        A01X+055109Y+100504X0177Y    R180 S1      
327GND              U26   -BB10       A01X+054369Y+100504X0177Y    R180 S1      
327GND              U26   -BB12       A01X+053629Y+100504X0177Y    R180 S1      
327GND              U26   -BB15       A01X+052519Y+100504X0177Y    R180 S1      
327GND              U26   -BB17       A01X+051779Y+100504X0177Y    R180 S1      
327GND              U26   -BB19       A01X+051038Y+100504X0177Y    R180 S1      
327GND              U26   -BB23       A01X+049558Y+100504X0177Y    R180 S1      
327GND              U26   -BB25       A01X+048818Y+100504X0177Y    R180 S1      
327GND              U26   -BB27       A01X+048078Y+100504X0177Y    R180 S1      
327GND              U26   -BB48       A01X+040306Y+100504X0177Y    R180 S1      
327GND              U26   -BB50       A01X+039566Y+100504X0177Y    R180 S1      
327GND              U26   -BB52       A01X+038826Y+100504X0177Y    R180 S1      
327GND              U26   -BB54       A01X+038086Y+100504X0177Y    R180 S1      
327GND              U26   -BB57       A01X+036976Y+100504X0177Y    R180 S1      
327GND              U26   -BB59       A01X+036235Y+100504X0177Y    R180 S1      
327GND              U26   -BB61       A01X+035495Y+100504X0177Y    R180 S1      
327GND              U26   -BB64       A01X+034385Y+100504X0177Y    R180 S1      
327GND              U26   -BB66       A01X+033645Y+100504X0177Y    R180 S1      
327GND              U26   -BB68       A01X+032905Y+100504X0177Y    R180 S1      
327GND              U26   -BB71       A01X+031794Y+100504X0177Y    R180 S1      
327GND              U26   -BB73       A01X+031054Y+100504X0177Y    R180 S1      
327GND              U26   -BC1        A01X+057515Y+100823X0177Y    R180 S1      
327GND              U26   -BC4        A01X+056405Y+100823X0177Y    R180 S1      
327GND              U26   -BC6        A01X+055664Y+100823X0177Y    R180 S1      
327GND              U26   -BC8        A01X+054924Y+100823X0177Y    R180 S1      
327GND              U26   -BC11       A01X+053814Y+100823X0177Y    R180 S1      
327GND              U26   -BC13       A01X+053074Y+100823X0177Y    R180 S1      
327GND              U26   -BC15       A01X+052334Y+100823X0177Y    R180 S1      
327GND              U26   -BC18       A01X+051224Y+100823X0177Y    R180 S1      
327GND              U26   -BC20       A01X+050483Y+100823X0177Y    R180 S1      
327GND              U26   -BC22       A01X+049743Y+100823X0177Y    R180 S1      
327GND              U26   -BC24       A01X+049003Y+100823X0177Y    R180 S1      
327GND              U26   -BC26       A01X+048263Y+100823X0177Y    R180 S1      
327GND              U26   -BC28       A01X+047523Y+100823X0177Y    R180 S1      
327GND              U26   -BC49       A01X+040121Y+100823X0177Y    R180 S1      
327GND              U26   -BC50       A01X+039751Y+100823X0177Y    R180 S1      
327GND              U26   -BC51       A01X+039381Y+100823X0177Y    R180 S1      
327GND              U26   -BC53       A01X+038641Y+100823X0177Y    R180 S1      
327GND              U26   -BC56       A01X+037531Y+100823X0177Y    R180 S1      
327GND              U26   -BC58       A01X+036790Y+100823X0177Y    R180 S1      
327GND              U26   -BC61       A01X+035680Y+100823X0177Y    R180 S1      
327GND              U26   -BC63       A01X+034940Y+100823X0177Y    R180 S1      
327GND              U26   -BC65       A01X+034200Y+100823X0177Y    R180 S1      
327GND              U26   -BC68       A01X+033090Y+100823X0177Y    R180 S1      
327GND              U26   -BC70       A01X+032350Y+100823X0177Y    R180 S1      
327GND              U26   -BC72       A01X+031609Y+100823X0177Y    R180 S1      
327GND              U26   -BC75       A01X+030499Y+100823X0177Y    R180 S1      
327GND              U26   -BD3        A01X+056960Y+101142X0177Y    R180 S1      
327GND              U26   -BD8        A01X+055109Y+101142X0177Y    R180 S1      
327GND              U26   -BD10       A01X+054369Y+101142X0177Y    R180 S1      
327GND              U26   -BD15       A01X+052519Y+101142X0177Y    R180 S1      
327GND              U26   -BD17       A01X+051779Y+101142X0177Y    R180 S1      
327GND              U26   -BD23       A01X+049558Y+101142X0177Y    R180 S1      
327GND              U26   -BD25       A01X+048818Y+101142X0177Y    R180 S1      
327GND              U26   -BD27       A01X+048078Y+101142X0177Y    R180 S1      
327GND              U26   -BD49       A01X+039936Y+101142X0177Y    R180 S1      
327GND              U26   -BD51       A01X+039196Y+101142X0177Y    R180 S1      
327GND              U26   -BD53       A01X+038456Y+101142X0177Y    R180 S1      
327GND              U26   -BD57       A01X+036976Y+101142X0177Y    R180 S1      
327GND              U26   -BD59       A01X+036235Y+101142X0177Y    R180 S1      
327GND              U26   -BD61       A01X+035495Y+101142X0177Y    R180 S1      
327GND              U26   -BD64       A01X+034385Y+101142X0177Y    R180 S1      
327GND              U26   -BD66       A01X+033645Y+101142X0177Y    R180 S1      
327GND              U26   -BD68       A01X+032905Y+101142X0177Y    R180 S1      
327GND              U26   -BD71       A01X+031794Y+101142X0177Y    R180 S1      
327GND              U26   -BD73       A01X+031054Y+101142X0177Y    R180 S1      
327GND              U26   -BF3        A01X+057078Y+102701X0177Y    R180 S1      
327GND              U26   -BF5        A01X+056338Y+102701X0177Y    R180 S1      
327GND              U26   -BF8        A01X+055228Y+102701X0177Y    R180 S1      
327GND              U26   -BF10       A01X+054487Y+102701X0177Y    R180 S1      
327GND              U26   -BF12       A01X+053747Y+102701X0177Y    R180 S1      
327GND              U26   -BF15       A01X+052637Y+102701X0177Y    R180 S1      
327GND              U26   -BF17       A01X+051897Y+102701X0177Y    R180 S1      
327GND              U26   -BF19       A01X+051157Y+102701X0177Y    R180 S1      
327GND              U26   -BF22       A01X+050046Y+102701X0177Y    R180 S1      
327GND              U26   -BF24       A01X+049306Y+102701X0177Y    R180 S1      
327GND              U26   -BF26       A01X+048566Y+102701X0177Y    R180 S1      
327GND              U26   -BF28       A01X+047826Y+102701X0177Y    R180 S1      
327GND              U26   -BF49       A01X+040054Y+102701X0177Y    R180 S1      
327GND              U26   -BF50       A01X+039684Y+102701X0177Y    R180 S1      
327GND              U26   -BF52       A01X+038944Y+102701X0177Y    R180 S1      
327GND              U26   -BF54       A01X+038204Y+102701X0177Y    R180 S1      
327GND              U26   -BF59       A01X+036354Y+102701X0177Y    R180 S1      
327GND              U26   -BF61       A01X+035613Y+102701X0177Y    R180 S1      
327GND              U26   -BF66       A01X+033763Y+102701X0177Y    R180 S1      
327GND              U26   -BF68       A01X+033023Y+102701X0177Y    R180 S1      
327GND              U26   -BF73       A01X+031172Y+102701X0177Y    R180 S1      
327GND              U26   -BG1        A01X+057633Y+103020X0177Y    R180 S1      
327GND              U26   -BG4        A01X+056523Y+103020X0177Y    R180 S1      
327GND              U26   -BG6        A01X+055783Y+103020X0177Y    R180 S1      
327GND              U26   -BG8        A01X+055042Y+103020X0177Y    R180 S1      
327GND              U26   -BG11       A01X+053932Y+103020X0177Y    R180 S1      
327GND              U26   -BG13       A01X+053192Y+103020X0177Y    R180 S1      
327GND              U26   -BG15       A01X+052452Y+103020X0177Y    R180 S1      
327GND              U26   -BG18       A01X+051342Y+103020X0177Y    R180 S1      
327GND              U26   -BG20       A01X+050602Y+103020X0177Y    R180 S1      
327GND              U26   -BG23       A01X+049491Y+103020X0177Y    R180 S1      
327GND              U26   -BG25       A01X+048751Y+103020X0177Y    R180 S1      
327GND              U26   -BG27       A01X+048011Y+103020X0177Y    R180 S1      
327GND              U26   -BG49       A01X+040239Y+103020X0177Y    R180 S1      
327GND              U26   -BG51       A01X+039499Y+103020X0177Y    R180 S1      
327GND              U26   -BG53       A01X+038759Y+103020X0177Y    R180 S1      
327GND              U26   -BG56       A01X+037649Y+103020X0177Y    R180 S1      
327GND              U26   -BG58       A01X+036909Y+103020X0177Y    R180 S1      
327GND              U26   -BG61       A01X+035798Y+103020X0177Y    R180 S1      
327GND              U26   -BG63       A01X+035058Y+103020X0177Y    R180 S1      
327GND              U26   -BG65       A01X+034318Y+103020X0177Y    R180 S1      
327GND              U26   -BG68       A01X+033208Y+103020X0177Y    R180 S1      
327GND              U26   -BG70       A01X+032468Y+103020X0177Y    R180 S1      
327GND              U26   -BG72       A01X+031728Y+103020X0177Y    R180 S1      
327GND              U26   -BG75       A01X+030617Y+103020X0177Y    R180 S1      
327GND              U26   -BH3        A01X+057078Y+103339X0177Y    R180 S1      
327GND              U26   -BH5        A01X+056338Y+103339X0177Y    R180 S1      
327GND              U26   -BH8        A01X+055228Y+103339X0177Y    R180 S1      
327GND              U26   -BH10       A01X+054487Y+103339X0177Y    R180 S1      
327GND              U26   -BH12       A01X+053747Y+103339X0177Y    R180 S1      
327GND              U26   -BH15       A01X+052637Y+103339X0177Y    R180 S1      
327GND              U26   -BH17       A01X+051897Y+103339X0177Y    R180 S1      
327GND              U26   -BH19       A01X+051157Y+103339X0177Y    R180 S1      
327GND              U26   -BH22       A01X+050046Y+103339X0177Y    R180 S1      
327GND              U26   -BH24       A01X+049306Y+103339X0177Y    R180 S1      
327GND              U26   -BH26       A01X+048566Y+103339X0177Y    R180 S1      
327GND              U26   -BH28       A01X+047826Y+103339X0177Y    R180 S1      
327GND              U26   -BH49       A01X+040054Y+103339X0177Y    R180 S1      
327GND              U26   -BH50       A01X+039684Y+103339X0177Y    R180 S1      
327GND              U26   -BH52       A01X+038944Y+103339X0177Y    R180 S1      
327GND              U26   -BH54       A01X+038204Y+103339X0177Y    R180 S1      
327GND              U26   -BH57       A01X+037094Y+103339X0177Y    R180 S1      
327GND              U26   -BH59       A01X+036354Y+103339X0177Y    R180 S1      
327GND              U26   -BH61       A01X+035613Y+103339X0177Y    R180 S1      
327GND              U26   -BH64       A01X+034503Y+103339X0177Y    R180 S1      
327GND              U26   -BH66       A01X+033763Y+103339X0177Y    R180 S1      
327GND              U26   -BH68       A01X+033023Y+103339X0177Y    R180 S1      
327GND              U26   -BH71       A01X+031913Y+103339X0177Y    R180 S1      
327GND              U26   -BH73       A01X+031172Y+103339X0177Y    R180 S1      
327GND              U26   -BJ1        A01X+057633Y+103658X0177Y    R180 S1      
327GND              U26   -BJ6        A01X+055783Y+103658X0177Y    R180 S1      
327GND              U26   -BJ8        A01X+055042Y+103658X0177Y    R180 S1      
327GND              U26   -BJ13       A01X+053192Y+103658X0177Y    R180 S1      
327GND              U26   -BJ15       A01X+052452Y+103658X0177Y    R180 S1      
327GND              U26   -BJ20       A01X+050602Y+103658X0177Y    R180 S1      
327GND              U26   -BJ22       A01X+049861Y+103658X0177Y    R180 S1      
327GND              U26   -BJ24       A01X+049121Y+103658X0177Y    R180 S1      
327GND              U26   -BJ26       A01X+048381Y+103658X0177Y    R180 S1      
327GND              U26   -BJ28       A01X+047641Y+103658X0177Y    R180 S1      
327GND              U26   -BJ49       A01X+040239Y+103658X0177Y    R180 S1      
327GND              U26   -BJ51       A01X+039499Y+103658X0177Y    R180 S1      
327GND              U26   -BJ53       A01X+038759Y+103658X0177Y    R180 S1      
327GND              U26   -BJ56       A01X+037649Y+103658X0177Y    R180 S1      
327GND              U26   -BJ61       A01X+035798Y+103658X0177Y    R180 S1      
327GND              U26   -BJ63       A01X+035058Y+103658X0177Y    R180 S1      
327GND              U26   -BJ68       A01X+033208Y+103658X0177Y    R180 S1      
327GND              U26   -BJ70       A01X+032468Y+103658X0177Y    R180 S1      
327GND              U26   -BJ75       A01X+030617Y+103658X0177Y    R180 S1      
327GND              U26   -BK3        A01X+057078Y+103976X0177Y    R180 S1      
327GND              U26   -BK5        A01X+056338Y+103976X0177Y    R180 S1      
327GND              U26   -BK8        A01X+055228Y+103976X0177Y    R180 S1      
327GND              U26   -BK10       A01X+054487Y+103976X0177Y    R180 S1      
327GND              U26   -BK12       A01X+053747Y+103976X0177Y    R180 S1      
327GND              U26   -BK15       A01X+052637Y+103976X0177Y    R180 S1      
327GND              U26   -BK17       A01X+051897Y+103976X0177Y    R180 S1      
327GND              U26   -BK19       A01X+051157Y+103976X0177Y    R180 S1      
327GND              U26   -BK23       A01X+049676Y+103976X0177Y    R180 S1      
327GND              U26   -BK25       A01X+048936Y+103976X0177Y    R180 S1      
327GND              U26   -BK27       A01X+048196Y+103976X0177Y    R180 S1      
327GND              U26   -BK48       A01X+040424Y+103976X0177Y    R180 S1      
327GND              U26   -BK50       A01X+039684Y+103976X0177Y    R180 S1      
327GND              U26   -BK52       A01X+038944Y+103976X0177Y    R180 S1      
327GND              U26   -BK54       A01X+038204Y+103976X0177Y    R180 S1      
327GND              U26   -BK57       A01X+037094Y+103976X0177Y    R180 S1      
327GND              U26   -BK59       A01X+036354Y+103976X0177Y    R180 S1      
327GND              U26   -BK61       A01X+035613Y+103976X0177Y    R180 S1      
327GND              U26   -BK64       A01X+034503Y+103976X0177Y    R180 S1      
327GND              U26   -BK66       A01X+033763Y+103976X0177Y    R180 S1      
327GND              U26   -BK68       A01X+033023Y+103976X0177Y    R180 S1      
327GND              U26   -BK71       A01X+031913Y+103976X0177Y    R180 S1      
327GND              U26   -BK73       A01X+031172Y+103976X0177Y    R180 S1      
327GND              U26   -BL1        A01X+057633Y+104295X0177Y    R180 S1      
327GND              U26   -BL4        A01X+056523Y+104295X0177Y    R180 S1      
327GND              U26   -BL6        A01X+055783Y+104295X0177Y    R180 S1      
327GND              U26   -BL8        A01X+055042Y+104295X0177Y    R180 S1      
327GND              U26   -BL11       A01X+053932Y+104295X0177Y    R180 S1      
327GND              U26   -BL13       A01X+053192Y+104295X0177Y    R180 S1      
327GND              U26   -BL15       A01X+052452Y+104295X0177Y    R180 S1      
327GND              U26   -BL18       A01X+051342Y+104295X0177Y    R180 S1      
327GND              U26   -BL20       A01X+050602Y+104295X0177Y    R180 S1      
327GND              U26   -BL22       A01X+049861Y+104295X0177Y    R180 S1      
327GND              U26   -BL24       A01X+049121Y+104295X0177Y    R180 S1      
327GND              U26   -AM42       A01X+042527Y+097315X0177Y    R180 S1      
327GND              U26   -AM43       A01X+042157Y+097315X0177Y    R180 S1      
327GND              U26   -AM44       A01X+041787Y+097315X0177Y    R180 S1      
327GND              U26   -AM45       A01X+041416Y+097315X0177Y    R180 S1      
327GND              U26   -AM46       A01X+041046Y+097315X0177Y    R180 S1      
327GND              U26   -AM47       A01X+040676Y+097315X0177Y    R180 S1      
327GND              U26   -AM48       A01X+040306Y+097315X0177Y    R180 S1      
327GND              U26   -AM49       A01X+039936Y+097315X0177Y    R180 S1      
327GND              U26   -AM50       A01X+039566Y+097315X0177Y    R180 S1      
327GND              U26   -AM51       A01X+039196Y+097315X0177Y    R180 S1      
327GND              U26   -AM52       A01X+038826Y+097315X0177Y    R180 S1      
327GND              U26   -AM53       A01X+038456Y+097315X0177Y    R180 S1      
327GND              U26   -AM59       A01X+036235Y+097315X0177Y    R180 S1      
327GND              U26   -AM61       A01X+035495Y+097315X0177Y    R180 S1      
327GND              U26   -AM66       A01X+033645Y+097315X0177Y    R180 S1      
327GND              U26   -AM68       A01X+032905Y+097315X0177Y    R180 S1      
327GND              U26   -AM73       A01X+031054Y+097315X0177Y    R180 S1      
327GND              U26   -AN1        A01X+057515Y+097634X0177Y    R180 S1      
327GND              U26   -AN4        A01X+056405Y+097634X0177Y    R180 S1      
327GND              U26   -AN6        A01X+055664Y+097634X0177Y    R180 S1      
327GND              U26   -AN8        A01X+054924Y+097634X0177Y    R180 S1      
327GND              U26   -AN11       A01X+053814Y+097634X0177Y    R180 S1      
327GND              U26   -AN13       A01X+053074Y+097634X0177Y    R180 S1      
327GND              U26   -AN15       A01X+052334Y+097634X0177Y    R180 S1      
327GND              U26   -AN18       A01X+051224Y+097634X0177Y    R180 S1      
327GND              U26   -AN22       A01X+049743Y+097634X0177Y    R180 S1      
327GND              U26   -AN25       A01X+048633Y+097634X0177Y    R180 S1      
327GND              U26   -AN28       A01X+047523Y+097634X0177Y    R180 S1      
327GND              U26   -AN31       A01X+046413Y+097634X0177Y    R180 S1      
327GND              U26   -AN34       A01X+045302Y+097634X0177Y    R180 S1      
327GND              U26   -AN35       A01X+044932Y+097634X0177Y    R180 S1      
327GND              U26   -AN36       A01X+044562Y+097634X0177Y    R180 S1      
327GND              U26   -AN40       A01X+043452Y+097634X0177Y    R180 S1      
327GND              U26   -AN41       A01X+043082Y+097634X0177Y    R180 S1      
327GND              U26   -AN42       A01X+042712Y+097634X0177Y    R180 S1      
327GND              U26   -AN45       A01X+041602Y+097634X0177Y    R180 S1      
327GND              U26   -AN48       A01X+040491Y+097634X0177Y    R180 S1      
327GND              U26   -AN51       A01X+039381Y+097634X0177Y    R180 S1      
327GND              U26   -AN54       A01X+038271Y+097634X0177Y    R180 S1      
327GND              U26   -AN56       A01X+037531Y+097634X0177Y    R180 S1      
327GND              U26   -AN58       A01X+036790Y+097634X0177Y    R180 S1      
327GND              U26   -AN61       A01X+035680Y+097634X0177Y    R180 S1      
327GND              U26   -AN63       A01X+034940Y+097634X0177Y    R180 S1      
327GND              U26   -AN65       A01X+034200Y+097634X0177Y    R180 S1      
327GND              U26   -AN68       A01X+033090Y+097634X0177Y    R180 S1      
327GND              U26   -AN70       A01X+032350Y+097634X0177Y    R180 S1      
327GND              U26   -AN72       A01X+031609Y+097634X0177Y    R180 S1      
327GND              U26   -AN75       A01X+030499Y+097634X0177Y    R180 S1      
327GND              U26   -AP3        A01X+056960Y+097953X0177Y    R180 S1      
327GND              U26   -AP5        A01X+056220Y+097953X0177Y    R180 S1      
327GND              U26   -AP8        A01X+055109Y+097953X0177Y    R180 S1      
327GND              U26   -AP10       A01X+054369Y+097953X0177Y    R180 S1      
327GND              U26   -AP12       A01X+053629Y+097953X0177Y    R180 S1      
327GND              U26   -AP15       A01X+052519Y+097953X0177Y    R180 S1      
327GND              U26   -AP17       A01X+051779Y+097953X0177Y    R180 S1      
327GND              U26   -AP19       A01X+051038Y+097953X0177Y    R180 S1      
327GND              U26   -AP22       A01X+049928Y+097953X0177Y    R180 S1      
327GND              U26   -AP25       A01X+048818Y+097953X0177Y    R180 S1      
327GND              U26   -AP28       A01X+047708Y+097953X0177Y    R180 S1      
327GND              U26   -AP31       A01X+046598Y+097953X0177Y    R180 S1      
327GND              U26   -AP34       A01X+045487Y+097953X0177Y    R180 S1      
327GND              U26   -AP37       A01X+044377Y+097953X0177Y    R180 S1      
327GND              U26   -AP39       A01X+043637Y+097953X0177Y    R180 S1      
327GND              U26   -AP42       A01X+042527Y+097953X0177Y    R180 S1      
327GND              U26   -AP45       A01X+041416Y+097953X0177Y    R180 S1      
327GND              U26   -AP48       A01X+040306Y+097953X0177Y    R180 S1      
327GND              U26   -AP51       A01X+039196Y+097953X0177Y    R180 S1      
327GND              U26   -AP54       A01X+038086Y+097953X0177Y    R180 S1      
327GND              U26   -AP57       A01X+036976Y+097953X0177Y    R180 S1      
327GND              U26   -AP59       A01X+036235Y+097953X0177Y    R180 S1      
327GND              U26   -AP61       A01X+035495Y+097953X0177Y    R180 S1      
327GND              U26   -AP64       A01X+034385Y+097953X0177Y    R180 S1      
327GND              U26   -AP66       A01X+033645Y+097953X0177Y    R180 S1      
327GND              U26   -AP68       A01X+032905Y+097953X0177Y    R180 S1      
327GND              U26   -AP71       A01X+031794Y+097953X0177Y    R180 S1      
327GND              U26   -AP73       A01X+031054Y+097953X0177Y    R180 S1      
327GND              U26   -AR1        A01X+057515Y+098272X0177Y    R180 S1      
327GND              U26   -AR5        A01X+056035Y+098272X0177Y    R180 S1      
327GND              U26   -AR6        A01X+055664Y+098272X0177Y    R180 S1      
327GND              U26   -AR8        A01X+054924Y+098272X0177Y    R180 S1      
327GND              U26   -AR9        A01X+054554Y+098272X0177Y    R180 S1      
327GND              U26   -AR12       A01X+053444Y+098272X0177Y    R180 S1      
327GND              U26   -AR13       A01X+053074Y+098272X0177Y    R180 S1      
327GND              U26   -AR15       A01X+052334Y+098272X0177Y    R180 S1      
327GND              U26   -AR16       A01X+051964Y+098272X0177Y    R180 S1      
327GND              U26   -AR19       A01X+050854Y+098272X0177Y    R180 S1      
327GND              U26   -AR20       A01X+050483Y+098272X0177Y    R180 S1      
327GND              U26   -AR22       A01X+049743Y+098272X0177Y    R180 S1      
327GND              U26   -AR24       A01X+049003Y+098272X0177Y    R180 S1      
327GND              U26   -AR26       A01X+048263Y+098272X0177Y    R180 S1      
327GND              U26   -AR28       A01X+047523Y+098272X0177Y    R180 S1      
327GND              U26   -AR30       A01X+046783Y+098272X0177Y    R180 S1      
327GND              U26   -AR32       A01X+046042Y+098272X0177Y    R180 S1      
327GND              U26   -AR34       A01X+045302Y+098272X0177Y    R180 S1      
327GND              U26   -AR36       A01X+044562Y+098272X0177Y    R180 S1      
327GND              U26   -AR41       A01X+043082Y+098272X0177Y    R180 S1      
327GND              U26   -AR43       A01X+042342Y+098272X0177Y    R180 S1      
327GND              U26   -AR45       A01X+041602Y+098272X0177Y    R180 S1      
327GND              U26   -AR47       A01X+040861Y+098272X0177Y    R180 S1      
327GND              U26   -AR49       A01X+040121Y+098272X0177Y    R180 S1      
327GND              U26   -AR51       A01X+039381Y+098272X0177Y    R180 S1      
327GND              U26   -AR53       A01X+038641Y+098272X0177Y    R180 S1      
327GND              U26   -AR56       A01X+037531Y+098272X0177Y    R180 S1      
327GND              U26   -AR57       A01X+037161Y+098272X0177Y    R180 S1      
327GND              U26   -AR60       A01X+036050Y+098272X0177Y    R180 S1      
327GND              U26   -AR61       A01X+035680Y+098272X0177Y    R180 S1      
327GND              U26   -AR63       A01X+034940Y+098272X0177Y    R180 S1      
327GND              U26   -AR64       A01X+034570Y+098272X0177Y    R180 S1      
327GND              U26   -AR67       A01X+033460Y+098272X0177Y    R180 S1      
327GND              U26   -AR68       A01X+033090Y+098272X0177Y    R180 S1      
327GND              U26   -AR70       A01X+032350Y+098272X0177Y    R180 S1      
327GND              U26   -AR71       A01X+031980Y+098272X0177Y    R180 S1      
327GND              U26   -AR75       A01X+030499Y+098272X0177Y    R180 S1      
327GND              U26   -AT3        A01X+056960Y+098591X0177Y    R180 S1      
327GND              U26   -AT4        A01X+056590Y+098591X0177Y    R180 S1      
327GND              U26   -AT5        A01X+056220Y+098591X0177Y    R180 S1      
327GND              U26   -AT6        A01X+055850Y+098591X0177Y    R180 S1      
327GND              U26   -AT8        A01X+055109Y+098591X0177Y    R180 S1      
327GND              U26   -AT9        A01X+054739Y+098591X0177Y    R180 S1      
327GND              U26   -AT10       A01X+054369Y+098591X0177Y    R180 S1      
327GND              U26   -AT12       A01X+053629Y+098591X0177Y    R180 S1      
327GND              U26   -AT13       A01X+053259Y+098591X0177Y    R180 S1      
327GND              U26   -AT15       A01X+052519Y+098591X0177Y    R180 S1      
327GND              U26   -AT16       A01X+052149Y+098591X0177Y    R180 S1      
327GND              U26   -AT17       A01X+051779Y+098591X0177Y    R180 S1      
327GND              U26   -AT19       A01X+051038Y+098591X0177Y    R180 S1      
327GND              U26   -AT20       A01X+050668Y+098591X0177Y    R180 S1      
327GND              U26   -AT23       A01X+049558Y+098591X0177Y    R180 S1      
327GND              U26   -AT25       A01X+048818Y+098591X0177Y    R180 S1      
327GND              U26   -AT27       A01X+048078Y+098591X0177Y    R180 S1      
327GND              U26   -AT29       A01X+047338Y+098591X0177Y    R180 S1      
327GND              U26   -AT31       A01X+046598Y+098591X0177Y    R180 S1      
327GND              U26   -AT33       A01X+045857Y+098591X0177Y    R180 S1      
327GND              U26   -AT35       A01X+045117Y+098591X0177Y    R180 S1      
327GND              U26   -AT37       A01X+044377Y+098591X0177Y    R180 S1      
327GND              U26   -AT40       A01X+043267Y+098591X0177Y    R180 S1      
327GND              U26   -AT42       A01X+042527Y+098591X0177Y    R180 S1      
327GND              U26   -AT44       A01X+041787Y+098591X0177Y    R180 S1      
327GND              U26   -AT46       A01X+041046Y+098591X0177Y    R180 S1      
327GND              U26   -AT48       A01X+040306Y+098591X0177Y    R180 S1      
327GND              U26   -AT50       A01X+039566Y+098591X0177Y    R180 S1      
327GND              U26   -AT52       A01X+038826Y+098591X0177Y    R180 S1      
327GND              U26   -AT54       A01X+038086Y+098591X0177Y    R180 S1      
327GND              U26   -AT56       A01X+037346Y+098591X0177Y    R180 S1      
327GND              U26   -AT57       A01X+036976Y+098591X0177Y    R180 S1      
327GND              U26   -AT59       A01X+036235Y+098591X0177Y    R180 S1      
327GND              U26   -AT60       A01X+035865Y+098591X0177Y    R180 S1      
327GND              U26   -AT61       A01X+035495Y+098591X0177Y    R180 S1      
327GND              U26   -AT63       A01X+034755Y+098591X0177Y    R180 S1      
327GND              U26   -AT64       A01X+034385Y+098591X0177Y    R180 S1      
327GND              U26   -AT66       A01X+033645Y+098591X0177Y    R180 S1      
327GND              U26   -AT67       A01X+033275Y+098591X0177Y    R180 S1      
327GND              U26   -AT68       A01X+032905Y+098591X0177Y    R180 S1      
327GND              U26   -AT70       A01X+032164Y+098591X0177Y    R180 S1      
327GND              U26   -AT71       A01X+031794Y+098591X0177Y    R180 S1      
327GND              U26   -AT72       A01X+031424Y+098591X0177Y    R180 S1      
327GND              U26   -AT73       A01X+031054Y+098591X0177Y    R180 S1      
327GND              U26   -AU1        A01X+057515Y+098910X0177Y    R180 S1      
327GND              U26   -AU3        A01X+056775Y+098910X0177Y    R180 S1      
327GND              U26   -AU4        A01X+056405Y+098910X0177Y    R180 S1      
327GND              U26   -AU6        A01X+055664Y+098910X0177Y    R180 S1      
327GND              U26   -AU8        A01X+054924Y+098910X0177Y    R180 S1      
327GND              U26   -AU11       A01X+053814Y+098910X0177Y    R180 S1      
327GND              U26   -AU13       A01X+053074Y+098910X0177Y    R180 S1      
327GND              U26   -AU15       A01X+052334Y+098910X0177Y    R180 S1      
327GND              U26   -AU18       A01X+051224Y+098910X0177Y    R180 S1      
327GND              U26   -AU20       A01X+050483Y+098910X0177Y    R180 S1      
327GND              U26   -AU22       A01X+049743Y+098910X0177Y    R180 S1      
327GND              U26   -AU24       A01X+049003Y+098910X0177Y    R180 S1      
327GND              U26   -AU26       A01X+048263Y+098910X0177Y    R180 S1      
327GND              U26   -AU28       A01X+047523Y+098910X0177Y    R180 S1      
327GND              U26   -AU30       A01X+046783Y+098910X0177Y    R180 S1      
327GND              U26   -AU32       A01X+046042Y+098910X0177Y    R180 S1      
327GND              U26   -AU34       A01X+045302Y+098910X0177Y    R180 S1      
327GND              U26   -AU36       A01X+044562Y+098910X0177Y    R180 S1      
327GND              U26   -AU41       A01X+043082Y+098910X0177Y    R180 S1      
327GND              U26   -AU43       A01X+042342Y+098910X0177Y    R180 S1      
327GND              U26   -AU45       A01X+041602Y+098910X0177Y    R180 S1      
327GND              U26   -AU47       A01X+040861Y+098910X0177Y    R180 S1      
327GND              U26   -AU49       A01X+040121Y+098910X0177Y    R180 S1      
327GND              U26   -AU51       A01X+039381Y+098910X0177Y    R180 S1      
327GND              U26   -AU53       A01X+038641Y+098910X0177Y    R180 S1      
327GND              U26   -AU56       A01X+037531Y+098910X0177Y    R180 S1      
327GND              U26   -AU58       A01X+036790Y+098910X0177Y    R180 S1      
327GND              U26   -AU61       A01X+035680Y+098910X0177Y    R180 S1      
327GND              U26   -AU63       A01X+034940Y+098910X0177Y    R180 S1      
327GND              U26   -AU65       A01X+034200Y+098910X0177Y    R180 S1      
327GND              U26   -AU68       A01X+033090Y+098910X0177Y    R180 S1      
327GND              U26   -AU70       A01X+032350Y+098910X0177Y    R180 S1      
327GND              U26   -AU72       A01X+031609Y+098910X0177Y    R180 S1      
327GND              U26   -AU73       A01X+031239Y+098910X0177Y    R180 S1      
327GND              U26   -AU75       A01X+030499Y+098910X0177Y    R180 S1      
327GND              U26   -AV3        A01X+056960Y+099228X0177Y    R180 S1      
327GND              U26   -AV8        A01X+055109Y+099228X0177Y    R180 S1      
327GND              U26   -AV10       A01X+054369Y+099228X0177Y    R180 S1      
327GND              U26   -AV15       A01X+052519Y+099228X0177Y    R180 S1      
327GND              U26   -AV17       A01X+051779Y+099228X0177Y    R180 S1      
327GND              U26   -AV23       A01X+049558Y+099228X0177Y    R180 S1      
327GND              U26   -AV25       A01X+048818Y+099228X0177Y    R180 S1      
327GND              U26   -AV27       A01X+048078Y+099228X0177Y    R180 S1      
327GND              U26   -AV29       A01X+047338Y+099228X0177Y    R180 S1      
327GND              U26   -AV31       A01X+046598Y+099228X0177Y    R180 S1      
327GND              U26   -AV33       A01X+045857Y+099228X0177Y    R180 S1      
327GND              U26   -AV35       A01X+045117Y+099228X0177Y    R180 S1      
327GND              U26   -AV37       A01X+044377Y+099228X0177Y    R180 S1      
327GND              U26   -AV40       A01X+043267Y+099228X0177Y    R180 S1      
327GND              U26   -AV42       A01X+042527Y+099228X0177Y    R180 S1      
327GND              U26   -AV44       A01X+041787Y+099228X0177Y    R180 S1      
327GND              U26   -AV46       A01X+041046Y+099228X0177Y    R180 S1      
327GND              U26   -AV48       A01X+040306Y+099228X0177Y    R180 S1      
327GND              U26   -AV50       A01X+039566Y+099228X0177Y    R180 S1      
327GND              U26   -AV52       A01X+038826Y+099228X0177Y    R180 S1      
327GND              U26   -AV54       A01X+038086Y+099228X0177Y    R180 S1      
327GND              U26   -AV59       A01X+036235Y+099228X0177Y    R180 S1      
327GND              U26   -AV61       A01X+035495Y+099228X0177Y    R180 S1      
327GND              U26   -AV66       A01X+033645Y+099228X0177Y    R180 S1      
327GND              U26   -AV68       A01X+032905Y+099228X0177Y    R180 S1      
327GND              U26   -AV73       A01X+031054Y+099228X0177Y    R180 S1      
327GND              U26   -AW1        A01X+057515Y+099547X0177Y    R180 S1      
327GND              U26   -AW4        A01X+056405Y+099547X0177Y    R180 S1      
327GND              U26   -AW6        A01X+055664Y+099547X0177Y    R180 S1      
327GND              U26   -AW8        A01X+054924Y+099547X0177Y    R180 S1      
327GND              U26   -AW11       A01X+053814Y+099547X0177Y    R180 S1      
327GND              U26   -AW13       A01X+053074Y+099547X0177Y    R180 S1      
327GND              U26   -AW15       A01X+052334Y+099547X0177Y    R180 S1      
327GND              U26   -AW18       A01X+051224Y+099547X0177Y    R180 S1      
327GND              U26   -AW20       A01X+050483Y+099547X0177Y    R180 S1      
327GND              U26   -AW22       A01X+049743Y+099547X0177Y    R180 S1      
327GND              U26   -AW24       A01X+049003Y+099547X0177Y    R180 S1      
327GND              U26   -AW26       A01X+048263Y+099547X0177Y    R180 S1      
327GND              U26   -AW28       A01X+047523Y+099547X0177Y    R180 S1      
327GND              U26   -AW49       A01X+040121Y+099547X0177Y    R180 S1      
327GND              U26   -AW51       A01X+039381Y+099547X0177Y    R180 S1      
327GND              U26   -AW53       A01X+038641Y+099547X0177Y    R180 S1      
327GND              U26   -AW56       A01X+037531Y+099547X0177Y    R180 S1      
327GND              U26   -AW58       A01X+036790Y+099547X0177Y    R180 S1      
327GND              U26   -AW61       A01X+035680Y+099547X0177Y    R180 S1      
327GND              U26   -AD49       A01X+039936Y+094764X0177Y    R180 S1      
327GND              U26   -AD50       A01X+039566Y+094764X0177Y    R180 S1      
327GND              U26   -AD51       A01X+039196Y+094764X0177Y    R180 S1      
327GND              U26   -AD52       A01X+038826Y+094764X0177Y    R180 S1      
327GND              U26   -AD53       A01X+038456Y+094764X0177Y    R180 S1      
327GND              U26   -AD57       A01X+036976Y+094764X0177Y    R180 S1      
327GND              U26   -AD59       A01X+036235Y+094764X0177Y    R180 S1      
327GND              U26   -AD61       A01X+035495Y+094764X0177Y    R180 S1      
327GND              U26   -AD64       A01X+034385Y+094764X0177Y    R180 S1      
327GND              U26   -AD66       A01X+033645Y+094764X0177Y    R180 S1      
327GND              U26   -AD68       A01X+032905Y+094764X0177Y    R180 S1      
327GND              U26   -AD71       A01X+031794Y+094764X0177Y    R180 S1      
327GND              U26   -AD73       A01X+031054Y+094764X0177Y    R180 S1      
327GND              U26   -AE1        A01X+057515Y+095083X0177Y    R180 S1      
327GND              U26   -AE6        A01X+055664Y+095083X0177Y    R180 S1      
327GND              U26   -AE8        A01X+054924Y+095083X0177Y    R180 S1      
327GND              U26   -AE11       A01X+053814Y+095083X0177Y    R180 S1      
327GND              U26   -AE13       A01X+053074Y+095083X0177Y    R180 S1      
327GND              U26   -AE15       A01X+052334Y+095083X0177Y    R180 S1      
327GND              U26   -AE18       A01X+051224Y+095083X0177Y    R180 S1      
327GND              U26   -AE20       A01X+050483Y+095083X0177Y    R180 S1      
327GND              U26   -AE22       A01X+049743Y+095083X0177Y    R180 S1      
327GND              U26   -AE25       A01X+048633Y+095083X0177Y    R180 S1      
327GND              U26   -AE28       A01X+047523Y+095083X0177Y    R180 S1      
327GND              U26   -AE31       A01X+046413Y+095083X0177Y    R180 S1      
327GND              U26   -AE34       A01X+045302Y+095083X0177Y    R180 S1      
327GND              U26   -AE35       A01X+044932Y+095083X0177Y    R180 S1      
327GND              U26   -AE36       A01X+044562Y+095083X0177Y    R180 S1      
327GND              U26   -AE40       A01X+043452Y+095083X0177Y    R180 S1      
327GND              U26   -AE41       A01X+043082Y+095083X0177Y    R180 S1      
327GND              U26   -AE42       A01X+042712Y+095083X0177Y    R180 S1      
327GND              U26   -AE45       A01X+041602Y+095083X0177Y    R180 S1      
327GND              U26   -AE48       A01X+040491Y+095083X0177Y    R180 S1      
327GND              U26   -AE51       A01X+039381Y+095083X0177Y    R180 S1      
327GND              U26   -AE54       A01X+038271Y+095083X0177Y    R180 S1      
327GND              U26   -AE56       A01X+037531Y+095083X0177Y    R180 S1      
327GND              U26   -AE58       A01X+036790Y+095083X0177Y    R180 S1      
327GND              U26   -AE61       A01X+035680Y+095083X0177Y    R180 S1      
327GND              U26   -AE63       A01X+034940Y+095083X0177Y    R180 S1      
327GND              U26   -AE65       A01X+034200Y+095083X0177Y    R180 S1      
327GND              U26   -AE68       A01X+033090Y+095083X0177Y    R180 S1      
327GND              U26   -AE70       A01X+032350Y+095083X0177Y    R180 S1      
327GND              U26   -AE72       A01X+031609Y+095083X0177Y    R180 S1      
327GND              U26   -AE75       A01X+030499Y+095083X0177Y    R180 S1      
327GND              U26   -AF3        A01X+056960Y+095402X0177Y    R180 S1      
327GND              U26   -AF8        A01X+055109Y+095402X0177Y    R180 S1      
327GND              U26   -AF10       A01X+054369Y+095402X0177Y    R180 S1      
327GND              U26   -AF15       A01X+052519Y+095402X0177Y    R180 S1      
327GND              U26   -AF17       A01X+051779Y+095402X0177Y    R180 S1      
327GND              U26   -AF22       A01X+049928Y+095402X0177Y    R180 S1      
327GND              U26   -AF25       A01X+048818Y+095402X0177Y    R180 S1      
327GND              U26   -AF28       A01X+047708Y+095402X0177Y    R180 S1      
327GND              U26   -AF31       A01X+046598Y+095402X0177Y    R180 S1      
327GND              U26   -AF34       A01X+045487Y+095402X0177Y    R180 S1      
327GND              U26   -AF37       A01X+044377Y+095402X0177Y    R180 S1      
327GND              U26   -AF39       A01X+043637Y+095402X0177Y    R180 S1      
327GND              U26   -AF42       A01X+042527Y+095402X0177Y    R180 S1      
327GND              U26   -AF45       A01X+041416Y+095402X0177Y    R180 S1      
327GND              U26   -AF48       A01X+040306Y+095402X0177Y    R180 S1      
327GND              U26   -AF51       A01X+039196Y+095402X0177Y    R180 S1      
327GND              U26   -AF54       A01X+038086Y+095402X0177Y    R180 S1      
327GND              U26   -AF59       A01X+036235Y+095402X0177Y    R180 S1      
327GND              U26   -AF61       A01X+035495Y+095402X0177Y    R180 S1      
327GND              U26   -AF66       A01X+033645Y+095402X0177Y    R180 S1      
327GND              U26   -AF68       A01X+032905Y+095402X0177Y    R180 S1      
327GND              U26   -AF73       A01X+031054Y+095402X0177Y    R180 S1      
327GND              U26   -AG1        A01X+057515Y+095721X0177Y    R180 S1      
327GND              U26   -AG4        A01X+056405Y+095721X0177Y    R180 S1      
327GND              U26   -AG6        A01X+055664Y+095721X0177Y    R180 S1      
327GND              U26   -AG8        A01X+054924Y+095721X0177Y    R180 S1      
327GND              U26   -AG11       A01X+053814Y+095721X0177Y    R180 S1      
327GND              U26   -AG13       A01X+053074Y+095721X0177Y    R180 S1      
327GND              U26   -AG15       A01X+052334Y+095721X0177Y    R180 S1      
327GND              U26   -AG18       A01X+051224Y+095721X0177Y    R180 S1      
327GND              U26   -AG20       A01X+050483Y+095721X0177Y    R180 S1      
327GND              U26   -AG22       A01X+049743Y+095721X0177Y    R180 S1      
327GND              U26   -AG25       A01X+048633Y+095721X0177Y    R180 S1      
327GND              U26   -AG28       A01X+047523Y+095721X0177Y    R180 S1      
327GND              U26   -AG31       A01X+046413Y+095721X0177Y    R180 S1      
327GND              U26   -AG34       A01X+045302Y+095721X0177Y    R180 S1      
327GND              U26   -AG42       A01X+042712Y+095721X0177Y    R180 S1      
327GND              U26   -AG45       A01X+041602Y+095721X0177Y    R180 S1      
327GND              U26   -AG48       A01X+040491Y+095721X0177Y    R180 S1      
327GND              U26   -AG51       A01X+039381Y+095721X0177Y    R180 S1      
327GND              U26   -AG54       A01X+038271Y+095721X0177Y    R180 S1      
327GND              U26   -AG56       A01X+037531Y+095721X0177Y    R180 S1      
327GND              U26   -AG58       A01X+036790Y+095721X0177Y    R180 S1      
327GND              U26   -AG61       A01X+035680Y+095721X0177Y    R180 S1      
327GND              U26   -AG63       A01X+034940Y+095721X0177Y    R180 S1      
327GND              U26   -AG65       A01X+034200Y+095721X0177Y    R180 S1      
327GND              U26   -AG68       A01X+033090Y+095721X0177Y    R180 S1      
327GND              U26   -AG70       A01X+032350Y+095721X0177Y    R180 S1      
327GND              U26   -AG72       A01X+031609Y+095721X0177Y    R180 S1      
327GND              U26   -AG75       A01X+030499Y+095721X0177Y    R180 S1      
327GND              U26   -AH3        A01X+056960Y+096040X0177Y    R180 S1      
327GND              U26   -AH5        A01X+056220Y+096040X0177Y    R180 S1      
327GND              U26   -AH8        A01X+055109Y+096040X0177Y    R180 S1      
327GND              U26   -AH10       A01X+054369Y+096040X0177Y    R180 S1      
327GND              U26   -AH12       A01X+053629Y+096040X0177Y    R180 S1      
327GND              U26   -AH15       A01X+052519Y+096040X0177Y    R180 S1      
327GND              U26   -AH17       A01X+051779Y+096040X0177Y    R180 S1      
327GND              U26   -AH19       A01X+051038Y+096040X0177Y    R180 S1      
327GND              U26   -AH23       A01X+049558Y+096040X0177Y    R180 S1      
327GND              U26   -AH24       A01X+049188Y+096040X0177Y    R180 S1      
327GND              U26   -AH25       A01X+048818Y+096040X0177Y    R180 S1      
327GND              U26   -AH26       A01X+048448Y+096040X0177Y    R180 S1      
327GND              U26   -AH27       A01X+048078Y+096040X0177Y    R180 S1      
327GND              U26   -AH28       A01X+047708Y+096040X0177Y    R180 S1      
327GND              U26   -AH29       A01X+047338Y+096040X0177Y    R180 S1      
327GND              U26   -AH30       A01X+046968Y+096040X0177Y    R180 S1      
327GND              U26   -AH31       A01X+046598Y+096040X0177Y    R180 S1      
327GND              U26   -AH32       A01X+046228Y+096040X0177Y    R180 S1      
327GND              U26   -AH34       A01X+045487Y+096040X0177Y    R180 S1      
327GND              U26   -AH37       A01X+044377Y+096040X0177Y    R180 S1      
327GND              U26   -AH39       A01X+043637Y+096040X0177Y    R180 S1      
327GND              U26   -AH42       A01X+042527Y+096040X0177Y    R180 S1      
327GND              U26   -AH43       A01X+042157Y+096040X0177Y    R180 S1      
327GND              U26   -AH44       A01X+041787Y+096040X0177Y    R180 S1      
327GND              U26   -AH45       A01X+041416Y+096040X0177Y    R180 S1      
327GND              U26   -AH46       A01X+041046Y+096040X0177Y    R180 S1      
327GND              U26   -AH47       A01X+040676Y+096040X0177Y    R180 S1      
327GND              U26   -AH48       A01X+040306Y+096040X0177Y    R180 S1      
327GND              U26   -AH49       A01X+039936Y+096040X0177Y    R180 S1      
327GND              U26   -AH50       A01X+039566Y+096040X0177Y    R180 S1      
327GND              U26   -AH51       A01X+039196Y+096040X0177Y    R180 S1      
327GND              U26   -AH52       A01X+038826Y+096040X0177Y    R180 S1      
327GND              U26   -AH53       A01X+038456Y+096040X0177Y    R180 S1      
327GND              U26   -AH57       A01X+036976Y+096040X0177Y    R180 S1      
327GND              U26   -AH59       A01X+036235Y+096040X0177Y    R180 S1      
327GND              U26   -AH61       A01X+035495Y+096040X0177Y    R180 S1      
327GND              U26   -AH64       A01X+034385Y+096040X0177Y    R180 S1      
327GND              U26   -AH66       A01X+033645Y+096040X0177Y    R180 S1      
327GND              U26   -AH68       A01X+032905Y+096040X0177Y    R180 S1      
327GND              U26   -AH71       A01X+031794Y+096040X0177Y    R180 S1      
327GND              U26   -AH73       A01X+031054Y+096040X0177Y    R180 S1      
327GND              U26   -AJ1        A01X+057515Y+096358X0177Y    R180 S1      
327GND              U26   -AJ6        A01X+055664Y+096358X0177Y    R180 S1      
327GND              U26   -AJ8        A01X+054924Y+096358X0177Y    R180 S1      
327GND              U26   -AJ15       A01X+052334Y+096358X0177Y    R180 S1      
327GND              U26   -AJ20       A01X+050483Y+096358X0177Y    R180 S1      
327GND              U26   -AJ22       A01X+049743Y+096358X0177Y    R180 S1      
327GND              U26   -AJ25       A01X+048633Y+096358X0177Y    R180 S1      
327GND              U26   -AJ28       A01X+047523Y+096358X0177Y    R180 S1      
327GND              U26   -AJ31       A01X+046413Y+096358X0177Y    R180 S1      
327GND              U26   -AJ34       A01X+045302Y+096358X0177Y    R180 S1      
327GND              U26   -AJ35       A01X+044932Y+096358X0177Y    R180 S1      
327GND              U26   -AJ36       A01X+044562Y+096358X0177Y    R180 S1      
327GND              U26   -AJ40       A01X+043452Y+096358X0177Y    R180 S1      
327GND              U26   -AJ41       A01X+043082Y+096358X0177Y    R180 S1      
327GND              U26   -AJ42       A01X+042712Y+096358X0177Y    R180 S1      
327GND              U26   -AJ45       A01X+041602Y+096358X0177Y    R180 S1      
327GND              U26   -AJ48       A01X+040491Y+096358X0177Y    R180 S1      
327GND              U26   -AJ51       A01X+039381Y+096358X0177Y    R180 S1      
327GND              U26   -AJ54       A01X+038271Y+096358X0177Y    R180 S1      
327GND              U26   -AJ56       A01X+037531Y+096358X0177Y    R180 S1      
327GND              U26   -AJ61       A01X+035680Y+096358X0177Y    R180 S1      
327GND              U26   -AJ63       A01X+034940Y+096358X0177Y    R180 S1      
327GND              U26   -AJ68       A01X+033090Y+096358X0177Y    R180 S1      
327GND              U26   -AJ70       A01X+032350Y+096358X0177Y    R180 S1      
327GND              U26   -AJ75       A01X+030499Y+096358X0177Y    R180 S1      
327GND              U26   -AK3        A01X+056960Y+096677X0177Y    R180 S1      
327GND              U26   -AK5        A01X+056220Y+096677X0177Y    R180 S1      
327GND              U26   -AK8        A01X+055109Y+096677X0177Y    R180 S1      
327GND              U26   -AK10       A01X+054369Y+096677X0177Y    R180 S1      
327GND              U26   -AK12       A01X+053629Y+096677X0177Y    R180 S1      
327GND              U26   -AK15       A01X+052519Y+096677X0177Y    R180 S1      
327GND              U26   -AK17       A01X+051779Y+096677X0177Y    R180 S1      
327GND              U26   -AK19       A01X+051038Y+096677X0177Y    R180 S1      
327GND              U26   -AK22       A01X+049928Y+096677X0177Y    R180 S1      
327GND              U26   -AK25       A01X+048818Y+096677X0177Y    R180 S1      
327GND              U26   -AK28       A01X+047708Y+096677X0177Y    R180 S1      
327GND              U26   -AK31       A01X+046598Y+096677X0177Y    R180 S1      
327GND              U26   -AK34       A01X+045487Y+096677X0177Y    R180 S1      
327GND              U26   -AK37       A01X+044377Y+096677X0177Y    R180 S1      
327GND              U26   -AK39       A01X+043637Y+096677X0177Y    R180 S1      
327GND              U26   -AK42       A01X+042527Y+096677X0177Y    R180 S1      
327GND              U26   -AK45       A01X+041416Y+096677X0177Y    R180 S1      
327GND              U26   -AK48       A01X+040306Y+096677X0177Y    R180 S1      
327GND              U26   -AK51       A01X+039196Y+096677X0177Y    R180 S1      
327GND              U26   -AK54       A01X+038086Y+096677X0177Y    R180 S1      
327GND              U26   -AK57       A01X+036976Y+096677X0177Y    R180 S1      
327GND              U26   -AK59       A01X+036235Y+096677X0177Y    R180 S1      
327GND              U26   -AK61       A01X+035495Y+096677X0177Y    R180 S1      
327GND              U26   -AK64       A01X+034385Y+096677X0177Y    R180 S1      
327GND              U26   -AK66       A01X+033645Y+096677X0177Y    R180 S1      
327GND              U26   -AK68       A01X+032905Y+096677X0177Y    R180 S1      
327GND              U26   -AK71       A01X+031794Y+096677X0177Y    R180 S1      
327GND              U26   -AK73       A01X+031054Y+096677X0177Y    R180 S1      
327GND              U26   -AL1        A01X+057515Y+096996X0177Y    R180 S1      
327GND              U26   -AL4        A01X+056405Y+096996X0177Y    R180 S1      
327GND              U26   -AL6        A01X+055664Y+096996X0177Y    R180 S1      
327GND              U26   -AL8        A01X+054924Y+096996X0177Y    R180 S1      
327GND              U26   -AL11       A01X+053814Y+096996X0177Y    R180 S1      
327GND              U26   -AL13       A01X+053074Y+096996X0177Y    R180 S1      
327GND              U26   -AL15       A01X+052334Y+096996X0177Y    R180 S1      
327GND              U26   -AL18       A01X+051224Y+096996X0177Y    R180 S1      
327GND              U26   -AL20       A01X+050483Y+096996X0177Y    R180 S1      
327GND              U26   -AL22       A01X+049743Y+096996X0177Y    R180 S1      
327GND              U26   -AL25       A01X+048633Y+096996X0177Y    R180 S1      
327GND              U26   -AL28       A01X+047523Y+096996X0177Y    R180 S1      
327GND              U26   -AL31       A01X+046413Y+096996X0177Y    R180 S1      
327GND              U26   -AL34       A01X+045302Y+096996X0177Y    R180 S1      
327GND              U26   -AL42       A01X+042712Y+096996X0177Y    R180 S1      
327GND              U26   -AL45       A01X+041602Y+096996X0177Y    R180 S1      
327GND              U26   -AL48       A01X+040491Y+096996X0177Y    R180 S1      
327GND              U26   -AL51       A01X+039381Y+096996X0177Y    R180 S1      
327GND              U26   -AL54       A01X+038271Y+096996X0177Y    R180 S1      
327GND              U26   -AL56       A01X+037531Y+096996X0177Y    R180 S1      
327GND              U26   -AL58       A01X+036790Y+096996X0177Y    R180 S1      
327GND              U26   -AL61       A01X+035680Y+096996X0177Y    R180 S1      
327GND              U26   -AL63       A01X+034940Y+096996X0177Y    R180 S1      
327GND              U26   -AL65       A01X+034200Y+096996X0177Y    R180 S1      
327GND              U26   -AL68       A01X+033090Y+096996X0177Y    R180 S1      
327GND              U26   -AL70       A01X+032350Y+096996X0177Y    R180 S1      
327GND              U26   -AL72       A01X+031609Y+096996X0177Y    R180 S1      
327GND              U26   -AL75       A01X+030499Y+096996X0177Y    R180 S1      
327GND              U26   -AM3        A01X+056960Y+097315X0177Y    R180 S1      
327GND              U26   -AM8        A01X+055109Y+097315X0177Y    R180 S1      
327GND              U26   -AM10       A01X+054369Y+097315X0177Y    R180 S1      
327GND              U26   -AM15       A01X+052519Y+097315X0177Y    R180 S1      
327GND              U26   -AM17       A01X+051779Y+097315X0177Y    R180 S1      
327GND              U26   -AM23       A01X+049558Y+097315X0177Y    R180 S1      
327GND              U26   -AM24       A01X+049188Y+097315X0177Y    R180 S1      
327GND              U26   -AM25       A01X+048818Y+097315X0177Y    R180 S1      
327GND              U26   -AM26       A01X+048448Y+097315X0177Y    R180 S1      
327GND              U26   -AM27       A01X+048078Y+097315X0177Y    R180 S1      
327GND              U26   -AM28       A01X+047708Y+097315X0177Y    R180 S1      
327GND              U26   -AM29       A01X+047338Y+097315X0177Y    R180 S1      
327GND              U26   -AM30       A01X+046968Y+097315X0177Y    R180 S1      
327GND              U26   -AM31       A01X+046598Y+097315X0177Y    R180 S1      
327GND              U26   -AM32       A01X+046228Y+097315X0177Y    R180 S1      
327GND              U26   -AM33       A01X+045857Y+097315X0177Y    R180 S1      
327GND              U26   -AM34       A01X+045487Y+097315X0177Y    R180 S1      
327GND              U26   -AM39       A01X+043637Y+097315X0177Y    R180 S1      
327GND              U26   -AA1        A01X+057515Y+093807X0177Y    R180 S1      
327GND              U26   -AA4        A01X+056405Y+093807X0177Y    R180 S1      
327GND              U26   -AA6        A01X+055664Y+093807X0177Y    R180 S1      
327GND              U26   -AA8        A01X+054924Y+093807X0177Y    R180 S1      
327GND              U26   -AA11       A01X+053814Y+093807X0177Y    R180 S1      
327GND              U26   -AA13       A01X+053074Y+093807X0177Y    R180 S1      
327GND              U26   -AA15       A01X+052334Y+093807X0177Y    R180 S1      
327GND              U26   -AA18       A01X+051224Y+093807X0177Y    R180 S1      
327GND              U26   -AA20       A01X+050483Y+093807X0177Y    R180 S1      
327GND              U26   -AA31       A01X+046413Y+093807X0177Y    R180 S1      
327GND              U26   -AA34       A01X+045302Y+093807X0177Y    R180 S1      
327GND              U26   -AA35       A01X+044932Y+093807X0177Y    R180 S1      
327GND              U26   -AA36       A01X+044562Y+093807X0177Y    R180 S1      
327GND              U26   -AA40       A01X+043452Y+093807X0177Y    R180 S1      
327GND              U26   -AA41       A01X+043082Y+093807X0177Y    R180 S1      
327GND              U26   -AA45       A01X+041602Y+093807X0177Y    R180 S1      
327GND              U26   -AA56       A01X+037531Y+093807X0177Y    R180 S1      
327GND              U26   -AA58       A01X+036790Y+093807X0177Y    R180 S1      
327GND              U26   -AA61       A01X+035680Y+093807X0177Y    R180 S1      
327GND              U26   -AA63       A01X+034940Y+093807X0177Y    R180 S1      
327GND              U26   -AA65       A01X+034200Y+093807X0177Y    R180 S1      
327GND              U26   -AA68       A01X+033090Y+093807X0177Y    R180 S1      
327GND              U26   -AA70       A01X+032350Y+093807X0177Y    R180 S1      
327GND              U26   -AA75       A01X+030499Y+093807X0177Y    R180 S1      
327GND              U26   -AB3        A01X+056960Y+094126X0177Y    R180 S1      
327GND              U26   -AB5        A01X+056220Y+094126X0177Y    R180 S1      
327GND              U26   -AB8        A01X+055109Y+094126X0177Y    R180 S1      
327GND              U26   -AB10       A01X+054369Y+094126X0177Y    R180 S1      
327GND              U26   -AB12       A01X+053629Y+094126X0177Y    R180 S1      
327GND              U26   -AB15       A01X+052519Y+094126X0177Y    R180 S1      
327GND              U26   -AB17       A01X+051779Y+094126X0177Y    R180 S1      
327GND              U26   -AB19       A01X+051038Y+094126X0177Y    R180 S1      
327GND              U26   -AB22       A01X+049928Y+094126X0177Y    R180 S1      
327GND              U26   -AB25       A01X+048818Y+094126X0177Y    R180 S1      
327GND              U26   -AB28       A01X+047708Y+094126X0177Y    R180 S1      
327GND              U26   -AB31       A01X+046598Y+094126X0177Y    R180 S1      
327GND              U26   -AB34       A01X+045487Y+094126X0177Y    R180 S1      
327GND              U26   -AB37       A01X+044377Y+094126X0177Y    R180 S1      
327GND              U26   -AB39       A01X+043637Y+094126X0177Y    R180 S1      
327GND              U26   -AB42       A01X+042527Y+094126X0177Y    R180 S1      
327GND              U26   -AB45       A01X+041416Y+094126X0177Y    R180 S1      
327GND              U26   -AB48       A01X+040306Y+094126X0177Y    R180 S1      
327GND              U26   -AB51       A01X+039196Y+094126X0177Y    R180 S1      
327GND              U26   -AB54       A01X+038086Y+094126X0177Y    R180 S1      
327GND              U26   -AB57       A01X+036976Y+094126X0177Y    R180 S1      
327GND              U26   -AB59       A01X+036235Y+094126X0177Y    R180 S1      
327GND              U26   -AB61       A01X+035495Y+094126X0177Y    R180 S1      
327GND              U26   -AB64       A01X+034385Y+094126X0177Y    R180 S1      
327GND              U26   -AB66       A01X+033645Y+094126X0177Y    R180 S1      
327GND              U26   -AB68       A01X+032905Y+094126X0177Y    R180 S1      
327GND              U26   -AB71       A01X+031794Y+094126X0177Y    R180 S1      
327GND              U26   -AB73       A01X+031054Y+094126X0177Y    R180 S1      
327GND              U26   -AC1        A01X+057515Y+094445X0177Y    R180 S1      
327GND              U26   -AC6        A01X+055664Y+094445X0177Y    R180 S1      
327GND              U26   -AC8        A01X+054924Y+094445X0177Y    R180 S1      
327GND              U26   -AC13       A01X+053074Y+094445X0177Y    R180 S1      
327GND              U26   -AC15       A01X+052334Y+094445X0177Y    R180 S1      
327GND              U26   -AC20       A01X+050483Y+094445X0177Y    R180 S1      
327GND              U26   -AC22       A01X+049743Y+094445X0177Y    R180 S1      
327GND              U26   -AC25       A01X+048633Y+094445X0177Y    R180 S1      
327GND              U26   -AC28       A01X+047523Y+094445X0177Y    R180 S1      
327GND              U26   -AC31       A01X+046413Y+094445X0177Y    R180 S1      
327GND              U26   -AC34       A01X+045302Y+094445X0177Y    R180 S1      
327GND              U26   -AC42       A01X+042712Y+094445X0177Y    R180 S1      
327GND              U26   -AC45       A01X+041602Y+094445X0177Y    R180 S1      
327GND              U26   -AC48       A01X+040491Y+094445X0177Y    R180 S1      
327GND              U26   -AC51       A01X+039381Y+094445X0177Y    R180 S1      
327GND              U26   -AC54       A01X+038271Y+094445X0177Y    R180 S1      
327GND              U26   -AC56       A01X+037531Y+094445X0177Y    R180 S1      
327GND              U26   -AC61       A01X+035680Y+094445X0177Y    R180 S1      
327GND              U26   -AC63       A01X+034940Y+094445X0177Y    R180 S1      
327GND              U26   -AC68       A01X+033090Y+094445X0177Y    R180 S1      
327GND              U26   -AC70       A01X+032350Y+094445X0177Y    R180 S1      
327GND              U26   -AC75       A01X+030499Y+094445X0177Y    R180 S1      
327GND              U26   -AD3        A01X+056960Y+094764X0177Y    R180 S1      
327GND              U26   -AD5        A01X+056220Y+094764X0177Y    R180 S1      
327GND              U26   -AD8        A01X+055109Y+094764X0177Y    R180 S1      
327GND              U26   -AD10       A01X+054369Y+094764X0177Y    R180 S1      
327GND              U26   -AD12       A01X+053629Y+094764X0177Y    R180 S1      
327GND              U26   -AD15       A01X+052519Y+094764X0177Y    R180 S1      
327GND              U26   -AD17       A01X+051779Y+094764X0177Y    R180 S1      
327GND              U26   -AD19       A01X+051038Y+094764X0177Y    R180 S1      
327GND              U26   -AD23       A01X+049558Y+094764X0177Y    R180 S1      
327GND              U26   -AD24       A01X+049188Y+094764X0177Y    R180 S1      
327GND              U26   -AD25       A01X+048818Y+094764X0177Y    R180 S1      
327GND              U26   -AD26       A01X+048448Y+094764X0177Y    R180 S1      
327GND              U26   -AD27       A01X+048078Y+094764X0177Y    R180 S1      
327GND              U26   -AD28       A01X+047708Y+094764X0177Y    R180 S1      
327GND              U26   -AD29       A01X+047338Y+094764X0177Y    R180 S1      
327GND              U26   -AD30       A01X+046968Y+094764X0177Y    R180 S1      
327GND              U26   -AD32       A01X+046228Y+094764X0177Y    R180 S1      
327GND              U26   -AD33       A01X+045857Y+094764X0177Y    R180 S1      
327GND              U26   -AD34       A01X+045487Y+094764X0177Y    R180 S1      
327GND              U26   -AD37       A01X+044377Y+094764X0177Y    R180 S1      
327GND              U26   -AD39       A01X+043637Y+094764X0177Y    R180 S1      
327GND              U26   -AD42       A01X+042527Y+094764X0177Y    R180 S1      
327GND              U26   -AD43       A01X+042157Y+094764X0177Y    R180 S1      
327GND              U26   -AD44       A01X+041787Y+094764X0177Y    R180 S1      
327GND              U26   -AD45       A01X+041416Y+094764X0177Y    R180 S1      
327GND              U26   -AD46       A01X+041046Y+094764X0177Y    R180 S1      
327GND              U26   -AD47       A01X+040676Y+094764X0177Y    R180 S1      
327GND              U26   -AD48       A01X+040306Y+094764X0177Y    R180 S1      
327GND              U26   -T66        A01X+033645Y+092213X0177Y    R180 S1      
327GND              U26   -T68        A01X+032905Y+092213X0177Y    R180 S1      
327GND              U26   -T71        A01X+031794Y+092213X0177Y    R180 S1      
327GND              U26   -T73        A01X+031054Y+092213X0177Y    R180 S1      
327GND              U26   -U1         A01X+057515Y+092532X0177Y    R180 S1      
327GND              U26   -U6         A01X+055664Y+092532X0177Y    R180 S1      
327GND              U26   -U8         A01X+054924Y+092532X0177Y    R180 S1      
327GND              U26   -U13        A01X+053074Y+092532X0177Y    R180 S1      
327GND              U26   -U15        A01X+052334Y+092532X0177Y    R180 S1      
327GND              U26   -U20        A01X+050483Y+092532X0177Y    R180 S1      
327GND              U26   -U22        A01X+049743Y+092532X0177Y    R180 S1      
327GND              U26   -U25        A01X+048633Y+092532X0177Y    R180 S1      
327GND              U26   -U28        A01X+047523Y+092532X0177Y    R180 S1      
327GND              U26   -U31        A01X+046413Y+092532X0177Y    R180 S1      
327GND              U26   -U34        A01X+045302Y+092532X0177Y    R180 S1      
327GND              U26   -U42        A01X+042712Y+092532X0177Y    R180 S1      
327GND              U26   -U45        A01X+041602Y+092532X0177Y    R180 S1      
327GND              U26   -U48        A01X+040491Y+092532X0177Y    R180 S1      
327GND              U26   -U51        A01X+039381Y+092532X0177Y    R180 S1      
327GND              U26   -U54        A01X+038271Y+092532X0177Y    R180 S1      
327GND              U26   -U56        A01X+037531Y+092532X0177Y    R180 S1      
327GND              U26   -U61        A01X+035680Y+092532X0177Y    R180 S1      
327GND              U26   -U63        A01X+034940Y+092532X0177Y    R180 S1      
327GND              U26   -U68        A01X+033090Y+092532X0177Y    R180 S1      
327GND              U26   -U70        A01X+032350Y+092532X0177Y    R180 S1      
327GND              U26   -U75        A01X+030499Y+092532X0177Y    R180 S1      
327GND              U26   -V3         A01X+056960Y+092850X0177Y    R180 S1      
327GND              U26   -V5         A01X+056220Y+092850X0177Y    R180 S1      
327GND              U26   -V8         A01X+055109Y+092850X0177Y    R180 S1      
327GND              U26   -V10        A01X+054369Y+092850X0177Y    R180 S1      
327GND              U26   -V12        A01X+053629Y+092850X0177Y    R180 S1      
327GND              U26   -V15        A01X+052519Y+092850X0177Y    R180 S1      
327GND              U26   -V17        A01X+051779Y+092850X0177Y    R180 S1      
327GND              U26   -V19        A01X+051038Y+092850X0177Y    R180 S1      
327GND              U26   -V23        A01X+049558Y+092850X0177Y    R180 S1      
327GND              U26   -V24        A01X+049188Y+092850X0177Y    R180 S1      
327GND              U26   -V25        A01X+048818Y+092850X0177Y    R180 S1      
327GND              U26   -V26        A01X+048448Y+092850X0177Y    R180 S1      
327GND              U26   -V28        A01X+047708Y+092850X0177Y    R180 S1      
327GND              U26   -V29        A01X+047338Y+092850X0177Y    R180 S1      
327GND              U26   -V30        A01X+046968Y+092850X0177Y    R180 S1      
327GND              U26   -V31        A01X+046598Y+092850X0177Y    R180 S1      
327GND              U26   -V32        A01X+046228Y+092850X0177Y    R180 S1      
327GND              U26   -V33        A01X+045857Y+092850X0177Y    R180 S1      
327GND              U26   -V34        A01X+045487Y+092850X0177Y    R180 S1      
327GND              U26   -V37        A01X+044377Y+092850X0177Y    R180 S1      
327GND              U26   -V39        A01X+043637Y+092850X0177Y    R180 S1      
327GND              U26   -V42        A01X+042527Y+092850X0177Y    R180 S1      
327GND              U26   -V43        A01X+042157Y+092850X0177Y    R180 S1      
327GND              U26   -V44        A01X+041787Y+092850X0177Y    R180 S1      
327GND              U26   -V45        A01X+041416Y+092850X0177Y    R180 S1      
327GND              U26   -V46        A01X+041046Y+092850X0177Y    R180 S1      
327GND              U26   -V47        A01X+040676Y+092850X0177Y    R180 S1      
327GND              U26   -V48        A01X+040306Y+092850X0177Y    R180 S1      
327GND              U26   -V49        A01X+039936Y+092850X0177Y    R180 S1      
327GND              U26   -V50        A01X+039566Y+092850X0177Y    R180 S1      
327GND              U26   -V51        A01X+039196Y+092850X0177Y    R180 S1      
327GND              U26   -V52        A01X+038826Y+092850X0177Y    R180 S1      
327GND              U26   -V53        A01X+038456Y+092850X0177Y    R180 S1      
327GND              U26   -V57        A01X+036976Y+092850X0177Y    R180 S1      
327GND              U26   -V59        A01X+036235Y+092850X0177Y    R180 S1      
327GND              U26   -V61        A01X+035495Y+092850X0177Y    R180 S1      
327GND              U26   -V64        A01X+034385Y+092850X0177Y    R180 S1      
327GND              U26   -V66        A01X+033645Y+092850X0177Y    R180 S1      
327GND              U26   -V71        A01X+031794Y+092850X0177Y    R180 S1      
327GND              U26   -V73        A01X+031054Y+092850X0177Y    R180 S1      
327GND              U26   -W1         A01X+057515Y+093169X0177Y    R180 S1      
327GND              U26   -W4         A01X+056405Y+093169X0177Y    R180 S1      
327GND              U26   -W6         A01X+055664Y+093169X0177Y    R180 S1      
327GND              U26   -W8         A01X+054924Y+093169X0177Y    R180 S1      
327GND              U26   -W11        A01X+053814Y+093169X0177Y    R180 S1      
327GND              U26   -W13        A01X+053074Y+093169X0177Y    R180 S1      
327GND              U26   -W15        A01X+052334Y+093169X0177Y    R180 S1      
327GND              U26   -W18        A01X+051224Y+093169X0177Y    R180 S1      
327GND              U26   -W20        A01X+050483Y+093169X0177Y    R180 S1      
327GND              U26   -W22        A01X+049743Y+093169X0177Y    R180 S1      
327GND              U26   -W25        A01X+048633Y+093169X0177Y    R180 S1      
327GND              U26   -W28        A01X+047523Y+093169X0177Y    R180 S1      
327GND              U26   -W34        A01X+045302Y+093169X0177Y    R180 S1      
327GND              U26   -W35        A01X+044932Y+093169X0177Y    R180 S1      
327GND              U26   -W36        A01X+044562Y+093169X0177Y    R180 S1      
327GND              U26   -W40        A01X+043452Y+093169X0177Y    R180 S1      
327GND              U26   -W41        A01X+043082Y+093169X0177Y    R180 S1      
327GND              U26   -W42        A01X+042712Y+093169X0177Y    R180 S1      
327GND              U26   -W45        A01X+041602Y+093169X0177Y    R180 S1      
327GND              U26   -W48        A01X+040491Y+093169X0177Y    R180 S1      
327GND              U26   -W51        A01X+039381Y+093169X0177Y    R180 S1      
327GND              U26   -W54        A01X+038271Y+093169X0177Y    R180 S1      
327GND              U26   -W56        A01X+037531Y+093169X0177Y    R180 S1      
327GND              U26   -W58        A01X+036790Y+093169X0177Y    R180 S1      
327GND              U26   -W61        A01X+035680Y+093169X0177Y    R180 S1      
327GND              U26   -W63        A01X+034940Y+093169X0177Y    R180 S1      
327GND              U26   -W65        A01X+034200Y+093169X0177Y    R180 S1      
327GND              U26   -W68        A01X+033090Y+093169X0177Y    R180 S1      
327GND              U26   -W70        A01X+032350Y+093169X0177Y    R180 S1      
327GND              U26   -W72        A01X+031609Y+093169X0177Y    R180 S1      
327GND              U26   -W75        A01X+030499Y+093169X0177Y    R180 S1      
327GND              U26   -Y3         A01X+056960Y+093488X0177Y    R180 S1      
327GND              U26   -Y8         A01X+055109Y+093488X0177Y    R180 S1      
327GND              U26   -Y10        A01X+054369Y+093488X0177Y    R180 S1      
327GND              U26   -Y15        A01X+052519Y+093488X0177Y    R180 S1      
327GND              U26   -Y17        A01X+051779Y+093488X0177Y    R180 S1      
327GND              U26   -Y22        A01X+049928Y+093488X0177Y    R180 S1      
327GND              U26   -Y23        A01X+049558Y+093488X0177Y    R180 S1      
327GND              U26   -Y24        A01X+049188Y+093488X0177Y    R180 S1      
327GND              U26   -Y25        A01X+048818Y+093488X0177Y    R180 S1      
327GND              U26   -Y26        A01X+048448Y+093488X0177Y    R180 S1      
327GND              U26   -Y27        A01X+048078Y+093488X0177Y    R180 S1      
327GND              U26   -Y28        A01X+047708Y+093488X0177Y    R180 S1      
327GND              U26   -Y31        A01X+046598Y+093488X0177Y    R180 S1      
327GND              U26   -Y32        A01X+046228Y+093488X0177Y    R180 S1      
327GND              U26   -Y33        A01X+045857Y+093488X0177Y    R180 S1      
327GND              U26   -Y34        A01X+045487Y+093488X0177Y    R180 S1      
327GND              U26   -Y37        A01X+044377Y+093488X0177Y    R180 S1      
327GND              U26   -Y39        A01X+043637Y+093488X0177Y    R180 S1      
327GND              U26   -Y42        A01X+042527Y+093488X0177Y    R180 S1      
327GND              U26   -Y43        A01X+042157Y+093488X0177Y    R180 S1      
327GND              U26   -Y44        A01X+041787Y+093488X0177Y    R180 S1      
327GND              U26   -Y45        A01X+041416Y+093488X0177Y    R180 S1      
327GND              U26   -Y48        A01X+040306Y+093488X0177Y    R180 S1      
327GND              U26   -Y49        A01X+039936Y+093488X0177Y    R180 S1      
327GND              U26   -Y50        A01X+039566Y+093488X0177Y    R180 S1      
327GND              U26   -Y51        A01X+039196Y+093488X0177Y    R180 S1      
327GND              U26   -Y52        A01X+038826Y+093488X0177Y    R180 S1      
327GND              U26   -Y53        A01X+038456Y+093488X0177Y    R180 S1      
327GND              U26   -Y54        A01X+038086Y+093488X0177Y    R180 S1      
327GND              U26   -Y59        A01X+036235Y+093488X0177Y    R180 S1      
327GND              U26   -Y61        A01X+035495Y+093488X0177Y    R180 S1      
327GND              U26   -Y66        A01X+033645Y+093488X0177Y    R180 S1      
327GND              U26   -Y68        A01X+032905Y+093488X0177Y    R180 S1      
327GND              U26   -Y73        A01X+031054Y+093488X0177Y    R180 S1      
327GND              U26   -J15        A01X+052334Y+089980X0177Y    R180 S1      
327GND              U26   -J18        A01X+051224Y+089980X0177Y    R180 S1      
327GND              U26   -J20        A01X+050483Y+089980X0177Y    R180 S1      
327GND              U26   -J22        A01X+049743Y+089980X0177Y    R180 S1      
327GND              U26   -J25        A01X+048633Y+089980X0177Y    R180 S1      
327GND              U26   -J28        A01X+047523Y+089980X0177Y    R180 S1      
327GND              U26   -J31        A01X+046413Y+089980X0177Y    R180 S1      
327GND              U26   -J34        A01X+045302Y+089980X0177Y    R180 S1      
327GND              U26   -J42        A01X+042712Y+089980X0177Y    R180 S1      
327GND              U26   -J45        A01X+041602Y+089980X0177Y    R180 S1      
327GND              U26   -J48        A01X+040491Y+089980X0177Y    R180 S1      
327GND              U26   -J51        A01X+039381Y+089980X0177Y    R180 S1      
327GND              U26   -J54        A01X+038271Y+089980X0177Y    R180 S1      
327GND              U26   -J56        A01X+037531Y+089980X0177Y    R180 S1      
327GND              U26   -J58        A01X+036790Y+089980X0177Y    R180 S1      
327GND              U26   -J61        A01X+035680Y+089980X0177Y    R180 S1      
327GND              U26   -J63        A01X+034940Y+089980X0177Y    R180 S1      
327GND              U26   -J65        A01X+034200Y+089980X0177Y    R180 S1      
327GND              U26   -J68        A01X+033090Y+089980X0177Y    R180 S1      
327GND              U26   -J70        A01X+032350Y+089980X0177Y    R180 S1      
327GND              U26   -J72        A01X+031609Y+089980X0177Y    R180 S1      
327GND              U26   -J75        A01X+030499Y+089980X0177Y    R180 S1      
327GND              U26   -K3         A01X+056960Y+090299X0177Y    R180 S1      
327GND              U26   -K5         A01X+056220Y+090299X0177Y    R180 S1      
327GND              U26   -K8         A01X+055109Y+090299X0177Y    R180 S1      
327GND              U26   -K10        A01X+054369Y+090299X0177Y    R180 S1      
327GND              U26   -K12        A01X+053629Y+090299X0177Y    R180 S1      
327GND              U26   -K15        A01X+052519Y+090299X0177Y    R180 S1      
327GND              U26   -K17        A01X+051779Y+090299X0177Y    R180 S1      
327GND              U26   -K19        A01X+051038Y+090299X0177Y    R180 S1      
327GND              U26   -K24        A01X+049188Y+090299X0177Y    R180 S1      
327GND              U26   -K25        A01X+048818Y+090299X0177Y    R180 S1      
327GND              U26   -K26        A01X+048448Y+090299X0177Y    R180 S1      
327GND              U26   -K27        A01X+048078Y+090299X0177Y    R180 S1      
327GND              U26   -K28        A01X+047708Y+090299X0177Y    R180 S1      
327GND              U26   -K29        A01X+047338Y+090299X0177Y    R180 S1      
327GND              U26   -K30        A01X+046968Y+090299X0177Y    R180 S1      
327GND              U26   -K31        A01X+046598Y+090299X0177Y    R180 S1      
327GND              U26   -K32        A01X+046228Y+090299X0177Y    R180 S1      
327GND              U26   -K33        A01X+045857Y+090299X0177Y    R180 S1      
327GND              U26   -K34        A01X+045487Y+090299X0177Y    R180 S1      
327GND              U26   -K37        A01X+044377Y+090299X0177Y    R180 S1      
327GND              U26   -K39        A01X+043637Y+090299X0177Y    R180 S1      
327GND              U26   -K42        A01X+042527Y+090299X0177Y    R180 S1      
327GND              U26   -K43        A01X+042157Y+090299X0177Y    R180 S1      
327GND              U26   -K44        A01X+041787Y+090299X0177Y    R180 S1      
327GND              U26   -K45        A01X+041416Y+090299X0177Y    R180 S1      
327GND              U26   -K46        A01X+041046Y+090299X0177Y    R180 S1      
327GND              U26   -K47        A01X+040676Y+090299X0177Y    R180 S1      
327GND              U26   -K48        A01X+040306Y+090299X0177Y    R180 S1      
327GND              U26   -K49        A01X+039936Y+090299X0177Y    R180 S1      
327GND              U26   -K50        A01X+039566Y+090299X0177Y    R180 S1      
327GND              U26   -K51        A01X+039196Y+090299X0177Y    R180 S1      
327GND              U26   -K52        A01X+038826Y+090299X0177Y    R180 S1      
327GND              U26   -K53        A01X+038456Y+090299X0177Y    R180 S1      
327GND              U26   -K57        A01X+036976Y+090299X0177Y    R180 S1      
327GND              U26   -K61        A01X+035495Y+090299X0177Y    R180 S1      
327GND              U26   -K64        A01X+034385Y+090299X0177Y    R180 S1      
327GND              U26   -K66        A01X+033645Y+090299X0177Y    R180 S1      
327GND              U26   -K68        A01X+032905Y+090299X0177Y    R180 S1      
327GND              U26   -K71        A01X+031794Y+090299X0177Y    R180 S1      
327GND              U26   -K73        A01X+031054Y+090299X0177Y    R180 S1      
327GND              U26   -L1         A01X+057515Y+090618X0177Y    R180 S1      
327GND              U26   -L6         A01X+055664Y+090618X0177Y    R180 S1      
327GND              U26   -L8         A01X+054924Y+090618X0177Y    R180 S1      
327GND              U26   -L13        A01X+053074Y+090618X0177Y    R180 S1      
327GND              U26   -L15        A01X+052334Y+090618X0177Y    R180 S1      
327GND              U26   -L20        A01X+050483Y+090618X0177Y    R180 S1      
327GND              U26   -L22        A01X+049743Y+090618X0177Y    R180 S1      
327GND              U26   -L25        A01X+048633Y+090618X0177Y    R180 S1      
327GND              U26   -L28        A01X+047523Y+090618X0177Y    R180 S1      
327GND              U26   -L31        A01X+046413Y+090618X0177Y    R180 S1      
327GND              U26   -L34        A01X+045302Y+090618X0177Y    R180 S1      
327GND              U26   -L35        A01X+044932Y+090618X0177Y    R180 S1      
327GND              U26   -L36        A01X+044562Y+090618X0177Y    R180 S1      
327GND              U26   -L40        A01X+043452Y+090618X0177Y    R180 S1      
327GND              U26   -L41        A01X+043082Y+090618X0177Y    R180 S1      
327GND              U26   -L42        A01X+042712Y+090618X0177Y    R180 S1      
327GND              U26   -L45        A01X+041602Y+090618X0177Y    R180 S1      
327GND              U26   -L48        A01X+040491Y+090618X0177Y    R180 S1      
327GND              U26   -L51        A01X+039381Y+090618X0177Y    R180 S1      
327GND              U26   -L54        A01X+038271Y+090618X0177Y    R180 S1      
327GND              U26   -L56        A01X+037531Y+090618X0177Y    R180 S1      
327GND              U26   -L61        A01X+035680Y+090618X0177Y    R180 S1      
327GND              U26   -L63        A01X+034940Y+090618X0177Y    R180 S1      
327GND              U26   -L68        A01X+033090Y+090618X0177Y    R180 S1      
327GND              U26   -L70        A01X+032350Y+090618X0177Y    R180 S1      
327GND              U26   -L75        A01X+030499Y+090618X0177Y    R180 S1      
327GND              U26   -M3         A01X+056960Y+090937X0177Y    R180 S1      
327GND              U26   -M5         A01X+056220Y+090937X0177Y    R180 S1      
327GND              U26   -M8         A01X+055109Y+090937X0177Y    R180 S1      
327GND              U26   -M12        A01X+053629Y+090937X0177Y    R180 S1      
327GND              U26   -M17        A01X+051779Y+090937X0177Y    R180 S1      
327GND              U26   -M19        A01X+051038Y+090937X0177Y    R180 S1      
327GND              U26   -M22        A01X+049928Y+090937X0177Y    R180 S1      
327GND              U26   -M28        A01X+047708Y+090937X0177Y    R180 S1      
327GND              U26   -M31        A01X+046598Y+090937X0177Y    R180 S1      
327GND              U26   -M37        A01X+044377Y+090937X0177Y    R180 S1      
327GND              U26   -M39        A01X+043637Y+090937X0177Y    R180 S1      
327GND              U26   -M45        A01X+041416Y+090937X0177Y    R180 S1      
327GND              U26   -M51        A01X+039196Y+090937X0177Y    R180 S1      
327GND              U26   -M54        A01X+038086Y+090937X0177Y    R180 S1      
327GND              U26   -M59        A01X+036235Y+090937X0177Y    R180 S1      
327GND              U26   -M64        A01X+034385Y+090937X0177Y    R180 S1      
327GND              U26   -M68        A01X+032905Y+090937X0177Y    R180 S1      
327GND              U26   -M71        A01X+031794Y+090937X0177Y    R180 S1      
327GND              U26   -M73        A01X+031054Y+090937X0177Y    R180 S1      
327GND              U26   -N1         A01X+057515Y+091256X0177Y    R180 S1      
327GND              U26   -N4         A01X+056405Y+091256X0177Y    R180 S1      
327GND              U26   -N6         A01X+055664Y+091256X0177Y    R180 S1      
327GND              U26   -N8         A01X+054924Y+091256X0177Y    R180 S1      
327GND              U26   -N11        A01X+053814Y+091256X0177Y    R180 S1      
327GND              U26   -N13        A01X+053074Y+091256X0177Y    R180 S1      
327GND              U26   -N15        A01X+052334Y+091256X0177Y    R180 S1      
327GND              U26   -N18        A01X+051224Y+091256X0177Y    R180 S1      
327GND              U26   -N20        A01X+050483Y+091256X0177Y    R180 S1      
327GND              U26   -N22        A01X+049743Y+091256X0177Y    R180 S1      
327GND              U26   -N25        A01X+048633Y+091256X0177Y    R180 S1      
327GND              U26   -N28        A01X+047523Y+091256X0177Y    R180 S1      
327GND              U26   -N31        A01X+046413Y+091256X0177Y    R180 S1      
327GND              U26   -N34        A01X+045302Y+091256X0177Y    R180 S1      
327GND              U26   -N42        A01X+042712Y+091256X0177Y    R180 S1      
327GND              U26   -N45        A01X+041602Y+091256X0177Y    R180 S1      
327GND              U26   -N48        A01X+040491Y+091256X0177Y    R180 S1      
327GND              U26   -N51        A01X+039381Y+091256X0177Y    R180 S1      
327GND              U26   -N54        A01X+038271Y+091256X0177Y    R180 S1      
327GND              U26   -N56        A01X+037531Y+091256X0177Y    R180 S1      
327GND              U26   -N58        A01X+036790Y+091256X0177Y    R180 S1      
327GND              U26   -N61        A01X+035680Y+091256X0177Y    R180 S1      
327GND              U26   -N63        A01X+034940Y+091256X0177Y    R180 S1      
327GND              U26   -N65        A01X+034200Y+091256X0177Y    R180 S1      
327GND              U26   -N68        A01X+033090Y+091256X0177Y    R180 S1      
327GND              U26   -N70        A01X+032350Y+091256X0177Y    R180 S1      
327GND              U26   -N72        A01X+031609Y+091256X0177Y    R180 S1      
327GND              U26   -N75        A01X+030499Y+091256X0177Y    R180 S1      
327GND              U26   -P3         A01X+056960Y+091575X0177Y    R180 S1      
327GND              U26   -P8         A01X+055109Y+091575X0177Y    R180 S1      
327GND              U26   -P10        A01X+054369Y+091575X0177Y    R180 S1      
327GND              U26   -P15        A01X+052519Y+091575X0177Y    R180 S1      
327GND              U26   -P17        A01X+051779Y+091575X0177Y    R180 S1      
327GND              U26   -P23        A01X+049558Y+091575X0177Y    R180 S1      
327GND              U26   -P24        A01X+049188Y+091575X0177Y    R180 S1      
327GND              U26   -P26        A01X+048448Y+091575X0177Y    R180 S1      
327GND              U26   -P27        A01X+048078Y+091575X0177Y    R180 S1      
327GND              U26   -P28        A01X+047708Y+091575X0177Y    R180 S1      
327GND              U26   -P29        A01X+047338Y+091575X0177Y    R180 S1      
327GND              U26   -P30        A01X+046968Y+091575X0177Y    R180 S1      
327GND              U26   -P31        A01X+046598Y+091575X0177Y    R180 S1      
327GND              U26   -P32        A01X+046228Y+091575X0177Y    R180 S1      
327GND              U26   -P33        A01X+045857Y+091575X0177Y    R180 S1      
327GND              U26   -P34        A01X+045487Y+091575X0177Y    R180 S1      
327GND              U26   -P37        A01X+044377Y+091575X0177Y    R180 S1      
327GND              U26   -P39        A01X+043637Y+091575X0177Y    R180 S1      
327GND              U26   -P42        A01X+042527Y+091575X0177Y    R180 S1      
327GND              U26   -P43        A01X+042157Y+091575X0177Y    R180 S1      
327GND              U26   -P44        A01X+041787Y+091575X0177Y    R180 S1      
327GND              U26   -P45        A01X+041416Y+091575X0177Y    R180 S1      
327GND              U26   -P46        A01X+041046Y+091575X0177Y    R180 S1      
327GND              U26   -P47        A01X+040676Y+091575X0177Y    R180 S1      
327GND              U26   -P48        A01X+040306Y+091575X0177Y    R180 S1      
327GND              U26   -P49        A01X+039936Y+091575X0177Y    R180 S1      
327GND              U26   -P50        A01X+039566Y+091575X0177Y    R180 S1      
327GND              U26   -P51        A01X+039196Y+091575X0177Y    R180 S1      
327GND              U26   -P52        A01X+038826Y+091575X0177Y    R180 S1      
327GND              U26   -P53        A01X+038456Y+091575X0177Y    R180 S1      
327GND              U26   -P59        A01X+036235Y+091575X0177Y    R180 S1      
327GND              U26   -P61        A01X+035495Y+091575X0177Y    R180 S1      
327GND              U26   -P66        A01X+033645Y+091575X0177Y    R180 S1      
327GND              U26   -P73        A01X+031054Y+091575X0177Y    R180 S1      
327GND              U26   -R1         A01X+057515Y+091894X0177Y    R180 S1      
327GND              U26   -R4         A01X+056405Y+091894X0177Y    R180 S1      
327GND              U26   -R6         A01X+055664Y+091894X0177Y    R180 S1      
327GND              U26   -R8         A01X+054924Y+091894X0177Y    R180 S1      
327GND              U26   -R11        A01X+053814Y+091894X0177Y    R180 S1      
327GND              U26   -R13        A01X+053074Y+091894X0177Y    R180 S1      
327GND              U26   -R15        A01X+052334Y+091894X0177Y    R180 S1      
327GND              U26   -R18        A01X+051224Y+091894X0177Y    R180 S1      
327GND              U26   -R20        A01X+050483Y+091894X0177Y    R180 S1      
327GND              U26   -R22        A01X+049743Y+091894X0177Y    R180 S1      
327GND              U26   -R25        A01X+048633Y+091894X0177Y    R180 S1      
327GND              U26   -R28        A01X+047523Y+091894X0177Y    R180 S1      
327GND              U26   -R31        A01X+046413Y+091894X0177Y    R180 S1      
327GND              U26   -R34        A01X+045302Y+091894X0177Y    R180 S1      
327GND              U26   -R35        A01X+044932Y+091894X0177Y    R180 S1      
327GND              U26   -R36        A01X+044562Y+091894X0177Y    R180 S1      
327GND              U26   -R40        A01X+043452Y+091894X0177Y    R180 S1      
327GND              U26   -R41        A01X+043082Y+091894X0177Y    R180 S1      
327GND              U26   -R42        A01X+042712Y+091894X0177Y    R180 S1      
327GND              U26   -R45        A01X+041602Y+091894X0177Y    R180 S1      
327GND              U26   -R48        A01X+040491Y+091894X0177Y    R180 S1      
327GND              U26   -R51        A01X+039381Y+091894X0177Y    R180 S1      
327GND              U26   -R54        A01X+038271Y+091894X0177Y    R180 S1      
327GND              U26   -R56        A01X+037531Y+091894X0177Y    R180 S1      
327GND              U26   -R58        A01X+036790Y+091894X0177Y    R180 S1      
327GND              U26   -R61        A01X+035680Y+091894X0177Y    R180 S1      
327GND              U26   -R63        A01X+034940Y+091894X0177Y    R180 S1      
327GND              U26   -R65        A01X+034200Y+091894X0177Y    R180 S1      
327GND              U26   -R68        A01X+033090Y+091894X0177Y    R180 S1      
327GND              U26   -R70        A01X+032350Y+091894X0177Y    R180 S1      
327GND              U26   -R72        A01X+031609Y+091894X0177Y    R180 S1      
327GND              U26   -R75        A01X+030499Y+091894X0177Y    R180 S1      
327GND              U26   -T3         A01X+056960Y+092213X0177Y    R180 S1      
327GND              U26   -T5         A01X+056220Y+092213X0177Y    R180 S1      
327GND              U26   -T8         A01X+055109Y+092213X0177Y    R180 S1      
327GND              U26   -T10        A01X+054369Y+092213X0177Y    R180 S1      
327GND              U26   -T12        A01X+053629Y+092213X0177Y    R180 S1      
327GND              U26   -T15        A01X+052519Y+092213X0177Y    R180 S1      
327GND              U26   -T17        A01X+051779Y+092213X0177Y    R180 S1      
327GND              U26   -T19        A01X+051038Y+092213X0177Y    R180 S1      
327GND              U26   -T22        A01X+049928Y+092213X0177Y    R180 S1      
327GND              U26   -T25        A01X+048818Y+092213X0177Y    R180 S1      
327GND              U26   -T28        A01X+047708Y+092213X0177Y    R180 S1      
327GND              U26   -T31        A01X+046598Y+092213X0177Y    R180 S1      
327GND              U26   -T34        A01X+045487Y+092213X0177Y    R180 S1      
327GND              U26   -T37        A01X+044377Y+092213X0177Y    R180 S1      
327GND              U26   -T39        A01X+043637Y+092213X0177Y    R180 S1      
327GND              U26   -T42        A01X+042527Y+092213X0177Y    R180 S1      
327GND              U26   -T45        A01X+041416Y+092213X0177Y    R180 S1      
327GND              U26   -T48        A01X+040306Y+092213X0177Y    R180 S1      
327GND              U26   -T51        A01X+039196Y+092213X0177Y    R180 S1      
327GND              U26   -T54        A01X+038086Y+092213X0177Y    R180 S1      
327GND              U26   -T57        A01X+036976Y+092213X0177Y    R180 S1      
327GND              U26   -T59        A01X+036235Y+092213X0177Y    R180 S1      
327GND              U26   -T61        A01X+035495Y+092213X0177Y    R180 S1      
327GND              U26   -T64        A01X+034385Y+092213X0177Y    R180 S1      
327GND              U26   -BL26       A01X+048381Y+104295X0177Y    R180 S1      
327GND              U26   -BL28       A01X+047641Y+104295X0177Y    R180 S1      
327GND              U26   -BL49       A01X+040239Y+104295X0177Y    R180 S1      
327GND              U26   -BL51       A01X+039499Y+104295X0177Y    R180 S1      
327GND              U26   -BL53       A01X+038759Y+104295X0177Y    R180 S1      
327GND              U26   -BL56       A01X+037649Y+104295X0177Y    R180 S1      
327GND              U26   -BL58       A01X+036909Y+104295X0177Y    R180 S1      
327GND              U26   -BL61       A01X+035798Y+104295X0177Y    R180 S1      
327GND              U26   -BL63       A01X+035058Y+104295X0177Y    R180 S1      
327GND              U26   -BL65       A01X+034318Y+104295X0177Y    R180 S1      
327GND              U26   -BL68       A01X+033208Y+104295X0177Y    R180 S1      
327GND              U26   -BL70       A01X+032468Y+104295X0177Y    R180 S1      
327GND              U26   -BL72       A01X+031728Y+104295X0177Y    R180 S1      
327GND              U26   -BL75       A01X+030617Y+104295X0177Y    R180 S1      
327GND              U26   -BM3        A01X+057078Y+104614X0177Y    R180 S1      
327GND              U26   -BM8        A01X+055228Y+104614X0177Y    R180 S1      
327GND              U26   -BM10       A01X+054487Y+104614X0177Y    R180 S1      
327GND              U26   -BM15       A01X+052637Y+104614X0177Y    R180 S1      
327GND              U26   -BM17       A01X+051897Y+104614X0177Y    R180 S1      
327GND              U26   -BM23       A01X+049676Y+104614X0177Y    R180 S1      
327GND              U26   -BM25       A01X+048936Y+104614X0177Y    R180 S1      
327GND              U26   -BM27       A01X+048196Y+104614X0177Y    R180 S1      
327GND              U26   -BM29       A01X+047456Y+104614X0177Y    R180 S1      
327GND              U26   -BM31       A01X+046716Y+104614X0177Y    R180 S1      
327GND              U26   -BM33       A01X+045976Y+104614X0177Y    R180 S1      
327GND              U26   -BM35       A01X+045235Y+104614X0177Y    R180 S1      
327GND              U26   -BM37       A01X+044495Y+104614X0177Y    R180 S1      
327GND              U26   -BM40       A01X+043385Y+104614X0177Y    R180 S1      
327GND              U26   -BM42       A01X+042645Y+104614X0177Y    R180 S1      
327GND              U26   -BM44       A01X+041905Y+104614X0177Y    R180 S1      
327GND              U26   -BM46       A01X+041164Y+104614X0177Y    R180 S1      
327GND              U26   -BM48       A01X+040424Y+104614X0177Y    R180 S1      
327GND              U26   -BM50       A01X+039684Y+104614X0177Y    R180 S1      
327GND              U26   -BM52       A01X+038944Y+104614X0177Y    R180 S1      
327GND              U26   -BM54       A01X+038204Y+104614X0177Y    R180 S1      
327GND              U26   -BM59       A01X+036354Y+104614X0177Y    R180 S1      
327GND              U26   -BM61       A01X+035613Y+104614X0177Y    R180 S1      
327GND              U26   -BM66       A01X+033763Y+104614X0177Y    R180 S1      
327GND              U26   -BM68       A01X+033023Y+104614X0177Y    R180 S1      
327GND              U26   -BM73       A01X+031172Y+104614X0177Y    R180 S1      
327GND              U26   -BN1        A01X+057633Y+104933X0177Y    R180 S1      
327GND              U26   -BN4        A01X+056523Y+104933X0177Y    R180 S1      
327GND              U26   -BN6        A01X+055783Y+104933X0177Y    R180 S1      
327GND              U26   -BN8        A01X+055042Y+104933X0177Y    R180 S1      
327GND              U26   -BN11       A01X+053932Y+104933X0177Y    R180 S1      
327GND              U26   -BN13       A01X+053192Y+104933X0177Y    R180 S1      
327GND              U26   -BN15       A01X+052452Y+104933X0177Y    R180 S1      
327GND              U26   -BN18       A01X+051342Y+104933X0177Y    R180 S1      
327GND              U26   -BN20       A01X+050602Y+104933X0177Y    R180 S1      
327GND              U26   -BN22       A01X+049861Y+104933X0177Y    R180 S1      
327GND              U26   -BN24       A01X+049121Y+104933X0177Y    R180 S1      
327GND              U26   -BN26       A01X+048381Y+104933X0177Y    R180 S1      
327GND              U26   -BN28       A01X+047641Y+104933X0177Y    R180 S1      
327GND              U26   -BN30       A01X+046901Y+104933X0177Y    R180 S1      
327GND              U26   -BN32       A01X+046161Y+104933X0177Y    R180 S1      
327GND              U26   -BN34       A01X+045420Y+104933X0177Y    R180 S1      
327GND              U26   -BN36       A01X+044680Y+104933X0177Y    R180 S1      
327GND              U26   -BN41       A01X+043200Y+104933X0177Y    R180 S1      
327GND              U26   -BN43       A01X+042460Y+104933X0177Y    R180 S1      
327GND              U26   -BN45       A01X+041720Y+104933X0177Y    R180 S1      
327GND              U26   -BN47       A01X+040980Y+104933X0177Y    R180 S1      
327GND              U26   -BN49       A01X+040239Y+104933X0177Y    R180 S1      
327GND              U26   -BN51       A01X+039499Y+104933X0177Y    R180 S1      
327GND              U26   -BN53       A01X+038759Y+104933X0177Y    R180 S1      
327GND              U26   -BN56       A01X+037649Y+104933X0177Y    R180 S1      
327GND              U26   -BN58       A01X+036909Y+104933X0177Y    R180 S1      
327GND              U26   -BN61       A01X+035798Y+104933X0177Y    R180 S1      
327GND              U26   -BN63       A01X+035058Y+104933X0177Y    R180 S1      
327GND              U26   -BN65       A01X+034318Y+104933X0177Y    R180 S1      
327GND              U26   -BN68       A01X+033208Y+104933X0177Y    R180 S1      
327GND              U26   -BN70       A01X+032468Y+104933X0177Y    R180 S1      
327GND              U26   -BN72       A01X+031728Y+104933X0177Y    R180 S1      
327GND              U26   -BN75       A01X+030617Y+104933X0177Y    R180 S1      
327GND              U26   -BP3        A01X+057078Y+105252X0177Y    R180 S1      
327GND              U26   -BP5        A01X+056338Y+105252X0177Y    R180 S1      
327GND              U26   -BP8        A01X+055228Y+105252X0177Y    R180 S1      
327GND              U26   -BP10       A01X+054487Y+105252X0177Y    R180 S1      
327GND              U26   -BP12       A01X+053747Y+105252X0177Y    R180 S1      
327GND              U26   -BP15       A01X+052637Y+105252X0177Y    R180 S1      
327GND              U26   -BP17       A01X+051897Y+105252X0177Y    R180 S1      
327GND              U26   -BP19       A01X+051157Y+105252X0177Y    R180 S1      
327GND              U26   -BP23       A01X+049676Y+105252X0177Y    R180 S1      
327GND              U26   -BP25       A01X+048936Y+105252X0177Y    R180 S1      
327GND              U26   -BP27       A01X+048196Y+105252X0177Y    R180 S1      
327GND              U26   -BP29       A01X+047456Y+105252X0177Y    R180 S1      
327GND              U26   -BP31       A01X+046716Y+105252X0177Y    R180 S1      
327GND              U26   -BP33       A01X+045976Y+105252X0177Y    R180 S1      
327GND              U26   -BP35       A01X+045235Y+105252X0177Y    R180 S1      
327GND              U26   -BP37       A01X+044495Y+105252X0177Y    R180 S1      
327GND              U26   -BP40       A01X+043385Y+105252X0177Y    R180 S1      
327GND              U26   -BP42       A01X+042645Y+105252X0177Y    R180 S1      
327GND              U26   -BP44       A01X+041905Y+105252X0177Y    R180 S1      
327GND              U26   -BP46       A01X+041164Y+105252X0177Y    R180 S1      
327GND              U26   -BP48       A01X+040424Y+105252X0177Y    R180 S1      
327GND              U26   -BP50       A01X+039684Y+105252X0177Y    R180 S1      
327GND              U26   -BP52       A01X+038944Y+105252X0177Y    R180 S1      
327GND              U26   -BP54       A01X+038204Y+105252X0177Y    R180 S1      
327GND              U26   -BP57       A01X+037094Y+105252X0177Y    R180 S1      
327GND              U26   -BP59       A01X+036354Y+105252X0177Y    R180 S1      
327GND              U26   -BP61       A01X+035613Y+105252X0177Y    R180 S1      
327GND              U26   -BP64       A01X+034503Y+105252X0177Y    R180 S1      
327GND              U26   -BP66       A01X+033763Y+105252X0177Y    R180 S1      
327GND              U26   -BP68       A01X+033023Y+105252X0177Y    R180 S1      
327GND              U26   -BP71       A01X+031913Y+105252X0177Y    R180 S1      
327GND              U26   -BP73       A01X+031172Y+105252X0177Y    R180 S1      
327GND              U26   -BR1        A01X+057633Y+105571X0177Y    R180 S1      
327GND              U26   -BR3        A01X+056893Y+105571X0177Y    R180 S1      
327GND              U26   -BR6        A01X+055783Y+105571X0177Y    R180 S1      
327GND              U26   -BR7        A01X+055413Y+105571X0177Y    R180 S1      
327GND              U26   -BR8        A01X+055042Y+105571X0177Y    R180 S1      
327GND              U26   -BR10       A01X+054302Y+105571X0177Y    R180 S1      
327GND              U26   -BR13       A01X+053192Y+105571X0177Y    R180 S1      
327GND              U26   -BR14       A01X+052822Y+105571X0177Y    R180 S1      
327GND              U26   -BR15       A01X+052452Y+105571X0177Y    R180 S1      
327GND              U26   -BR17       A01X+051712Y+105571X0177Y    R180 S1      
327GND              U26   -BR20       A01X+050602Y+105571X0177Y    R180 S1      
327GND              U26   -BR21       A01X+050232Y+105571X0177Y    R180 S1      
327GND              U26   -BR22       A01X+049861Y+105571X0177Y    R180 S1      
327GND              U26   -BR24       A01X+049121Y+105571X0177Y    R180 S1      
327GND              U26   -BR26       A01X+048381Y+105571X0177Y    R180 S1      
327GND              U26   -BR28       A01X+047641Y+105571X0177Y    R180 S1      
327GND              U26   -BR30       A01X+046901Y+105571X0177Y    R180 S1      
327GND              U26   -BR32       A01X+046161Y+105571X0177Y    R180 S1      
327GND              U26   -BR34       A01X+045420Y+105571X0177Y    R180 S1      
327GND              U26   -BR36       A01X+044680Y+105571X0177Y    R180 S1      
327GND              U26   -BR41       A01X+043200Y+105571X0177Y    R180 S1      
327GND              U26   -BR43       A01X+042460Y+105571X0177Y    R180 S1      
327GND              U26   -BR45       A01X+041720Y+105571X0177Y    R180 S1      
327GND              U26   -BR47       A01X+040980Y+105571X0177Y    R180 S1      
327GND              U26   -BR49       A01X+040239Y+105571X0177Y    R180 S1      
327GND              U26   -BR51       A01X+039499Y+105571X0177Y    R180 S1      
327GND              U26   -BR55       A01X+038019Y+105571X0177Y    R180 S1      
327GND              U26   -BR56       A01X+037649Y+105571X0177Y    R180 S1      
327GND              U26   -BR59       A01X+036538Y+105571X0177Y    R180 S1      
327GND              U26   -BR61       A01X+035798Y+105571X0177Y    R180 S1      
327GND              U26   -BR62       A01X+035428Y+105571X0177Y    R180 S1      
327GND              U26   -BR63       A01X+035058Y+105571X0177Y    R180 S1      
327GND              U26   -BR66       A01X+033948Y+105571X0177Y    R180 S1      
327GND              U26   -BR68       A01X+033208Y+105571X0177Y    R180 S1      
327GND              U26   -BR69       A01X+032838Y+105571X0177Y    R180 S1      
327GND              U26   -BR70       A01X+032468Y+105571X0177Y    R180 S1      
327GND              U26   -BR73       A01X+031357Y+105571X0177Y    R180 S1      
327GND              U26   -BR75       A01X+030617Y+105571X0177Y    R180 S1      
327GND              U26   -BT3        A01X+057078Y+105890X0177Y    R180 S1      
327GND              U26   -BT4        A01X+056708Y+105890X0177Y    R180 S1      
327GND              U26   -BT5        A01X+056338Y+105890X0177Y    R180 S1      
327GND              U26   -BT7        A01X+055598Y+105890X0177Y    R180 S1      
327GND              U26   -BT8        A01X+055228Y+105890X0177Y    R180 S1      
327GND              U26   -BT10       A01X+054487Y+105890X0177Y    R180 S1      
327GND              U26   -BT11       A01X+054117Y+105890X0177Y    R180 S1      
327GND              U26   -BT12       A01X+053747Y+105890X0177Y    R180 S1      
327GND              U26   -BT14       A01X+053007Y+105890X0177Y    R180 S1      
327GND              U26   -BT15       A01X+052637Y+105890X0177Y    R180 S1      
327GND              U26   -BT17       A01X+051897Y+105890X0177Y    R180 S1      
327GND              U26   -BT18       A01X+051527Y+105890X0177Y    R180 S1      
327GND              U26   -BT19       A01X+051157Y+105890X0177Y    R180 S1      
327GND              U26   -BT21       A01X+050416Y+105890X0177Y    R180 S1      
327GND              U26   -BT22       A01X+050046Y+105890X0177Y    R180 S1      
327GND              U26   -BT25       A01X+048936Y+105890X0177Y    R180 S1      
327GND              U26   -BT28       A01X+047826Y+105890X0177Y    R180 S1      
327GND              U26   -BT31       A01X+046716Y+105890X0177Y    R180 S1      
327GND              U26   -BT34       A01X+045606Y+105890X0177Y    R180 S1      
327GND              U26   -BT37       A01X+044495Y+105890X0177Y    R180 S1      
327GND              U26   -BT39       A01X+043755Y+105890X0177Y    R180 S1      
327GND              U26   -BT42       A01X+042645Y+105890X0177Y    R180 S1      
327GND              U26   -BT45       A01X+041535Y+105890X0177Y    R180 S1      
327GND              U26   -BT48       A01X+040424Y+105890X0177Y    R180 S1      
327GND              U26   -BT51       A01X+039314Y+105890X0177Y    R180 S1      
327GND              U26   -BT54       A01X+038204Y+105890X0177Y    R180 S1      
327GND              U26   -BT55       A01X+037834Y+105890X0177Y    R180 S1      
327GND              U26   -BT57       A01X+037094Y+105890X0177Y    R180 S1      
327GND              U26   -BT58       A01X+036724Y+105890X0177Y    R180 S1      
327GND              U26   -BT59       A01X+036354Y+105890X0177Y    R180 S1      
327GND              U26   -BT61       A01X+035613Y+105890X0177Y    R180 S1      
327GND              U26   -BT62       A01X+035243Y+105890X0177Y    R180 S1      
327GND              U26   -BT64       A01X+034503Y+105890X0177Y    R180 S1      
327GND              U26   -BT65       A01X+034133Y+105890X0177Y    R180 S1      
327GND              U26   -BT66       A01X+033763Y+105890X0177Y    R180 S1      
327GND              U26   -BT68       A01X+033023Y+105890X0177Y    R180 S1      
327GND              U26   -BT69       A01X+032653Y+105890X0177Y    R180 S1      
327GND              U26   -BT71       A01X+031913Y+105890X0177Y    R180 S1      
327GND              U26   -BT72       A01X+031542Y+105890X0177Y    R180 S1      
327GND              U26   -BT73       A01X+031172Y+105890X0177Y    R180 S1      
327GND              U26   -BU1        A01X+057633Y+106209X0177Y    R180 S1      
327GND              U26   -BU4        A01X+056523Y+106209X0177Y    R180 S1      
327GND              U26   -BU6        A01X+055783Y+106209X0177Y    R180 S1      
327GND              U26   -BU8        A01X+055042Y+106209X0177Y    R180 S1      
327GND              U26   -BU11       A01X+053932Y+106209X0177Y    R180 S1      
327GND              U26   -BU13       A01X+053192Y+106209X0177Y    R180 S1      
327GND              U26   -BU15       A01X+052452Y+106209X0177Y    R180 S1      
327GND              U26   -BU18       A01X+051342Y+106209X0177Y    R180 S1      
327GND              U26   -BU20       A01X+050602Y+106209X0177Y    R180 S1      
327GND              U26   -BU22       A01X+049861Y+106209X0177Y    R180 S1      
327GND              U26   -BU25       A01X+048751Y+106209X0177Y    R180 S1      
327GND              U26   -BU28       A01X+047641Y+106209X0177Y    R180 S1      
327GND              U26   -BU31       A01X+046531Y+106209X0177Y    R180 S1      
327GND              U26   -BU34       A01X+045420Y+106209X0177Y    R180 S1      
327GND              U26   -BU35       A01X+045050Y+106209X0177Y    R180 S1      
327GND              U26   -BU36       A01X+044680Y+106209X0177Y    R180 S1      
327GND              U26   -BU40       A01X+043570Y+106209X0177Y    R180 S1      
327GND              U26   -BU41       A01X+043200Y+106209X0177Y    R180 S1      
327GND              U26   -BU42       A01X+042830Y+106209X0177Y    R180 S1      
327GND              U26   -BU45       A01X+041720Y+106209X0177Y    R180 S1      
327GND              U26   -BU48       A01X+040609Y+106209X0177Y    R180 S1      
327GND              U26   -BU51       A01X+039499Y+106209X0177Y    R180 S1      
327GND              U26   -BU54       A01X+038389Y+106209X0177Y    R180 S1      
327GND              U26   -BU56       A01X+037649Y+106209X0177Y    R180 S1      
327GND              U26   -BU58       A01X+036909Y+106209X0177Y    R180 S1      
327GND              U26   -BU61       A01X+035798Y+106209X0177Y    R180 S1      
327GND              U26   -BU63       A01X+035058Y+106209X0177Y    R180 S1      
327GND              U26   -BU65       A01X+034318Y+106209X0177Y    R180 S1      
327GND              U26   -BU68       A01X+033208Y+106209X0177Y    R180 S1      
327GND              U26   -BU70       A01X+032468Y+106209X0177Y    R180 S1      
327GND              U26   -BU72       A01X+031728Y+106209X0177Y    R180 S1      
327GND              U26   -BU75       A01X+030617Y+106209X0177Y    R180 S1      
327GND              U26   -BV3        A01X+057078Y+106528X0177Y    R180 S1      
327GND              U26   -BV8        A01X+055228Y+106528X0177Y    R180 S1      
327GND              U26   -BV10       A01X+054487Y+106528X0177Y    R180 S1      
327GND              U26   -BV15       A01X+052637Y+106528X0177Y    R180 S1      
327GND              U26   -BV17       A01X+051897Y+106528X0177Y    R180 S1      
327GND              U26   -BV23       A01X+049676Y+106528X0177Y    R180 S1      
327GND              U26   -BV24       A01X+049306Y+106528X0177Y    R180 S1      
327GND              U26   -BV25       A01X+048936Y+106528X0177Y    R180 S1      
327GND              U26   -BV26       A01X+048566Y+106528X0177Y    R180 S1      
327GND              U26   -BV27       A01X+048196Y+106528X0177Y    R180 S1      
327GND              U26   -BV28       A01X+047826Y+106528X0177Y    R180 S1      
327GND              U26   -BV29       A01X+047456Y+106528X0177Y    R180 S1      
327GND              U26   -BV30       A01X+047086Y+106528X0177Y    R180 S1      
327GND              U26   -BV31       A01X+046716Y+106528X0177Y    R180 S1      
327GND              U26   -BV32       A01X+046346Y+106528X0177Y    R180 S1      
327GND              U26   -BV33       A01X+045976Y+106528X0177Y    R180 S1      
327GND              U26   -BV34       A01X+045606Y+106528X0177Y    R180 S1      
327GND              U26   -BV37       A01X+044495Y+106528X0177Y    R180 S1      
327GND              U26   -BV39       A01X+043755Y+106528X0177Y    R180 S1      
327GND              U26   -BV43       A01X+042275Y+106528X0177Y    R180 S1      
327GND              U26   -BV44       A01X+041905Y+106528X0177Y    R180 S1      
327GND              U26   -BV45       A01X+041535Y+106528X0177Y    R180 S1      
327GND              U26   -BV46       A01X+041164Y+106528X0177Y    R180 S1      
327GND              U26   -BV47       A01X+040794Y+106528X0177Y    R180 S1      
327GND              U26   -BV48       A01X+040424Y+106528X0177Y    R180 S1      
327GND              U26   -BV49       A01X+040054Y+106528X0177Y    R180 S1      
327GND              U26   -BV50       A01X+039684Y+106528X0177Y    R180 S1      
327GND              U26   -BV51       A01X+039314Y+106528X0177Y    R180 S1      
327GND              U26   -BV52       A01X+038944Y+106528X0177Y    R180 S1      
327GND              U26   -BV53       A01X+038574Y+106528X0177Y    R180 S1      
327GND              U26   -BV59       A01X+036354Y+106528X0177Y    R180 S1      
327GND              U26   -BV61       A01X+035613Y+106528X0177Y    R180 S1      
327GND              U26   -BV66       A01X+033763Y+106528X0177Y    R180 S1      
327GND              U26   -BV68       A01X+033023Y+106528X0177Y    R180 S1      
327GND              U26   -BV73       A01X+031172Y+106528X0177Y    R180 S1      
327GND              U26   -BW1        A01X+057633Y+106847X0177Y    R180 S1      
327GND              U26   -BW4        A01X+056523Y+106847X0177Y    R180 S1      
327GND              U26   -BW6        A01X+055783Y+106847X0177Y    R180 S1      
327GND              U26   -BW8        A01X+055042Y+106847X0177Y    R180 S1      
327GND              U26   -BW11       A01X+053932Y+106847X0177Y    R180 S1      
327GND              U26   -BW13       A01X+053192Y+106847X0177Y    R180 S1      
327GND              U26   -BW15       A01X+052452Y+106847X0177Y    R180 S1      
327GND              U26   -BW18       A01X+051342Y+106847X0177Y    R180 S1      
327GND              U26   -BW20       A01X+050602Y+106847X0177Y    R180 S1      
327GND              U26   -BW22       A01X+049861Y+106847X0177Y    R180 S1      
327GND              U26   -BW28       A01X+047641Y+106847X0177Y    R180 S1      
327GND              U26   -BW31       A01X+046531Y+106847X0177Y    R180 S1      
327GND              U26   -BW34       A01X+045420Y+106847X0177Y    R180 S1      
327GND              U26   -BW42       A01X+042830Y+106847X0177Y    R180 S1      
327GND              U26   -BW45       A01X+041720Y+106847X0177Y    R180 S1      
327GND              U26   -BW48       A01X+040609Y+106847X0177Y    R180 S1      
327GND              U26   -BW51       A01X+039499Y+106847X0177Y    R180 S1      
327GND              U26   -BW54       A01X+038389Y+106847X0177Y    R180 S1      
327GND              U26   -BW56       A01X+037649Y+106847X0177Y    R180 S1      
327GND              U26   -BW58       A01X+036909Y+106847X0177Y    R180 S1      
327GND              U26   -BW61       A01X+035798Y+106847X0177Y    R180 S1      
327GND              U26   -BW63       A01X+035058Y+106847X0177Y    R180 S1      
327GND              U26   -BW65       A01X+034318Y+106847X0177Y    R180 S1      
327GND              U26   -BW68       A01X+033208Y+106847X0177Y    R180 S1      
327GND              U26   -BW70       A01X+032468Y+106847X0177Y    R180 S1      
327GND              U26   -BW72       A01X+031728Y+106847X0177Y    R180 S1      
327GND              U26   -BW75       A01X+030617Y+106847X0177Y    R180 S1      
327GND              U26   -BY3        A01X+057078Y+107166X0177Y    R180 S1      
327GND              U26   -BY5        A01X+056338Y+107166X0177Y    R180 S1      
327GND              U26   -BY8        A01X+055228Y+107166X0177Y    R180 S1      
327GND              U26   -BY10       A01X+054487Y+107166X0177Y    R180 S1      
327GND              U26   -BY12       A01X+053747Y+107166X0177Y    R180 S1      
327GND              U26   -BY15       A01X+052637Y+107166X0177Y    R180 S1      
327GND              U26   -BY17       A01X+051897Y+107166X0177Y    R180 S1      
327GND              U26   -BY19       A01X+051157Y+107166X0177Y    R180 S1      
327GND              U26   -BY22       A01X+050046Y+107166X0177Y    R180 S1      
327GND              U26   -BY25       A01X+048936Y+107166X0177Y    R180 S1      
327GND              U26   -BY28       A01X+047826Y+107166X0177Y    R180 S1      
327GND              U26   -BY31       A01X+046716Y+107166X0177Y    R180 S1      
327GND              U26   -BY34       A01X+045606Y+107166X0177Y    R180 S1      
327GND              U26   -BY37       A01X+044495Y+107166X0177Y    R180 S1      
327GND              U26   -BY39       A01X+043755Y+107166X0177Y    R180 S1      
327GND              U26   -BY42       A01X+042645Y+107166X0177Y    R180 S1      
327GND              U26   -BY45       A01X+041535Y+107166X0177Y    R180 S1      
327GND              U26   -BY48       A01X+040424Y+107166X0177Y    R180 S1      
327GND              U26   -BY51       A01X+039314Y+107166X0177Y    R180 S1      
327GND              U26   -BY54       A01X+038204Y+107166X0177Y    R180 S1      
327GND              U26   -BY57       A01X+037094Y+107166X0177Y    R180 S1      
327GND              U26   -BY59       A01X+036354Y+107166X0177Y    R180 S1      
327GND              U26   -BY61       A01X+035613Y+107166X0177Y    R180 S1      
327GND              U26   -BY64       A01X+034503Y+107166X0177Y    R180 S1      
327GND              U26   -BY66       A01X+033763Y+107166X0177Y    R180 S1      
327GND              U26   -BY68       A01X+033023Y+107166X0177Y    R180 S1      
327GND              U26   -BY71       A01X+031913Y+107166X0177Y    R180 S1      
327GND              U26   -BY73       A01X+031172Y+107166X0177Y    R180 S1      
327GND              U26   -CA1        A01X+057633Y+107484X0177Y    R180 S1      
327GND              U26   -CA6        A01X+055783Y+107484X0177Y    R180 S1      
327GND              U26   -CA8        A01X+055042Y+107484X0177Y    R180 S1      
327GND              U26   -CA13       A01X+053192Y+107484X0177Y    R180 S1      
327GND              U26   -CA15       A01X+052452Y+107484X0177Y    R180 S1      
327GND              U26   -CA20       A01X+050602Y+107484X0177Y    R180 S1      
327GND              U26   -CA22       A01X+049861Y+107484X0177Y    R180 S1      
327GND              U26   -CA25       A01X+048751Y+107484X0177Y    R180 S1      
327GND              U26   -CA28       A01X+047641Y+107484X0177Y    R180 S1      
327GND              U26   -CA31       A01X+046531Y+107484X0177Y    R180 S1      
327GND              U26   -CA34       A01X+045420Y+107484X0177Y    R180 S1      
327GND              U26   -CA35       A01X+045050Y+107484X0177Y    R180 S1      
327GND              U26   -CA36       A01X+044680Y+107484X0177Y    R180 S1      
327GND              U26   -CA40       A01X+043570Y+107484X0177Y    R180 S1      
327GND              U26   -CA41       A01X+043200Y+107484X0177Y    R180 S1      
327GND              U26   -CA42       A01X+042830Y+107484X0177Y    R180 S1      
327GND              U26   -CA45       A01X+041720Y+107484X0177Y    R180 S1      
327GND              U26   -CA48       A01X+040609Y+107484X0177Y    R180 S1      
327GND              U26   -CA51       A01X+039499Y+107484X0177Y    R180 S1      
327GND              U26   -CA54       A01X+038389Y+107484X0177Y    R180 S1      
327GND              U26   -CA56       A01X+037649Y+107484X0177Y    R180 S1      
327GND              U26   -CA61       A01X+035798Y+107484X0177Y    R180 S1      
327GND              U26   -CA63       A01X+035058Y+107484X0177Y    R180 S1      
327GND              U26   -CA68       A01X+033208Y+107484X0177Y    R180 S1      
327GND              U26   -CA70       A01X+032468Y+107484X0177Y    R180 S1      
327GND              U26   -CA75       A01X+030617Y+107484X0177Y    R180 S1      
327GND              U26   -CB3        A01X+057078Y+107803X0177Y    R180 S1      
327GND              U26   -CB5        A01X+056338Y+107803X0177Y    R180 S1      
327GND              U26   -CB8        A01X+055228Y+107803X0177Y    R180 S1      
327GND              U26   -CB10       A01X+054487Y+107803X0177Y    R180 S1      
327GND              U26   -CB12       A01X+053747Y+107803X0177Y    R180 S1      
327GND              U26   -CB15       A01X+052637Y+107803X0177Y    R180 S1      
327GND              U26   -CB17       A01X+051897Y+107803X0177Y    R180 S1      
327GND              U26   -CB19       A01X+051157Y+107803X0177Y    R180 S1      
327GND              U26   -CB23       A01X+049676Y+107803X0177Y    R180 S1      
327GND              U26   -CB24       A01X+049306Y+107803X0177Y    R180 S1      
327GND              U26   -CB25       A01X+048936Y+107803X0177Y    R180 S1      
327GND              U26   -CB26       A01X+048566Y+107803X0177Y    R180 S1      
327GND              U26   -CB27       A01X+048196Y+107803X0177Y    R180 S1      
327GND              U26   -CB28       A01X+047826Y+107803X0177Y    R180 S1      
327GND              U26   -CB29       A01X+047456Y+107803X0177Y    R180 S1      
327GND              U26   -CB30       A01X+047086Y+107803X0177Y    R180 S1      
327GND              U26   -CB31       A01X+046716Y+107803X0177Y    R180 S1      
327GND              U26   -CB32       A01X+046346Y+107803X0177Y    R180 S1      
327GND              U26   -CB33       A01X+045976Y+107803X0177Y    R180 S1      
327GND              U26   -CB34       A01X+045606Y+107803X0177Y    R180 S1      
327GND              U26   -CB37       A01X+044495Y+107803X0177Y    R180 S1      
327GND              U26   -CB39       A01X+043755Y+107803X0177Y    R180 S1      
327GND              U26   -CB42       A01X+042645Y+107803X0177Y    R180 S1      
327GND              U26   -CB43       A01X+042275Y+107803X0177Y    R180 S1      
327GND              U26   -CB45       A01X+041535Y+107803X0177Y    R180 S1      
327GND              U26   -CB46       A01X+041164Y+107803X0177Y    R180 S1      
327GND              U26   -CB47       A01X+040794Y+107803X0177Y    R180 S1      
327GND              U26   -CB48       A01X+040424Y+107803X0177Y    R180 S1      
327GND              U26   -CB49       A01X+040054Y+107803X0177Y    R180 S1      
327GND              U26   -CB50       A01X+039684Y+107803X0177Y    R180 S1      
327GND              U26   -CB51       A01X+039314Y+107803X0177Y    R180 S1      
327GND              U26   -CB52       A01X+038944Y+107803X0177Y    R180 S1      
327GND              U26   -CB53       A01X+038574Y+107803X0177Y    R180 S1      
327GND              U26   -CB57       A01X+037094Y+107803X0177Y    R180 S1      
327GND              U26   -CB59       A01X+036354Y+107803X0177Y    R180 S1      
327GND              U26   -CB61       A01X+035613Y+107803X0177Y    R180 S1      
327GND              U26   -CB64       A01X+034503Y+107803X0177Y    R180 S1      
327GND              U26   -CB66       A01X+033763Y+107803X0177Y    R180 S1      
327GND              U26   -CB68       A01X+033023Y+107803X0177Y    R180 S1      
327GND              U26   -CB71       A01X+031913Y+107803X0177Y    R180 S1      
327GND              U26   -CB73       A01X+031172Y+107803X0177Y    R180 S1      
327GND              U26   -CC1        A01X+057633Y+108122X0177Y    R180 S1      
327GND              U26   -CC4        A01X+056523Y+108122X0177Y    R180 S1      
327GND              U26   -CC6        A01X+055783Y+108122X0177Y    R180 S1      
327GND              U26   -CC8        A01X+055042Y+108122X0177Y    R180 S1      
327GND              U26   -CC11       A01X+053932Y+108122X0177Y    R180 S1      
327GND              U26   -CC13       A01X+053192Y+108122X0177Y    R180 S1      
327GND              U26   -CC15       A01X+052452Y+108122X0177Y    R180 S1      
327GND              U26   -CC18       A01X+051342Y+108122X0177Y    R180 S1      
327GND              U26   -CC20       A01X+050602Y+108122X0177Y    R180 S1      
327GND              U26   -CC25       A01X+048751Y+108122X0177Y    R180 S1      
327GND              U26   -CC28       A01X+047641Y+108122X0177Y    R180 S1      
327GND              U26   -CC31       A01X+046531Y+108122X0177Y    R180 S1      
327GND              U26   -CC34       A01X+045420Y+108122X0177Y    R180 S1      
327GND              U26   -CC42       A01X+042830Y+108122X0177Y    R180 S1      
327GND              U26   -CC45       A01X+041720Y+108122X0177Y    R180 S1      
327GND              U26   -CC48       A01X+040609Y+108122X0177Y    R180 S1      
327GND              U26   -CC51       A01X+039499Y+108122X0177Y    R180 S1      
327GND              U26   -CC54       A01X+038389Y+108122X0177Y    R180 S1      
327GND              U26   -CC56       A01X+037649Y+108122X0177Y    R180 S1      
327GND              U26   -CC58       A01X+036909Y+108122X0177Y    R180 S1      
327GND              U26   -CC61       A01X+035798Y+108122X0177Y    R180 S1      
327GND              U26   -CC63       A01X+035058Y+108122X0177Y    R180 S1      
327GND              U26   -CC65       A01X+034318Y+108122X0177Y    R180 S1      
327GND              U26   -CC68       A01X+033208Y+108122X0177Y    R180 S1      
327GND              U26   -CC70       A01X+032468Y+108122X0177Y    R180 S1      
327GND              U26   -CC72       A01X+031728Y+108122X0177Y    R180 S1      
327GND              U26   -CC75       A01X+030617Y+108122X0177Y    R180 S1      
327GND              U26   -CD3        A01X+057078Y+108441X0177Y    R180 S1      
327GND              U26   -CD8        A01X+055228Y+108441X0177Y    R180 S1      
327GND              U26   -CD10       A01X+054487Y+108441X0177Y    R180 S1      
327GND              U26   -CD15       A01X+052637Y+108441X0177Y    R180 S1      
327GND              U26   -CD17       A01X+051897Y+108441X0177Y    R180 S1      
327GND              U26   -CD22       A01X+050046Y+108441X0177Y    R180 S1      
327GND              U26   -CD25       A01X+048936Y+108441X0177Y    R180 S1      
327GND              U26   -CD28       A01X+047826Y+108441X0177Y    R180 S1      
327GND              U26   -CD31       A01X+046716Y+108441X0177Y    R180 S1      
327GND              U26   -CD34       A01X+045606Y+108441X0177Y    R180 S1      
327GND              U26   -CD37       A01X+044495Y+108441X0177Y    R180 S1      
327GND              U26   -CD39       A01X+043755Y+108441X0177Y    R180 S1      
327GND              U26   -CD42       A01X+042645Y+108441X0177Y    R180 S1      
327GND              U26   -CD45       A01X+041535Y+108441X0177Y    R180 S1      
327GND              U26   -CD48       A01X+040424Y+108441X0177Y    R180 S1      
327GND              U26   -CD51       A01X+039314Y+108441X0177Y    R180 S1      
327GND              U26   -CD54       A01X+038204Y+108441X0177Y    R180 S1      
327GND              U26   -CD59       A01X+036354Y+108441X0177Y    R180 S1      
327GND              U26   -CD61       A01X+035613Y+108441X0177Y    R180 S1      
327GND              U26   -CD66       A01X+033763Y+108441X0177Y    R180 S1      
327GND              U26   -CD68       A01X+033023Y+108441X0177Y    R180 S1      
327GND              U26   -CD73       A01X+031172Y+108441X0177Y    R180 S1      
327GND              U26   -CE1        A01X+057633Y+108760X0177Y    R180 S1      
327GND              U26   -CE4        A01X+056523Y+108760X0177Y    R180 S1      
327GND              U26   -CE6        A01X+055783Y+108760X0177Y    R180 S1      
327GND              U26   -CE8        A01X+055042Y+108760X0177Y    R180 S1      
327GND              U26   -CE11       A01X+053932Y+108760X0177Y    R180 S1      
327GND              U26   -CE13       A01X+053192Y+108760X0177Y    R180 S1      
327GND              U26   -CE15       A01X+052452Y+108760X0177Y    R180 S1      
327GND              U26   -CE18       A01X+051342Y+108760X0177Y    R180 S1      
327GND              U26   -CE20       A01X+050602Y+108760X0177Y    R180 S1      
327GND              U26   -CE22       A01X+049861Y+108760X0177Y    R180 S1      
327GND              U26   -CE25       A01X+048751Y+108760X0177Y    R180 S1      
327GND              U26   -CE28       A01X+047641Y+108760X0177Y    R180 S1      
327GND              U26   -CE31       A01X+046531Y+108760X0177Y    R180 S1      
327GND              U26   -CE34       A01X+045420Y+108760X0177Y    R180 S1      
327GND              U26   -CE35       A01X+045050Y+108760X0177Y    R180 S1      
327GND              U26   -CE36       A01X+044680Y+108760X0177Y    R180 S1      
327GND              U26   -CE40       A01X+043570Y+108760X0177Y    R180 S1      
327GND              U26   -CE41       A01X+043200Y+108760X0177Y    R180 S1      
327GND              U26   -CE42       A01X+042830Y+108760X0177Y    R180 S1      
327GND              U26   -CE45       A01X+041720Y+108760X0177Y    R180 S1      
327GND              U26   -CE48       A01X+040609Y+108760X0177Y    R180 S1      
327GND              U26   -CE51       A01X+039499Y+108760X0177Y    R180 S1      
327GND              U26   -CE54       A01X+038389Y+108760X0177Y    R180 S1      
327GND              U26   -CE56       A01X+037649Y+108760X0177Y    R180 S1      
327GND              U26   -CE58       A01X+036909Y+108760X0177Y    R180 S1      
327GND              U26   -CE61       A01X+035798Y+108760X0177Y    R180 S1      
327GND              U26   -CE63       A01X+035058Y+108760X0177Y    R180 S1      
327GND              U26   -CE65       A01X+034318Y+108760X0177Y    R180 S1      
327GND              U26   -CE68       A01X+033208Y+108760X0177Y    R180 S1      
327GND              U26   -CE70       A01X+032468Y+108760X0177Y    R180 S1      
327GND              U26   -CE72       A01X+031728Y+108760X0177Y    R180 S1      
327GND              U26   -CE75       A01X+030617Y+108760X0177Y    R180 S1      
327GND              U26   -CF3        A01X+057078Y+109079X0177Y    R180 S1      
327GND              U26   -CF5        A01X+056338Y+109079X0177Y    R180 S1      
327GND              U26   -CF8        A01X+055228Y+109079X0177Y    R180 S1      
327GND              U26   -CF10       A01X+054487Y+109079X0177Y    R180 S1      
327GND              U26   -CF12       A01X+053747Y+109079X0177Y    R180 S1      
327GND              U26   -CF15       A01X+052637Y+109079X0177Y    R180 S1      
327GND              U26   -CF17       A01X+051897Y+109079X0177Y    R180 S1      
327GND              U26   -CF19       A01X+051157Y+109079X0177Y    R180 S1      
327GND              U26   -CF23       A01X+049676Y+109079X0177Y    R180 S1      
327GND              U26   -CF24       A01X+049306Y+109079X0177Y    R180 S1      
327GND              U26   -CF25       A01X+048936Y+109079X0177Y    R180 S1      
327GND              U26   -CF26       A01X+048566Y+109079X0177Y    R180 S1      
327GND              U26   -CF27       A01X+048196Y+109079X0177Y    R180 S1      
327GND              U26   -CF28       A01X+047826Y+109079X0177Y    R180 S1      
327GND              U26   -CF29       A01X+047456Y+109079X0177Y    R180 S1      
327GND              U26   -CF30       A01X+047086Y+109079X0177Y    R180 S1      
327GND              U26   -CF31       A01X+046716Y+109079X0177Y    R180 S1      
327GND              U26   -CF32       A01X+046346Y+109079X0177Y    R180 S1      
327GND              U26   -CF33       A01X+045976Y+109079X0177Y    R180 S1      
327GND              U26   -CF34       A01X+045606Y+109079X0177Y    R180 S1      
327GND              U26   -CF37       A01X+044495Y+109079X0177Y    R180 S1      
327GND              U26   -CF39       A01X+043755Y+109079X0177Y    R180 S1      
327GND              U26   -CF42       A01X+042645Y+109079X0177Y    R180 S1      
327GND              U26   -CF43       A01X+042275Y+109079X0177Y    R180 S1      
327GND              U26   -CF44       A01X+041905Y+109079X0177Y    R180 S1      
327GND              U26   -CF45       A01X+041535Y+109079X0177Y    R180 S1      
327GND              U26   -CF47       A01X+040794Y+109079X0177Y    R180 S1      
327GND              U26   -CF48       A01X+040424Y+109079X0177Y    R180 S1      
327GND              U26   -CF49       A01X+040054Y+109079X0177Y    R180 S1      
327GND              U26   -CF50       A01X+039684Y+109079X0177Y    R180 S1      
327GND              U26   -CF51       A01X+039314Y+109079X0177Y    R180 S1      
327GND              U26   -CF52       A01X+038944Y+109079X0177Y    R180 S1      
327GND              U26   -CF53       A01X+038574Y+109079X0177Y    R180 S1      
327GND              U26   -CF57       A01X+037094Y+109079X0177Y    R180 S1      
327GND              U26   -CF59       A01X+036354Y+109079X0177Y    R180 S1      
327GND              U26   -CF61       A01X+035613Y+109079X0177Y    R180 S1      
327GND              U26   -CF64       A01X+034503Y+109079X0177Y    R180 S1      
327GND              U26   -CF66       A01X+033763Y+109079X0177Y    R180 S1      
327GND              U26   -CF68       A01X+033023Y+109079X0177Y    R180 S1      
327GND              U26   -CF71       A01X+031913Y+109079X0177Y    R180 S1      
327GND              U26   -CF73       A01X+031172Y+109079X0177Y    R180 S1      
327GND              U26   -CG1        A01X+057633Y+109398X0177Y    R180 S1      
327GND              U26   -CG6        A01X+055783Y+109398X0177Y    R180 S1      
327GND              U26   -CG8        A01X+055042Y+109398X0177Y    R180 S1      
327GND              U26   -CG13       A01X+053192Y+109398X0177Y    R180 S1      
327GND              U26   -CG15       A01X+052452Y+109398X0177Y    R180 S1      
327GND              U26   -CG20       A01X+050602Y+109398X0177Y    R180 S1      
327GND              U26   -CG22       A01X+049861Y+109398X0177Y    R180 S1      
327GND              U26   -CG25       A01X+048751Y+109398X0177Y    R180 S1      
327GND              U26   -CG28       A01X+047641Y+109398X0177Y    R180 S1      
327GND              U26   -CG31       A01X+046531Y+109398X0177Y    R180 S1      
327GND              U26   -CG34       A01X+045420Y+109398X0177Y    R180 S1      
327GND              U26   -CG45       A01X+041720Y+109398X0177Y    R180 S1      
327GND              U26   -CG48       A01X+040609Y+109398X0177Y    R180 S1      
327GND              U26   -CG51       A01X+039499Y+109398X0177Y    R180 S1      
327GND              U26   -CG54       A01X+038389Y+109398X0177Y    R180 S1      
327GND              U26   -CG56       A01X+037649Y+109398X0177Y    R180 S1      
327GND              U26   -CG61       A01X+035798Y+109398X0177Y    R180 S1      
327GND              U26   -CG63       A01X+035058Y+109398X0177Y    R180 S1      
327GND              U26   -CG68       A01X+033208Y+109398X0177Y    R180 S1      
327GND              U26   -CG70       A01X+032468Y+109398X0177Y    R180 S1      
327GND              U26   -CG75       A01X+030617Y+109398X0177Y    R180 S1      
327GND              U26   -CH3        A01X+057078Y+109717X0177Y    R180 S1      
327GND              U26   -CH5        A01X+056338Y+109717X0177Y    R180 S1      
327GND              U26   -CH8        A01X+055228Y+109717X0177Y    R180 S1      
327GND              U26   -CH10       A01X+054487Y+109717X0177Y    R180 S1      
327GND              U26   -CH12       A01X+053747Y+109717X0177Y    R180 S1      
327GND              U26   -CH15       A01X+052637Y+109717X0177Y    R180 S1      
327GND              U26   -CH17       A01X+051897Y+109717X0177Y    R180 S1      
327GND              U26   -CH19       A01X+051157Y+109717X0177Y    R180 S1      
327GND              U26   -CH22       A01X+050046Y+109717X0177Y    R180 S1      
327GND              U26   -CH25       A01X+048936Y+109717X0177Y    R180 S1      
327GND              U26   -CH28       A01X+047826Y+109717X0177Y    R180 S1      
327GND              U26   -CH31       A01X+046716Y+109717X0177Y    R180 S1      
327GND              U26   -CH34       A01X+045606Y+109717X0177Y    R180 S1      
327GND              U26   -CH37       A01X+044495Y+109717X0177Y    R180 S1      
327GND              U26   -CH39       A01X+043755Y+109717X0177Y    R180 S1      
327GND              U26   -CH42       A01X+042645Y+109717X0177Y    R180 S1      
327GND              U26   -CH45       A01X+041535Y+109717X0177Y    R180 S1      
327GND              U26   -CH48       A01X+040424Y+109717X0177Y    R180 S1      
327GND              U26   -CH51       A01X+039314Y+109717X0177Y    R180 S1      
327GND              U26   -CH54       A01X+038204Y+109717X0177Y    R180 S1      
327GND              U26   -CH57       A01X+037094Y+109717X0177Y    R180 S1      
327GND              U26   -CH59       A01X+036354Y+109717X0177Y    R180 S1      
327GND              U26   -CH61       A01X+035613Y+109717X0177Y    R180 S1      
327GND              U26   -CH64       A01X+034503Y+109717X0177Y    R180 S1      
327GND              U26   -CH66       A01X+033763Y+109717X0177Y    R180 S1      
327GND              U26   -CH68       A01X+033023Y+109717X0177Y    R180 S1      
327GND              U26   -CH71       A01X+031913Y+109717X0177Y    R180 S1      
327GND              U26   -CH73       A01X+031172Y+109717X0177Y    R180 S1      
327GND              U26   -CJ1        A01X+057633Y+110036X0177Y    R180 S1      
327GND              U26   -CJ4        A01X+056523Y+110036X0177Y    R180 S1      
327GND              U26   -CJ6        A01X+055783Y+110036X0177Y    R180 S1      
327GND              U26   -CJ8        A01X+055042Y+110036X0177Y    R180 S1      
327GND              U26   -CJ11       A01X+053932Y+110036X0177Y    R180 S1      
327GND              U26   -CJ13       A01X+053192Y+110036X0177Y    R180 S1      
327GND              U26   -CJ15       A01X+052452Y+110036X0177Y    R180 S1      
327GND              U26   -CJ18       A01X+051342Y+110036X0177Y    R180 S1      
327GND              U26   -CJ20       A01X+050602Y+110036X0177Y    R180 S1      
327GND              U26   -CJ23       A01X+049491Y+110036X0177Y    R180 S1      
327GND              U26   -CJ31       A01X+046531Y+110036X0177Y    R180 S1      
327GND              U26   -CJ34       A01X+045420Y+110036X0177Y    R180 S1      
327GND              U26   -CJ35       A01X+045050Y+110036X0177Y    R180 S1      
327GND              U26   -CJ36       A01X+044680Y+110036X0177Y    R180 S1      
327GND              U26   -CJ40       A01X+043570Y+110036X0177Y    R180 S1      
327GND              U26   -CJ41       A01X+043200Y+110036X0177Y    R180 S1      
327GND              U26   -CJ42       A01X+042830Y+110036X0177Y    R180 S1      
327GND              U26   -CJ45       A01X+041720Y+110036X0177Y    R180 S1      
327GND              U26   -CJ56       A01X+037649Y+110036X0177Y    R180 S1      
327GND              U26   -CJ58       A01X+036909Y+110036X0177Y    R180 S1      
327GND              U26   -CJ61       A01X+035798Y+110036X0177Y    R180 S1      
327GND              U26   -CJ63       A01X+035058Y+110036X0177Y    R180 S1      
327GND              U26   -CJ65       A01X+034318Y+110036X0177Y    R180 S1      
327GND              U26   -CJ68       A01X+033208Y+110036X0177Y    R180 S1      
327GND              U26   -CJ70       A01X+032468Y+110036X0177Y    R180 S1      
327GND              U26   -CJ72       A01X+031728Y+110036X0177Y    R180 S1      
327GND              U26   -CJ75       A01X+030617Y+110036X0177Y    R180 S1      
327GND              U26   -CK3        A01X+057078Y+110354X0177Y    R180 S1      
327GND              U26   -CK8        A01X+055228Y+110354X0177Y    R180 S1      
327GND              U26   -CK15       A01X+052637Y+110354X0177Y    R180 S1      
327GND              U26   -CK17       A01X+051897Y+110354X0177Y    R180 S1      
327GND              U26   -CK22       A01X+050046Y+110354X0177Y    R180 S1      
327GND              U26   -CK23       A01X+049676Y+110354X0177Y    R180 S1      
327GND              U26   -CK24       A01X+049306Y+110354X0177Y    R180 S1      
327GND              U26   -CK25       A01X+048936Y+110354X0177Y    R180 S1      
327GND              U26   -CK26       A01X+048566Y+110354X0177Y    R180 S1      
327GND              U26   -CK27       A01X+048196Y+110354X0177Y    R180 S1      
327GND              U26   -CK28       A01X+047826Y+110354X0177Y    R180 S1      
327GND              U26   -CK32       A01X+046346Y+110354X0177Y    R180 S1      
327GND              U26   -CK33       A01X+045976Y+110354X0177Y    R180 S1      
327GND              U26   -CK34       A01X+045606Y+110354X0177Y    R180 S1      
327GND              U26   -CK37       A01X+044495Y+110354X0177Y    R180 S1      
327GND              U26   -CK39       A01X+043755Y+110354X0177Y    R180 S1      
327GND              U26   -CK42       A01X+042645Y+110354X0177Y    R180 S1      
327GND              U26   -CK43       A01X+042275Y+110354X0177Y    R180 S1      
327GND              U26   -CK44       A01X+041905Y+110354X0177Y    R180 S1      
327GND              U26   -CK45       A01X+041535Y+110354X0177Y    R180 S1      
327GND              U26   -CK48       A01X+040424Y+110354X0177Y    R180 S1      
327GND              U26   -CK49       A01X+040054Y+110354X0177Y    R180 S1      
327GND              U26   -CK50       A01X+039684Y+110354X0177Y    R180 S1      
327GND              U26   -CK51       A01X+039314Y+110354X0177Y    R180 S1      
327GND              U26   -CK52       A01X+038944Y+110354X0177Y    R180 S1      
327GND              U26   -CK53       A01X+038574Y+110354X0177Y    R180 S1      
327GND              U26   -CK54       A01X+038204Y+110354X0177Y    R180 S1      
327GND              U26   -CK59       A01X+036354Y+110354X0177Y    R180 S1      
327GND              U26   -CK61       A01X+035613Y+110354X0177Y    R180 S1      
327GND              U26   -CK66       A01X+033763Y+110354X0177Y    R180 S1      
327GND              U26   -CK68       A01X+033023Y+110354X0177Y    R180 S1      
327GND              U26   -CK73       A01X+031172Y+110354X0177Y    R180 S1      
327GND              U26   -CL1        A01X+057633Y+110673X0177Y    R180 S1      
327GND              U26   -CL4        A01X+056523Y+110673X0177Y    R180 S1      
327GND              U26   -CL6        A01X+055783Y+110673X0177Y    R180 S1      
327GND              U26   -CL8        A01X+055042Y+110673X0177Y    R180 S1      
327GND              U26   -CL11       A01X+053932Y+110673X0177Y    R180 S1      
327GND              U26   -CL13       A01X+053192Y+110673X0177Y    R180 S1      
327GND              U26   -CL15       A01X+052452Y+110673X0177Y    R180 S1      
327GND              U26   -CL18       A01X+051342Y+110673X0177Y    R180 S1      
327GND              U26   -CL20       A01X+050602Y+110673X0177Y    R180 S1      
327GND              U26   -CL22       A01X+049861Y+110673X0177Y    R180 S1      
327GND              U26   -CL25       A01X+048751Y+110673X0177Y    R180 S1      
327GND              U26   -CL28       A01X+047641Y+110673X0177Y    R180 S1      
327GND              U26   -CL31       A01X+046531Y+110673X0177Y    R180 S1      
327GND              U26   -CL34       A01X+045420Y+110673X0177Y    R180 S1      
327GND              U26   -CL35       A01X+045050Y+110673X0177Y    R180 S1      
327GND              U26   -CL36       A01X+044680Y+110673X0177Y    R180 S1      
327GND              U26   -CL40       A01X+043570Y+110673X0177Y    R180 S1      
327GND              U26   -CL41       A01X+043200Y+110673X0177Y    R180 S1      
327GND              U26   -CL42       A01X+042830Y+110673X0177Y    R180 S1      
327GND              U26   -CL45       A01X+041720Y+110673X0177Y    R180 S1      
327GND              U26   -CL48       A01X+040609Y+110673X0177Y    R180 S1      
327GND              U26   -CL51       A01X+039499Y+110673X0177Y    R180 S1      
327GND              U26   -CL54       A01X+038389Y+110673X0177Y    R180 S1      
327GND              U26   -CL56       A01X+037649Y+110673X0177Y    R180 S1      
327GND              U26   -CL58       A01X+036909Y+110673X0177Y    R180 S1      
327GND              U26   -CL61       A01X+035798Y+110673X0177Y    R180 S1      
327GND              U26   -CL63       A01X+035058Y+110673X0177Y    R180 S1      
327GND              U26   -CL65       A01X+034318Y+110673X0177Y    R180 S1      
327GND              U26   -CL68       A01X+033208Y+110673X0177Y    R180 S1      
327GND              U26   -CL70       A01X+032468Y+110673X0177Y    R180 S1      
327GND              U26   -CL72       A01X+031728Y+110673X0177Y    R180 S1      
327GND              U26   -CL75       A01X+030617Y+110673X0177Y    R180 S1      
327GND              U26   -CM3        A01X+057078Y+110992X0177Y    R180 S1      
327GND              U26   -CM5        A01X+056338Y+110992X0177Y    R180 S1      
327GND              U26   -CM8        A01X+055228Y+110992X0177Y    R180 S1      
327GND              U26   -CM10       A01X+054487Y+110992X0177Y    R180 S1      
327GND              U26   -CM12       A01X+053747Y+110992X0177Y    R180 S1      
327GND              U26   -CM15       A01X+052637Y+110992X0177Y    R180 S1      
327GND              U26   -CM17       A01X+051897Y+110992X0177Y    R180 S1      
327GND              U26   -CM19       A01X+051157Y+110992X0177Y    R180 S1      
327GND              U26   -CM23       A01X+049676Y+110992X0177Y    R180 S1      
327GND              U26   -CM24       A01X+049306Y+110992X0177Y    R180 S1      
327GND              U26   -CM25       A01X+048936Y+110992X0177Y    R180 S1      
327GND              U26   -CM26       A01X+048566Y+110992X0177Y    R180 S1      
327GND              U26   -CM27       A01X+048196Y+110992X0177Y    R180 S1      
327GND              U26   -CM28       A01X+047826Y+110992X0177Y    R180 S1      
327GND              U26   -CM29       A01X+047456Y+110992X0177Y    R180 S1      
327GND              U26   -CM30       A01X+047086Y+110992X0177Y    R180 S1      
327GND              U26   -CM31       A01X+046716Y+110992X0177Y    R180 S1      
327GND              U26   -CM32       A01X+046346Y+110992X0177Y    R180 S1      
327GND              U26   -CM33       A01X+045976Y+110992X0177Y    R180 S1      
327GND              U26   -CM34       A01X+045606Y+110992X0177Y    R180 S1      
327GND              U26   -CM37       A01X+044495Y+110992X0177Y    R180 S1      
327GND              U26   -CM39       A01X+043755Y+110992X0177Y    R180 S1      
327GND              U26   -CM42       A01X+042645Y+110992X0177Y    R180 S1      
327GND              U26   -CM43       A01X+042275Y+110992X0177Y    R180 S1      
327GND              U26   -CM44       A01X+041905Y+110992X0177Y    R180 S1      
327GND              U26   -CM45       A01X+041535Y+110992X0177Y    R180 S1      
327GND              U26   -CM46       A01X+041164Y+110992X0177Y    R180 S1      
327GND              U26   -CM47       A01X+040794Y+110992X0177Y    R180 S1      
327GND              U26   -CM48       A01X+040424Y+110992X0177Y    R180 S1      
327GND              U26   -CM49       A01X+040054Y+110992X0177Y    R180 S1      
327GND              U26   -CM51       A01X+039314Y+110992X0177Y    R180 S1      
327GND              U26   -CM52       A01X+038944Y+110992X0177Y    R180 S1      
327GND              U26   -CM53       A01X+038574Y+110992X0177Y    R180 S1      
327GND              U26   -CM57       A01X+037094Y+110992X0177Y    R180 S1      
327GND              U26   -CM59       A01X+036354Y+110992X0177Y    R180 S1      
327GND              U26   -CM61       A01X+035613Y+110992X0177Y    R180 S1      
327GND              U26   -CM64       A01X+034503Y+110992X0177Y    R180 S1      
327GND              U26   -CM66       A01X+033763Y+110992X0177Y    R180 S1      
327GND              U26   -CM68       A01X+033023Y+110992X0177Y    R180 S1      
327GND              U26   -CM71       A01X+031913Y+110992X0177Y    R180 S1      
327GND              U26   -CM73       A01X+031172Y+110992X0177Y    R180 S1      
327GND              U26   -CN1        A01X+057633Y+111311X0177Y    R180 S1      
327GND              U26   -CN6        A01X+055783Y+111311X0177Y    R180 S1      
327GND              U26   -CN8        A01X+055042Y+111311X0177Y    R180 S1      
327GND              U26   -CN13       A01X+053192Y+111311X0177Y    R180 S1      
327GND              U26   -CN15       A01X+052452Y+111311X0177Y    R180 S1      
327GND              U26   -CN20       A01X+050602Y+111311X0177Y    R180 S1      
327GND              U26   -CN22       A01X+049861Y+111311X0177Y    R180 S1      
327GND              U26   -CN25       A01X+048751Y+111311X0177Y    R180 S1      
327GND              U26   -CN28       A01X+047641Y+111311X0177Y    R180 S1      
327GND              U26   -CN31       A01X+046531Y+111311X0177Y    R180 S1      
327GND              U26   -CN34       A01X+045420Y+111311X0177Y    R180 S1      
327GND              U26   -CN42       A01X+042830Y+111311X0177Y    R180 S1      
327GND              U26   -CN45       A01X+041720Y+111311X0177Y    R180 S1      
327GND              U26   -CN48       A01X+040609Y+111311X0177Y    R180 S1      
327GND              U26   -CN51       A01X+039499Y+111311X0177Y    R180 S1      
327GND              U26   -CN56       A01X+037649Y+111311X0177Y    R180 S1      
327GND              U26   -CN61       A01X+035798Y+111311X0177Y    R180 S1      
327GND              U26   -CN63       A01X+035058Y+111311X0177Y    R180 S1      
327GND              U26   -CN68       A01X+033208Y+111311X0177Y    R180 S1      
327GND              U26   -CN70       A01X+032468Y+111311X0177Y    R180 S1      
327GND              U26   -CN75       A01X+030617Y+111311X0177Y    R180 S1      
327GND              U26   -CP3        A01X+057078Y+111630X0177Y    R180 S1      
327GND              U26   -CP5        A01X+056338Y+111630X0177Y    R180 S1      
327GND              U26   -CP8        A01X+055228Y+111630X0177Y    R180 S1      
327GND              U26   -CP10       A01X+054487Y+111630X0177Y    R180 S1      
327GND              U26   -CP12       A01X+053747Y+111630X0177Y    R180 S1      
327GND              U26   -CP15       A01X+052637Y+111630X0177Y    R180 S1      
327GND              U26   -CP17       A01X+051897Y+111630X0177Y    R180 S1      
327GND              U26   -CP19       A01X+051157Y+111630X0177Y    R180 S1      
327GND              U26   -CP22       A01X+050046Y+111630X0177Y    R180 S1      
327GND              U26   -CP25       A01X+048936Y+111630X0177Y    R180 S1      
327GND              U26   -CP28       A01X+047826Y+111630X0177Y    R180 S1      
327GND              U26   -CP31       A01X+046716Y+111630X0177Y    R180 S1      
327GND              U26   -CP34       A01X+045606Y+111630X0177Y    R180 S1      
327GND              U26   -CP37       A01X+044495Y+111630X0177Y    R180 S1      
327GND              U26   -CP39       A01X+043755Y+111630X0177Y    R180 S1      
327GND              U26   -CP42       A01X+042645Y+111630X0177Y    R180 S1      
327GND              U26   -CP45       A01X+041535Y+111630X0177Y    R180 S1      
327GND              U26   -CP48       A01X+040424Y+111630X0177Y    R180 S1      
327GND              U26   -CP51       A01X+039314Y+111630X0177Y    R180 S1      
327GND              U26   -CP54       A01X+038204Y+111630X0177Y    R180 S1      
327GND              U26   -CP57       A01X+037094Y+111630X0177Y    R180 S1      
327GND              U26   -CP59       A01X+036354Y+111630X0177Y    R180 S1      
327GND              U26   -CP61       A01X+035613Y+111630X0177Y    R180 S1      
327GND              U26   -CP64       A01X+034503Y+111630X0177Y    R180 S1      
327GND              U26   -CP66       A01X+033763Y+111630X0177Y    R180 S1      
327GND              U26   -CP68       A01X+033023Y+111630X0177Y    R180 S1      
327GND              U26   -CP71       A01X+031913Y+111630X0177Y    R180 S1      
327GND              U26   -CP73       A01X+031172Y+111630X0177Y    R180 S1      
327GND              U26   -CR1        A01X+057633Y+111949X0177Y    R180 S1      
327GND              U26   -CR4        A01X+056523Y+111949X0177Y    R180 S1      
327GND              U26   -CR6        A01X+055783Y+111949X0177Y    R180 S1      
327GND              U26   -CR8        A01X+055042Y+111949X0177Y    R180 S1      
327GND              U26   -CR11       A01X+053932Y+111949X0177Y    R180 S1      
327GND              U26   -CR13       A01X+053192Y+111949X0177Y    R180 S1      
327GND              U26   -CR15       A01X+052452Y+111949X0177Y    R180 S1      
327GND              U26   -CR18       A01X+051342Y+111949X0177Y    R180 S1      
327GND              U26   -CR20       A01X+050602Y+111949X0177Y    R180 S1      
327GND              U26   -CR22       A01X+049861Y+111949X0177Y    R180 S1      
327GND              U26   -CR25       A01X+048751Y+111949X0177Y    R180 S1      
327GND              U26   -CR28       A01X+047641Y+111949X0177Y    R180 S1      
327GND              U26   -CR31       A01X+046531Y+111949X0177Y    R180 S1      
327GND              U26   -CR34       A01X+045420Y+111949X0177Y    R180 S1      
327GND              U26   -CR35       A01X+045050Y+111949X0177Y    R180 S1      
327GND              U26   -CR36       A01X+044680Y+111949X0177Y    R180 S1      
327GND              U26   -CR40       A01X+043570Y+111949X0177Y    R180 S1      
327GND              U26   -CR41       A01X+043200Y+111949X0177Y    R180 S1      
327GND              U26   -CR42       A01X+042830Y+111949X0177Y    R180 S1      
327GND              U26   -CR45       A01X+041720Y+111949X0177Y    R180 S1      
327GND              U26   -CR48       A01X+040609Y+111949X0177Y    R180 S1      
327GND              U26   -CR51       A01X+039499Y+111949X0177Y    R180 S1      
327GND              U26   -CR54       A01X+038389Y+111949X0177Y    R180 S1      
327GND              U26   -CR56       A01X+037649Y+111949X0177Y    R180 S1      
327GND              U26   -CR58       A01X+036909Y+111949X0177Y    R180 S1      
327GND              U26   -CR61       A01X+035798Y+111949X0177Y    R180 S1      
327GND              U26   -CR63       A01X+035058Y+111949X0177Y    R180 S1      
327GND              U26   -CR65       A01X+034318Y+111949X0177Y    R180 S1      
327GND              U26   -CR68       A01X+033208Y+111949X0177Y    R180 S1      
327GND              U26   -CR70       A01X+032468Y+111949X0177Y    R180 S1      
327GND              U26   -CR72       A01X+031728Y+111949X0177Y    R180 S1      
327GND              U26   -CR75       A01X+030617Y+111949X0177Y    R180 S1      
327GND              U26   -CT3        A01X+057078Y+112268X0177Y    R180 S1      
327GND              U26   -CT8        A01X+055228Y+112268X0177Y    R180 S1      
327GND              U26   -CT10       A01X+054487Y+112268X0177Y    R180 S1      
327GND              U26   -CT15       A01X+052637Y+112268X0177Y    R180 S1      
327GND              U26   -CT17       A01X+051897Y+112268X0177Y    R180 S1      
327GND              U26   -CT23       A01X+049676Y+112268X0177Y    R180 S1      
327GND              U26   -CT24       A01X+049306Y+112268X0177Y    R180 S1      
327GND              U26   -CT25       A01X+048936Y+112268X0177Y    R180 S1      
327GND              U26   -CT26       A01X+048566Y+112268X0177Y    R180 S1      
327GND              U26   -CT27       A01X+048196Y+112268X0177Y    R180 S1      
327GND              U26   -CT28       A01X+047826Y+112268X0177Y    R180 S1      
327GND              U26   -CT29       A01X+047456Y+112268X0177Y    R180 S1      
327GND              U26   -CT30       A01X+047086Y+112268X0177Y    R180 S1      
327GND              U26   -CT31       A01X+046716Y+112268X0177Y    R180 S1      
327GND              U26   -CT32       A01X+046346Y+112268X0177Y    R180 S1      
327GND              U26   -CT33       A01X+045976Y+112268X0177Y    R180 S1      
327GND              U26   -CT34       A01X+045606Y+112268X0177Y    R180 S1      
327GND              U26   -CT37       A01X+044495Y+112268X0177Y    R180 S1      
327GND              U26   -CT39       A01X+043755Y+112268X0177Y    R180 S1      
327GND              U26   -CT42       A01X+042645Y+112268X0177Y    R180 S1      
327GND              U26   -CT43       A01X+042275Y+112268X0177Y    R180 S1      
327GND              U26   -CT44       A01X+041905Y+112268X0177Y    R180 S1      
327GND              U26   -CT45       A01X+041535Y+112268X0177Y    R180 S1      
327GND              U26   -CT46       A01X+041164Y+112268X0177Y    R180 S1      
327GND              U26   -CT47       A01X+040794Y+112268X0177Y    R180 S1      
327GND              U26   -CT48       A01X+040424Y+112268X0177Y    R180 S1      
327GND              U26   -CT49       A01X+040054Y+112268X0177Y    R180 S1      
327GND              U26   -CT50       A01X+039684Y+112268X0177Y    R180 S1      
327GND              U26   -CT51       A01X+039314Y+112268X0177Y    R180 S1      
327GND              U26   -CT53       A01X+038574Y+112268X0177Y    R180 S1      
327GND              U26   -CT59       A01X+036354Y+112268X0177Y    R180 S1      
327GND              U26   -CT61       A01X+035613Y+112268X0177Y    R180 S1      
327GND              U26   -CT66       A01X+033763Y+112268X0177Y    R180 S1      
327GND              U26   -CT68       A01X+033023Y+112268X0177Y    R180 S1      
327GND              U26   -CT73       A01X+031172Y+112268X0177Y    R180 S1      
327GND              U26   -CU1        A01X+057633Y+112587X0177Y    R180 S1      
327GND              U26   -CU4        A01X+056523Y+112587X0177Y    R180 S1      
327GND              U26   -CU6        A01X+055783Y+112587X0177Y    R180 S1      
327GND              U26   -CU8        A01X+055042Y+112587X0177Y    R180 S1      
327GND              U26   -CU11       A01X+053932Y+112587X0177Y    R180 S1      
327GND              U26   -CU13       A01X+053192Y+112587X0177Y    R180 S1      
327GND              U26   -CU15       A01X+052452Y+112587X0177Y    R180 S1      
327GND              U26   -CU18       A01X+051342Y+112587X0177Y    R180 S1      
327GND              U26   -CU20       A01X+050602Y+112587X0177Y    R180 S1      
327GND              U26   -CU22       A01X+049861Y+112587X0177Y    R180 S1      
327GND              U26   -CU25       A01X+048751Y+112587X0177Y    R180 S1      
327GND              U26   -CU28       A01X+047641Y+112587X0177Y    R180 S1      
327GND              U26   -CU31       A01X+046531Y+112587X0177Y    R180 S1      
327GND              U26   -CU34       A01X+045420Y+112587X0177Y    R180 S1      
327GND              U26   -CU42       A01X+042830Y+112587X0177Y    R180 S1      
327GND              U26   -CU45       A01X+041720Y+112587X0177Y    R180 S1      
327GND              U26   -CU48       A01X+040609Y+112587X0177Y    R180 S1      
327GND              U26   -CU51       A01X+039499Y+112587X0177Y    R180 S1      
327GND              U26   -CU54       A01X+038389Y+112587X0177Y    R180 S1      
327GND              U26   -CU56       A01X+037649Y+112587X0177Y    R180 S1      
327GND              U26   -CU61       A01X+035798Y+112587X0177Y    R180 S1      
327GND              U26   -CU63       A01X+035058Y+112587X0177Y    R180 S1      
327GND              U26   -CU65       A01X+034318Y+112587X0177Y    R180 S1      
327GND              U26   -CU68       A01X+033208Y+112587X0177Y    R180 S1      
327GND              U26   -CU70       A01X+032468Y+112587X0177Y    R180 S1      
327GND              U26   -CU72       A01X+031728Y+112587X0177Y    R180 S1      
327GND              U26   -CU75       A01X+030617Y+112587X0177Y    R180 S1      
327GND              U26   -CV3        A01X+057078Y+112906X0177Y    R180 S1      
327GND              U26   -CV5        A01X+056338Y+112906X0177Y    R180 S1      
327GND              U26   -CV8        A01X+055228Y+112906X0177Y    R180 S1      
327GND              U26   -CV12       A01X+053747Y+112906X0177Y    R180 S1      
327GND              U26   -CV17       A01X+051897Y+112906X0177Y    R180 S1      
327GND              U26   -CV22       A01X+050046Y+112906X0177Y    R180 S1      
327GND              U26   -CV25       A01X+048936Y+112906X0177Y    R180 S1      
327GND              U26   -CV28       A01X+047826Y+112906X0177Y    R180 S1      
327GND              U26   -CV31       A01X+046716Y+112906X0177Y    R180 S1      
327GND              U26   -CV37       A01X+044495Y+112906X0177Y    R180 S1      
327GND              U26   -CV39       A01X+043755Y+112906X0177Y    R180 S1      
327GND              U26   -CV45       A01X+041535Y+112906X0177Y    R180 S1      
327GND              U26   -CV48       A01X+040424Y+112906X0177Y    R180 S1      
327GND              U26   -CV54       A01X+038204Y+112906X0177Y    R180 S1      
327GND              U26   -CV57       A01X+037094Y+112906X0177Y    R180 S1      
327GND              U26   -CV59       A01X+036354Y+112906X0177Y    R180 S1      
327GND              U26   -CV64       A01X+034503Y+112906X0177Y    R180 S1      
327GND              U26   -CV68       A01X+033023Y+112906X0177Y    R180 S1      
327GND              U26   -CV71       A01X+031913Y+112906X0177Y    R180 S1      
327GND              U26   -CV73       A01X+031172Y+112906X0177Y    R180 S1      
327GND              U26   -CW1        A01X+057633Y+113225X0177Y    R180 S1      
327GND              U26   -CW6        A01X+055783Y+113225X0177Y    R180 S1      
327GND              U26   -CW8        A01X+055042Y+113225X0177Y    R180 S1      
327GND              U26   -CW13       A01X+053192Y+113225X0177Y    R180 S1      
327GND              U26   -CW15       A01X+052452Y+113225X0177Y    R180 S1      
327GND              U26   -CW20       A01X+050602Y+113225X0177Y    R180 S1      
327GND              U26   -CW22       A01X+049861Y+113225X0177Y    R180 S1      
327GND              U26   -CW25       A01X+048751Y+113225X0177Y    R180 S1      
327GND              U26   -CW28       A01X+047641Y+113225X0177Y    R180 S1      
327GND              U26   -CW31       A01X+046531Y+113225X0177Y    R180 S1      
327GND              U26   -CW34       A01X+045420Y+113225X0177Y    R180 S1      
327GND              U26   -CW35       A01X+045050Y+113225X0177Y    R180 S1      
327GND              U26   -CW36       A01X+044680Y+113225X0177Y    R180 S1      
327GND              U26   -CW40       A01X+043570Y+113225X0177Y    R180 S1      
327GND              U26   -CW41       A01X+043200Y+113225X0177Y    R180 S1      
327GND              U26   -CW42       A01X+042830Y+113225X0177Y    R180 S1      
327GND              U26   -CW45       A01X+041720Y+113225X0177Y    R180 S1      
327GND              U26   -CW48       A01X+040609Y+113225X0177Y    R180 S1      
327GND              U26   -CW51       A01X+039499Y+113225X0177Y    R180 S1      
327GND              U26   -CW54       A01X+038389Y+113225X0177Y    R180 S1      
327GND              U26   -CW56       A01X+037649Y+113225X0177Y    R180 S1      
327GND              U26   -CW61       A01X+035798Y+113225X0177Y    R180 S1      
327GND              U26   -CW63       A01X+035058Y+113225X0177Y    R180 S1      
327GND              U26   -CW68       A01X+033208Y+113225X0177Y    R180 S1      
327GND              U26   -CW70       A01X+032468Y+113225X0177Y    R180 S1      
327GND              U26   -CW75       A01X+030617Y+113225X0177Y    R180 S1      
327GND              U26   -CY3        A01X+057078Y+113543X0177Y    R180 S1      
327GND              U26   -CY5        A01X+056338Y+113543X0177Y    R180 S1      
327GND              U26   -CY8        A01X+055228Y+113543X0177Y    R180 S1      
327GND              U26   -CY10       A01X+054487Y+113543X0177Y    R180 S1      
327GND              U26   -CY12       A01X+053747Y+113543X0177Y    R180 S1      
327GND              U26   -CY15       A01X+052637Y+113543X0177Y    R180 S1      
327GND              U26   -CY17       A01X+051897Y+113543X0177Y    R180 S1      
327GND              U26   -CY19       A01X+051157Y+113543X0177Y    R180 S1      
327GND              U26   -CY23       A01X+049676Y+113543X0177Y    R180 S1      
327GND              U26   -CY24       A01X+049306Y+113543X0177Y    R180 S1      
327GND              U26   -CY25       A01X+048936Y+113543X0177Y    R180 S1      
327GND              U26   -CY26       A01X+048566Y+113543X0177Y    R180 S1      
327GND              U26   -CY27       A01X+048196Y+113543X0177Y    R180 S1      
327GND              U26   -CY28       A01X+047826Y+113543X0177Y    R180 S1      
327GND              U26   -CY29       A01X+047456Y+113543X0177Y    R180 S1      
327GND              U26   -CY30       A01X+047086Y+113543X0177Y    R180 S1      
327GND              U26   -CY31       A01X+046716Y+113543X0177Y    R180 S1      
327GND              U26   -CY32       A01X+046346Y+113543X0177Y    R180 S1      
327GND              U26   -CY33       A01X+045976Y+113543X0177Y    R180 S1      
327GND              U26   -CY34       A01X+045606Y+113543X0177Y    R180 S1      
327GND              U26   -CY37       A01X+044495Y+113543X0177Y    R180 S1      
327GND              U26   -CY39       A01X+043755Y+113543X0177Y    R180 S1      
327GND              U26   -CY42       A01X+042645Y+113543X0177Y    R180 S1      
327GND              U26   -CY43       A01X+042275Y+113543X0177Y    R180 S1      
327GND              U26   -CY44       A01X+041905Y+113543X0177Y    R180 S1      
327GND              U26   -CY45       A01X+041535Y+113543X0177Y    R180 S1      
327GND              U26   -CY46       A01X+041164Y+113543X0177Y    R180 S1      
327GND              U26   -CY47       A01X+040794Y+113543X0177Y    R180 S1      
327GND              U26   -CY48       A01X+040424Y+113543X0177Y    R180 S1      
327GND              U26   -CY49       A01X+040054Y+113543X0177Y    R180 S1      
327GND              U26   -CY50       A01X+039684Y+113543X0177Y    R180 S1      
327GND              U26   -CY51       A01X+039314Y+113543X0177Y    R180 S1      
327GND              U26   -CY52       A01X+038944Y+113543X0177Y    R180 S1      
327GND              U26   -CY53       A01X+038574Y+113543X0177Y    R180 S1      
327GND              U26   -CY59       A01X+036354Y+113543X0177Y    R180 S1      
327GND              U26   -CY61       A01X+035613Y+113543X0177Y    R180 S1      
327GND              U26   -CY64       A01X+034503Y+113543X0177Y    R180 S1      
327GND              U26   -CY66       A01X+033763Y+113543X0177Y    R180 S1      
327GND              U26   -CY68       A01X+033023Y+113543X0177Y    R180 S1      
327GND              U26   -CY71       A01X+031913Y+113543X0177Y    R180 S1      
327GND              U26   -CY73       A01X+031172Y+113543X0177Y    R180 S1      
327GND              U26   -DA1        A01X+057633Y+113862X0177Y    R180 S1      
327GND              U26   -DA4        A01X+056523Y+113862X0177Y    R180 S1      
327GND              U26   -DA6        A01X+055783Y+113862X0177Y    R180 S1      
327GND              U26   -DA8        A01X+055042Y+113862X0177Y    R180 S1      
327GND              U26   -DA11       A01X+053932Y+113862X0177Y    R180 S1      
327GND              U26   -DA13       A01X+053192Y+113862X0177Y    R180 S1      
327GND              U26   -DA15       A01X+052452Y+113862X0177Y    R180 S1      
327GND              U26   -DA18       A01X+051342Y+113862X0177Y    R180 S1      
327GND              U26   -DA20       A01X+050602Y+113862X0177Y    R180 S1      
327GND              U26   -DA22       A01X+049861Y+113862X0177Y    R180 S1      
327GND              U26   -DA25       A01X+048751Y+113862X0177Y    R180 S1      
327GND              U26   -DA28       A01X+047641Y+113862X0177Y    R180 S1      
327GND              U26   -DA31       A01X+046531Y+113862X0177Y    R180 S1      
327GND              U26   -DA34       A01X+045420Y+113862X0177Y    R180 S1      
327GND              U26   -DA42       A01X+042830Y+113862X0177Y    R180 S1      
327GND              U26   -DA45       A01X+041720Y+113862X0177Y    R180 S1      
327GND              U26   -DA48       A01X+040609Y+113862X0177Y    R180 S1      
327GND              U26   -DA51       A01X+039499Y+113862X0177Y    R180 S1      
327GND              U26   -DA54       A01X+038389Y+113862X0177Y    R180 S1      
327GND              U26   -DA58       A01X+036909Y+113862X0177Y    R180 S1      
327GND              U26   -DA61       A01X+035798Y+113862X0177Y    R180 S1      
327GND              U26   -DA63       A01X+035058Y+113862X0177Y    R180 S1      
327GND              U26   -DA65       A01X+034318Y+113862X0177Y    R180 S1      
327GND              U26   -DA68       A01X+033208Y+113862X0177Y    R180 S1      
327GND              U26   -DA70       A01X+032468Y+113862X0177Y    R180 S1      
327GND              U26   -AA42       A01X+042712Y+093807X0177Y    R180 S1      
327GND              U26   -AA72       A01X+031609Y+093807X0177Y    R180 S1      
327GND              U26   -AD31       A01X+046598Y+094764X0177Y    R180 S1      
327GND              U26   -AE4        A01X+056405Y+095083X0177Y    R180 S1      
327GND              U26   -AH33       A01X+045857Y+096040X0177Y    R180 S1      
327GND              U26   -AJ13       A01X+053074Y+096358X0177Y    R180 S1      
327GND              U26   -AM37       A01X+044377Y+097315X0177Y    R180 S1      
327GND              U26   -AN20       A01X+050483Y+097634X0177Y    R180 S1      
327GND              U26   -BV42       A01X+042645Y+106528X0177Y    R180 S1      
327GND              U26   -BW25       A01X+048751Y+106847X0177Y    R180 S1      
327GND              U26   -CB44       A01X+041905Y+107803X0177Y    R180 S1      
327GND              U26   -CC22       A01X+049861Y+108122X0177Y    R180 S1      
327GND              U26   -CF46       A01X+041164Y+109079X0177Y    R180 S1      
327GND              U26   -CG42       A01X+042830Y+109398X0177Y    R180 S1      
327GND              U26   -CK10       A01X+054487Y+110354X0177Y    R180 S1      
327GND              U26   -CK31       A01X+046716Y+110354X0177Y    R180 S1      
327GND              U26   -CM50       A01X+039684Y+110992X0177Y    R180 S1      
327GND              U26   -CN54       A01X+038389Y+111311X0177Y    R180 S1      
327GND              U26   -CT52       A01X+038944Y+112268X0177Y    R180 S1      
327GND              U26   -CU58       A01X+036909Y+112587X0177Y    R180 S1      
327GND              U26   -CY57       A01X+037094Y+113543X0177Y    R180 S1      
327GND              U26   -DA56       A01X+037649Y+113862X0177Y    R180 S1      
327GND              U26   -DA72       A01X+031728Y+113862X0177Y    R180 S1      
327GND              U26   -DA75       A01X+030617Y+113862X0177Y    R180 S1      
327GND              U26   -DB3        A01X+057078Y+114181X0177Y    R180 S1      
327GND              U26   -DB8        A01X+055228Y+114181X0177Y    R180 S1      
327GND              U26   -DB10       A01X+054487Y+114181X0177Y    R180 S1      
327GND              U26   -DB15       A01X+052637Y+114181X0177Y    R180 S1      
327GND              U26   -DB17       A01X+051897Y+114181X0177Y    R180 S1      
327GND              U26   -DB22       A01X+050046Y+114181X0177Y    R180 S1      
327GND              U26   -DB25       A01X+048936Y+114181X0177Y    R180 S1      
327GND              U26   -DB28       A01X+047826Y+114181X0177Y    R180 S1      
327GND              U26   -DB31       A01X+046716Y+114181X0177Y    R180 S1      
327GND              U26   -DB34       A01X+045606Y+114181X0177Y    R180 S1      
327GND              U26   -DB37       A01X+044495Y+114181X0177Y    R180 S1      
327GND              U26   -DB39       A01X+043755Y+114181X0177Y    R180 S1      
327GND              U26   -DB42       A01X+042645Y+114181X0177Y    R180 S1      
327GND              U26   -DB45       A01X+041535Y+114181X0177Y    R180 S1      
327GND              U26   -DB48       A01X+040424Y+114181X0177Y    R180 S1      
327GND              U26   -DB51       A01X+039314Y+114181X0177Y    R180 S1      
327GND              U26   -DB54       A01X+038204Y+114181X0177Y    R180 S1      
327GND              U26   -DB59       A01X+036354Y+114181X0177Y    R180 S1      
327GND              U26   -DB61       A01X+035613Y+114181X0177Y    R180 S1      
327GND              U26   -DB66       A01X+033763Y+114181X0177Y    R180 S1      
327GND              U26   -DB68       A01X+033023Y+114181X0177Y    R180 S1      
327GND              U26   -DB73       A01X+031172Y+114181X0177Y    R180 S1      
327GND              U26   -DC1        A01X+057633Y+114500X0177Y    R180 S1      
327GND              U26   -DC4        A01X+056523Y+114500X0177Y    R180 S1      
327GND              U26   -DC6        A01X+055783Y+114500X0177Y    R180 S1      
327GND              U26   -DC8        A01X+055042Y+114500X0177Y    R180 S1      
327GND              U26   -DC11       A01X+053932Y+114500X0177Y    R180 S1      
327GND              U26   -DC13       A01X+053192Y+114500X0177Y    R180 S1      
327GND              U26   -DC15       A01X+052452Y+114500X0177Y    R180 S1      
327GND              U26   -DC18       A01X+051342Y+114500X0177Y    R180 S1      
327GND              U26   -DC20       A01X+050602Y+114500X0177Y    R180 S1      
327GND              U26   -DC22       A01X+049861Y+114500X0177Y    R180 S1      
327GND              U26   -DC25       A01X+048751Y+114500X0177Y    R180 S1      
327GND              U26   -DC28       A01X+047641Y+114500X0177Y    R180 S1      
327GND              U26   -DC31       A01X+046531Y+114500X0177Y    R180 S1      
327GND              U26   -DC34       A01X+045420Y+114500X0177Y    R180 S1      
327GND              U26   -DC42       A01X+042830Y+114500X0177Y    R180 S1      
327GND              U26   -DC45       A01X+041720Y+114500X0177Y    R180 S1      
327GND              U26   -DC48       A01X+040609Y+114500X0177Y    R180 S1      
327GND              U26   -DC51       A01X+039499Y+114500X0177Y    R180 S1      
327GND              U26   -DC54       A01X+038389Y+114500X0177Y    R180 S1      
327GND              U26   -DC56       A01X+037649Y+114500X0177Y    R180 S1      
327GND              U26   -DC58       A01X+036909Y+114500X0177Y    R180 S1      
327GND              U26   -DC61       A01X+035798Y+114500X0177Y    R180 S1      
327GND              U26   -DC63       A01X+035058Y+114500X0177Y    R180 S1      
327GND              U26   -DC65       A01X+034318Y+114500X0177Y    R180 S1      
327GND              U26   -DC68       A01X+033208Y+114500X0177Y    R180 S1      
327GND              U26   -DC70       A01X+032468Y+114500X0177Y    R180 S1      
327GND              U26   -DC72       A01X+031728Y+114500X0177Y    R180 S1      
327GND              U26   -DC75       A01X+030617Y+114500X0177Y    R180 S1      
327GND              U26   -DD3        A01X+057078Y+114819X0177Y    R180 S1      
327GND              U26   -DD5        A01X+056338Y+114819X0177Y    R180 S1      
327GND              U26   -DD8        A01X+055228Y+114819X0177Y    R180 S1      
327GND              U26   -DD10       A01X+054487Y+114819X0177Y    R180 S1      
327GND              U26   -DD12       A01X+053747Y+114819X0177Y    R180 S1      
327GND              U26   -DD15       A01X+052637Y+114819X0177Y    R180 S1      
327GND              U26   -DD17       A01X+051897Y+114819X0177Y    R180 S1      
327GND              U26   -DD19       A01X+051157Y+114819X0177Y    R180 S1      
327GND              U26   -DD23       A01X+049676Y+114819X0177Y    R180 S1      
327GND              U26   -DD24       A01X+049306Y+114819X0177Y    R180 S1      
327GND              U26   -DD26       A01X+048566Y+114819X0177Y    R180 S1      
327GND              U26   -DD27       A01X+048196Y+114819X0177Y    R180 S1      
327GND              U26   -DD29       A01X+047456Y+114819X0177Y    R180 S1      
327GND              U26   -DD30       A01X+047086Y+114819X0177Y    R180 S1      
327GND              U26   -DD32       A01X+046346Y+114819X0177Y    R180 S1      
327GND              U26   -DD33       A01X+045976Y+114819X0177Y    R180 S1      
327GND              U26   -DD35       A01X+045235Y+114819X0177Y    R180 S1      
327GND              U26   -DD36       A01X+044865Y+114819X0177Y    R180 S1      
327GND              U26   -DD37       A01X+044495Y+114819X0177Y    R180 S1      
327GND              U26   -DD39       A01X+043755Y+114819X0177Y    R180 S1      
327GND              U26   -DD40       A01X+043385Y+114819X0177Y    R180 S1      
327GND              U26   -DD41       A01X+043015Y+114819X0177Y    R180 S1      
327GND              U26   -DD43       A01X+042275Y+114819X0177Y    R180 S1      
327GND              U26   -DD44       A01X+041905Y+114819X0177Y    R180 S1      
327GND              U26   -DD46       A01X+041164Y+114819X0177Y    R180 S1      
327GND              U26   -DD47       A01X+040794Y+114819X0177Y    R180 S1      
327GND              U26   -DD49       A01X+040054Y+114819X0177Y    R180 S1      
327GND              U26   -DD50       A01X+039684Y+114819X0177Y    R180 S1      
327GND              U26   -DD52       A01X+038944Y+114819X0177Y    R180 S1      
327GND              U26   -DD53       A01X+038574Y+114819X0177Y    R180 S1      
327GND              U26   -DD57       A01X+037094Y+114819X0177Y    R180 S1      
327GND              U26   -DD59       A01X+036354Y+114819X0177Y    R180 S1      
327GND              U26   -DD61       A01X+035613Y+114819X0177Y    R180 S1      
327GND              U26   -DD64       A01X+034503Y+114819X0177Y    R180 S1      
327GND              U26   -DD66       A01X+033763Y+114819X0177Y    R180 S1      
327GND              U26   -DD68       A01X+033023Y+114819X0177Y    R180 S1      
327GND              U26   -DD71       A01X+031913Y+114819X0177Y    R180 S1      
327GND              U26   -DD73       A01X+031172Y+114819X0177Y    R180 S1      
327GND              U26   -DE1        A01X+057633Y+115138X0177Y    R180 S1      
327GND              U26   -DE6        A01X+055783Y+115138X0177Y    R180 S1      
327GND              U26   -DE8        A01X+055042Y+115138X0177Y    R180 S1      
327GND              U26   -DE13       A01X+053192Y+115138X0177Y    R180 S1      
327GND              U26   -DE15       A01X+052452Y+115138X0177Y    R180 S1      
327GND              U26   -DE20       A01X+050602Y+115138X0177Y    R180 S1      
327GND              U26   -DE23       A01X+049491Y+115138X0177Y    R180 S1      
327GND              U26   -DE26       A01X+048381Y+115138X0177Y    R180 S1      
327GND              U26   -DE29       A01X+047271Y+115138X0177Y    R180 S1      
327GND              U26   -DE33       A01X+045790Y+115138X0177Y    R180 S1      
327GND              U26   -DE56       A01X+037649Y+115138X0177Y    R180 S1      
327GND              U26   -DE61       A01X+035798Y+115138X0177Y    R180 S1      
327GND              U26   -DE63       A01X+035058Y+115138X0177Y    R180 S1      
327GND              U26   -DE68       A01X+033208Y+115138X0177Y    R180 S1      
327GND              U26   -DE70       A01X+032468Y+115138X0177Y    R180 S1      
327GND              U26   -DE75       A01X+030617Y+115138X0177Y    R180 S1      
327GND              U26   -DF3        A01X+057078Y+115457X0177Y    R180 S1      
327GND              U26   -DF4        A01X+056708Y+115457X0177Y    R180 S1      
327GND              U26   -DF5        A01X+056338Y+115457X0177Y    R180 S1      
327GND              U26   -DF6        A01X+055968Y+115457X0177Y    R180 S1      
327GND              U26   -DF8        A01X+055228Y+115457X0177Y    R180 S1      
327GND              U26   -DF10       A01X+054487Y+115457X0177Y    R180 S1      
327GND              U26   -DF11       A01X+054117Y+115457X0177Y    R180 S1      
327GND              U26   -DF12       A01X+053747Y+115457X0177Y    R180 S1      
327GND              U26   -DF13       A01X+053377Y+115457X0177Y    R180 S1      
327GND              U26   -DF15       A01X+052637Y+115457X0177Y    R180 S1      
327GND              U26   -DF17       A01X+051897Y+115457X0177Y    R180 S1      
327GND              U26   -DF18       A01X+051527Y+115457X0177Y    R180 S1      
327GND              U26   -DF19       A01X+051157Y+115457X0177Y    R180 S1      
327GND              U26   -DF20       A01X+050787Y+115457X0177Y    R180 S1      
327GND              U26   -DF22       A01X+050046Y+115457X0177Y    R180 S1      
327GND              U26   -DF23       A01X+049676Y+115457X0177Y    R180 S1      
327GND              U26   -DF26       A01X+048566Y+115457X0177Y    R180 S1      
327GND              U26   -DF29       A01X+047456Y+115457X0177Y    R180 S1      
327GND              U26   -DF32       A01X+046346Y+115457X0177Y    R180 S1      
327GND              U26   -DF35       A01X+045235Y+115457X0177Y    R180 S1      
327GND              U26   -DF37       A01X+044495Y+115457X0177Y    R180 S1      
327GND              U26   -DF39       A01X+043755Y+115457X0177Y    R180 S1      
327GND              U26   -DF42       A01X+042645Y+115457X0177Y    R180 S1      
327GND              U26   -DF43       A01X+042275Y+115457X0177Y    R180 S1      
327GND              U26   -DF44       A01X+041905Y+115457X0177Y    R180 S1      
327GND              U26   -DF45       A01X+041535Y+115457X0177Y    R180 S1      
327GND              U26   -DF46       A01X+041164Y+115457X0177Y    R180 S1      
327GND              U26   -DF47       A01X+040794Y+115457X0177Y    R180 S1      
327GND              U26   -DF48       A01X+040424Y+115457X0177Y    R180 S1      
327GND              U26   -DF49       A01X+040054Y+115457X0177Y    R180 S1      
327GND              U26   -DF50       A01X+039684Y+115457X0177Y    R180 S1      
327GND              U26   -DF51       A01X+039314Y+115457X0177Y    R180 S1      
327GND              U26   -DF52       A01X+038944Y+115457X0177Y    R180 S1      
327GND              U26   -DF53       A01X+038574Y+115457X0177Y    R180 S1      
327GND              U26   -DF54       A01X+038204Y+115457X0177Y    R180 S1      
327GND              U26   -DF56       A01X+037464Y+115457X0177Y    R180 S1      
327GND              U26   -DF57       A01X+037094Y+115457X0177Y    R180 S1      
327GND              U26   -DF58       A01X+036724Y+115457X0177Y    R180 S1      
327GND              U26   -DF59       A01X+036354Y+115457X0177Y    R180 S1      
327GND              U26   -DF61       A01X+035613Y+115457X0177Y    R180 S1      
327GND              U26   -DF63       A01X+034873Y+115457X0177Y    R180 S1      
327GND              U26   -DF64       A01X+034503Y+115457X0177Y    R180 S1      
327GND              U26   -DF65       A01X+034133Y+115457X0177Y    R180 S1      
327GND              U26   -DF66       A01X+033763Y+115457X0177Y    R180 S1      
327GND              U26   -DF68       A01X+033023Y+115457X0177Y    R180 S1      
327GND              U26   -DF70       A01X+032283Y+115457X0177Y    R180 S1      
327GND              U26   -DF71       A01X+031913Y+115457X0177Y    R180 S1      
327GND              U26   -DF72       A01X+031542Y+115457X0177Y    R180 S1      
327GND              U26   -DF73       A01X+031172Y+115457X0177Y    R180 S1      
327GND              U26   -DG1        A01X+057633Y+115776X0177Y    R180 S1      
327GND              U26   -DG2        A01X+057263Y+115776X0177Y    R180 S1      
327GND              U26   -DG6        A01X+055783Y+115776X0177Y    R180 S1      
327GND              U26   -DG7        A01X+055413Y+115776X0177Y    R180 S1      
327GND              U26   -DG8        A01X+055042Y+115776X0177Y    R180 S1      
327GND              U26   -DG9        A01X+054672Y+115776X0177Y    R180 S1      
327GND              U26   -DG13       A01X+053192Y+115776X0177Y    R180 S1      
327GND              U26   -DG14       A01X+052822Y+115776X0177Y    R180 S1      
327GND              U26   -DG15       A01X+052452Y+115776X0177Y    R180 S1      
327GND              U26   -DG16       A01X+052082Y+115776X0177Y    R180 S1      
327GND              U26   -DG18       A01X+051342Y+115776X0177Y    R180 S1      
327GND              U26   -DG20       A01X+050602Y+115776X0177Y    R180 S1      
327GND              U26   -DG21       A01X+050232Y+115776X0177Y    R180 S1      
327GND              U26   -DG24       A01X+049121Y+115776X0177Y    R180 S1      
327GND              U26   -DG27       A01X+048011Y+115776X0177Y    R180 S1      
327GND              U26   -DG30       A01X+046901Y+115776X0177Y    R180 S1      
327GND              U26   -DG33       A01X+045790Y+115776X0177Y    R180 S1      
327GND              U26   -DG41       A01X+043200Y+115776X0177Y    R180 S1      
327GND              U26   -DG43       A01X+042460Y+115776X0177Y    R180 S1      
327GND              U26   -DG46       A01X+041350Y+115776X0177Y    R180 S1      
327GND              U26   -DG49       A01X+040239Y+115776X0177Y    R180 S1      
327GND              U26   -DG52       A01X+039129Y+115776X0177Y    R180 S1      
327GND              U26   -DG55       A01X+038019Y+115776X0177Y    R180 S1      
327GND              U26   -DG56       A01X+037649Y+115776X0177Y    R180 S1      
327GND              U26   -DG59       A01X+036538Y+115776X0177Y    R180 S1      
327GND              U26   -DG60       A01X+036168Y+115776X0177Y    R180 S1      
327GND              U26   -DG61       A01X+035798Y+115776X0177Y    R180 S1      
327GND              U26   -DG62       A01X+035428Y+115776X0177Y    R180 S1      
327GND              U26   -DG63       A01X+035058Y+115776X0177Y    R180 S1      
327GND              U26   -DG65       A01X+034318Y+115776X0177Y    R180 S1      
327GND              U26   -DG66       A01X+033948Y+115776X0177Y    R180 S1      
327GND              U26   -DG67       A01X+033578Y+115776X0177Y    R180 S1      
327GND              U26   -DG68       A01X+033208Y+115776X0177Y    R180 S1      
327GND              U26   -DG69       A01X+032838Y+115776X0177Y    R180 S1      
327GND              U26   -DG70       A01X+032468Y+115776X0177Y    R180 S1      
327GND              U26   -DG74       A01X+030987Y+115776X0177Y    R180 S1      
327GND              U26   -DG75       A01X+030617Y+115776X0177Y    R180 S1      
327GND              U26   -DH5        A01X+056338Y+116095X0177Y    R180 S1      
327GND              U26   -DH11       A01X+054117Y+116095X0177Y    R180 S1      
327GND              U26   -DH18       A01X+051527Y+116095X0177Y    R180 S1      
327GND              U26   -DH37       A01X+044495Y+116095X0177Y    R180 S1      
327GND              U26   -DH39       A01X+043755Y+116095X0177Y    R180 S1      
327GND              U26   -DH43       A01X+042275Y+116095X0177Y    R180 S1      
327GND              U26   -DH46       A01X+041164Y+116095X0177Y    R180 S1      
327GND              U26   -DH49       A01X+040054Y+116095X0177Y    R180 S1      
327GND              U26   -DH52       A01X+038944Y+116095X0177Y    R180 S1      
327GND              U26   -DH55       A01X+037834Y+116095X0177Y    R180 S1      
327GND              U26   -DH59       A01X+036354Y+116095X0177Y    R180 S1      
327GND              U26   -DH61       A01X+035613Y+116095X0177Y    R180 S1      
327GND              U26   -DH63       A01X+034873Y+116095X0177Y    R180 S1      
327GND              U26   -DH64       A01X+034503Y+116095X0177Y    R180 S1      
327GND              U26   -DH66       A01X+033763Y+116095X0177Y    R180 S1      
327GND              U26   -DH68       A01X+033023Y+116095X0177Y    R180 S1      
327GND              U26   -DH70       A01X+032283Y+116095X0177Y    R180 S1      
327GND              U26   -DJ7        A01X+055413Y+116414X0177Y    R180 S1      
327GND              U26   -DJ15       A01X+052452Y+116414X0177Y    R180 S1      
327GND              U26   -DJ19       A01X+050972Y+116414X0177Y    R180 S1      
327GND              U26   -DJ43       A01X+042460Y+116414X0177Y    R180 S1      
327GND              U26   -DJ49       A01X+040239Y+116414X0177Y    R180 S1      
327GND              U26   -DJ59       A01X+036538Y+116414X0177Y    R180 S1      
327GND              U26   -DJ61       A01X+035798Y+116414X0177Y    R180 S1      
327GND              U26   -DJ63       A01X+035058Y+116414X0177Y    R180 S1      
327GND              U26   -DJ66       A01X+033948Y+116414X0177Y    R180 S1      
327GND              U26   -DJ68       A01X+033208Y+116414X0177Y    R180 S1      
327GND              U26   -DJ73       A01X+031357Y+116414X0177Y    R180 S1      
327GND              U26   -K23        A01X+049558Y+090299X0177Y    R180 S1      
327GND              U26   -K59        A01X+036235Y+090299X0177Y    R180 S1      
327GND              U26   -P25        A01X+048818Y+091575X0177Y    R180 S1      
327GND              U26   -P68        A01X+032905Y+091575X0177Y    R180 S1      
327GND              U26   -V27        A01X+048078Y+092850X0177Y    R180 S1      
327GND              U26   -V68        A01X+032905Y+092850X0177Y    R180 S1      
317GND              J45   -B3  MD0402PA00X+091878Y+170489X0657Y    R270 S3      
317GND              J45   -P1_1MD0402PA00X+103878Y+171489X0657Y    R270 S3      
317GND              J45   -P1_2MD0402PA00X+103878Y+170489X0657Y    R270 S3      
317GND              J45   -P1_3MD0402PA00X+103878Y+169489X0657Y    R270 S3      
317GND              J45   -P1_4MD0402PA00X+103878Y+168489X0657Y    R270 S3      
317GND              J45   -P1_5MD0402PA00X+102878Y+171489X0657Y    R270 S3      
317GND              J45   -P1_6MD0402PA00X+102878Y+170489X0657Y    R270 S3      
317GND              J45   -P1_7MD0402PA00X+102878Y+169489X0657Y    R270 S3      
317GND              J45   -P1_8MD0402PA00X+102878Y+168489X0657Y    R270 S3      
317GND              J45   -P2_1MD0402PA00X+100378Y+171489X0657Y    R270 S3      
317GND              J45   -P2_2MD0402PA00X+100378Y+170489X0657Y    R270 S3      
317GND              J45   -P2_3MD0402PA00X+100378Y+169489X0657Y    R270 S3      
317GND              J45   -P2_4MD0402PA00X+100378Y+168489X0657Y    R270 S3      
317GND              J45   -P2_5MD0402PA00X+099378Y+171489X0657Y    R270 S3      
317GND              J45   -P2_6MD0402PA00X+099378Y+170489X0657Y    R270 S3      
317GND              J45   -P2_7MD0402PA00X+099378Y+169489X0657Y    R270 S3      
317GND              J45   -P2_8MD0402PA00X+099378Y+168489X0657Y    R270 S3      
317GND              J45   -P3_1MD0402PA00X+096878Y+171489X0657Y    R270 S3      
317GND              J45   -P3_2MD0402PA00X+096878Y+170489X0657Y    R270 S3      
317GND              J45   -P3_3MD0402PA00X+096878Y+169489X0657Y    R270 S3      
317GND              J45   -P3_4MD0402PA00X+096878Y+168489X0657Y    R270 S3      
317GND              J45   -P3_5MD0402PA00X+095878Y+171489X0657Y    R270 S3      
317GND              J45   -P3_6MD0402PA00X+095878Y+170489X0657Y    R270 S3      
317GND              J45   -P3_7MD0402PA00X+095878Y+169489X0657Y    R270 S3      
317GND              J45   -P3_8MD0402PA00X+095878Y+168489X0657Y    R270 S3      
327GND              Y8004 -2          A01X+002500Y+038778X0360Y0400     S1      
327GND              Y8004 -4          A01X+003110Y+039507X0360Y0400     S1      
327GND              U320  -3          A01X+150244Y+013456X0180Y0520R090 S1      
327GND              U321  -3          A01X+034767Y+012252X0180Y0520R270 S1      
317GND              VIA   -    MD0100PA00X+075009Y+007282X0200Y         S0      
317GND              VIA   -    MD0100PA00X+071734Y+005710X0200Y         S0      
327GND              PC479 -2          A01X+144174Y+059629X0198Y0197R270 S1      
317GND              VIA   -    MD0100PA00X+046405Y+022480X0200Y         S0      
317GND              VIA   -    MD0100PA00X+082611Y+126955X0200Y         S0      
317GND              J105  -A8  MD0197PA00X+162500Y+173342X0357Y    R180 S3      
317GND              J105  -A6  MD0197PA00X+160925Y+173342X0357Y    R180 S3      
317GND              J105  -A4  MD0197PA00X+159350Y+173342X0357Y    R180 S3      
317GND              J105  -A2  MD0197PA00X+157776Y+173342X0357Y    R180 S3      
317GND              J106  -A8  MD0197PA00X+155807Y+173342X0357Y    R180 S3      
317GND              J106  -A6  MD0197PA00X+154232Y+173342X0357Y    R180 S3      
317GND              J106  -A4  MD0197PA00X+152657Y+173342X0357Y    R180 S3      
317GND              J106  -A2  MD0197PA00X+151083Y+173342X0357Y    R180 S3      
317GND              VIA   -    MD0100PA00X+139318Y+173312X0200Y    R270 S0      
317GND              J107  -A8  MD0197PA00X+136083Y+173342X0357Y    R180 S3      
317GND              J107  -A6  MD0197PA00X+134508Y+173342X0357Y    R180 S3      
317GND              J107  -A4  MD0197PA00X+132933Y+173342X0357Y    R180 S3      
317GND              J107  -A2  MD0197PA00X+131358Y+173342X0357Y    R180 S3      
317GND              J108  -A8  MD0197PA00X+129390Y+173342X0357Y    R180 S3      
317GND              J108  -A6  MD0197PA00X+127815Y+173342X0357Y    R180 S3      
317GND              J108  -A4  MD0197PA00X+126240Y+173342X0357Y    R180 S3      
317GND              J108  -A2  MD0197PA00X+124665Y+173342X0357Y    R180 S3      
317GND              J109  -A8  MD0197PA00X+061713Y+173342X0357Y    R180 S3      
317GND              J109  -A6  MD0197PA00X+060138Y+173342X0357Y    R180 S3      
317GND              J109  -A4  MD0197PA00X+058563Y+173342X0357Y    R180 S3      
317GND              J109  -A2  MD0197PA00X+056988Y+173342X0357Y    R180 S3      
317GND              J110  -A8  MD0197PA00X+055020Y+173342X0357Y    R180 S3      
317GND              J110  -A6  MD0197PA00X+053445Y+173342X0357Y    R180 S3      
317GND              J110  -A4  MD0197PA00X+051870Y+173342X0357Y    R180 S3      
317GND              J110  -A2  MD0197PA00X+050295Y+173342X0357Y    R180 S3      
317GND              VIA   -    MD0100PA00X+046250Y+173350X0200Y    R270 S0      
317GND              J111  -A8  MD0197PA00X+035295Y+173342X0357Y    R180 S3      
317GND              J111  -A6  MD0197PA00X+033720Y+173342X0357Y    R180 S3      
317GND              J111  -A4  MD0197PA00X+032146Y+173342X0357Y    R180 S3      
317GND              J111  -A2  MD0197PA00X+030571Y+173342X0357Y    R180 S3      
317GND              J112  -A8  MD0197PA00X+028602Y+173342X0357Y    R180 S3      
317GND              J112  -A6  MD0197PA00X+027028Y+173342X0357Y    R180 S3      
317GND              J112  -A4  MD0197PA00X+025453Y+173342X0357Y    R180 S3      
317GND              J112  -A2  MD0197PA00X+023878Y+173342X0357Y    R180 S3      
317GND              VIA   -    MD0080PA00X+161949Y+171790X0180Y         S0      
317GND              VIA   -    MD0080PA00X+161949Y+172244X0180Y         S0      
317GND              VIA   -    MD0080PA00X+161949Y+172697X0180Y         S0      
317GND              VIA   -    MD0080PA00X+162736Y+173091X0180Y         S0      
317GND              VIA   -    MD0080PA00X+162736Y+172638X0180Y         S0      
317GND              VIA   -    MD0080PA00X+162736Y+172184X0180Y         S0      
317GND              J105  -D8  MD0197PA00X+162500Y+171925X0357Y    R180 S3      
317GND              VIA   -    MD0080PA00X+160374Y+171790X0180Y         S0      
317GND              VIA   -    MD0080PA00X+160374Y+172244X0180Y         S0      
317GND              VIA   -    MD0080PA00X+160374Y+172697X0180Y         S0      
317GND              VIA   -    MD0080PA00X+161161Y+173091X0180Y         S0      
317GND              VIA   -    MD0080PA00X+161161Y+172638X0180Y         S0      
317GND              VIA   -    MD0080PA00X+161161Y+172184X0180Y         S0      
317GND              J105  -B7  MD0197PA00X+161713Y+172949X0357Y    R180 S3      
317GND              J105  -D6  MD0197PA00X+160925Y+171925X0357Y    R180 S3      
317GND              VIA   -    MD0080PA00X+159586Y+173091X0180Y         S0      
317GND              VIA   -    MD0080PA00X+159586Y+172638X0180Y         S0      
317GND              VIA   -    MD0080PA00X+159586Y+172184X0180Y         S0      
317GND              J105  -B5  MD0197PA00X+160138Y+172949X0357Y    R180 S3      
317GND              J105  -D4  MD0197PA00X+159350Y+171925X0357Y    R180 S3      
317GND              VIA   -    MD0080PA00X+158799Y+171790X0180Y         S0      
317GND              VIA   -    MD0080PA00X+158799Y+172244X0180Y         S0      
317GND              VIA   -    MD0080PA00X+158799Y+172697X0180Y         S0      
317GND              VIA   -    MD0080PA00X+158012Y+173091X0180Y         S0      
317GND              VIA   -    MD0080PA00X+158012Y+172638X0180Y         S0      
317GND              VIA   -    MD0080PA00X+158012Y+172184X0180Y         S0      
317GND              J105  -B3  MD0197PA00X+158563Y+172949X0357Y    R180 S3      
317GND              J105  -D2  MD0197PA00X+157776Y+171925X0357Y    R180 S3      
317GND              VIA   -    MD0080PA00X+156043Y+173091X0180Y         S0      
317GND              VIA   -    MD0080PA00X+156043Y+172638X0180Y         S0      
317GND              VIA   -    MD0080PA00X+156043Y+172184X0180Y         S0      
317GND              VIA   -    MD0080PA00X+157224Y+171790X0180Y         S0      
317GND              VIA   -    MD0080PA00X+157224Y+172244X0180Y         S0      
317GND              VIA   -    MD0080PA00X+157224Y+172697X0180Y         S0      
317GND              J105  -B1  MD0197PA00X+156988Y+172949X0357Y    R180 S3      
317GND              VIA   -    MD0080PA00X+155256Y+171790X0180Y         S0      
317GND              VIA   -    MD0080PA00X+155256Y+172244X0180Y         S0      
317GND              VIA   -    MD0080PA00X+155256Y+172697X0180Y         S0      
317GND              VIA   -    MD0080PA00X+154468Y+173091X0180Y         S0      
317GND              VIA   -    MD0080PA00X+154468Y+172638X0180Y         S0      
317GND              VIA   -    MD0080PA00X+154468Y+172184X0180Y         S0      
317GND              J106  -B7  MD0197PA00X+155020Y+172949X0357Y    R180 S3      
317GND              J106  -D8  MD0197PA00X+155807Y+171925X0357Y    R180 S3      
317GND              VIA   -    MD0080PA00X+153681Y+171790X0180Y         S0      
317GND              VIA   -    MD0080PA00X+153681Y+172244X0180Y         S0      
317GND              VIA   -    MD0080PA00X+153681Y+172697X0180Y         S0      
317GND              VIA   -    MD0080PA00X+152894Y+173091X0180Y         S0      
317GND              VIA   -    MD0080PA00X+152894Y+172638X0180Y         S0      
317GND              VIA   -    MD0080PA00X+152894Y+172184X0180Y         S0      
317GND              J106  -B5  MD0197PA00X+153445Y+172949X0357Y    R180 S3      
317GND              J106  -D6  MD0197PA00X+154232Y+171925X0357Y    R180 S3      
317GND              VIA   -    MD0080PA00X+152106Y+171790X0180Y         S0      
317GND              VIA   -    MD0080PA00X+152106Y+172244X0180Y         S0      
317GND              VIA   -    MD0080PA00X+152106Y+172697X0180Y         S0      
317GND              J106  -B3  MD0197PA00X+151870Y+172949X0357Y    R180 S3      
317GND              J106  -D4  MD0197PA00X+152657Y+171925X0357Y    R180 S3      
317GND              VIA   -    MD0080PA00X+150531Y+171790X0180Y         S0      
317GND              VIA   -    MD0080PA00X+150531Y+172244X0180Y         S0      
317GND              VIA   -    MD0080PA00X+150531Y+172697X0180Y         S0      
317GND              VIA   -    MD0080PA00X+151319Y+173091X0180Y         S0      
317GND              VIA   -    MD0080PA00X+151319Y+172638X0180Y         S0      
317GND              VIA   -    MD0080PA00X+151319Y+172184X0180Y         S0      
317GND              J106  -B1  MD0197PA00X+150295Y+172949X0357Y    R180 S3      
317GND              J106  -D2  MD0197PA00X+151083Y+171925X0357Y    R180 S3      
317GND              VIA   -    MD0100PA00X+138506Y+172142X0200Y         S0      
327GND              U316  -3          A01X+138506Y+172392X0160Y0200R180 S1      
317GND              VIA   -    MD0100PA00X+138762Y+172142X0200Y         S0      
327GND              U316  -2          A01X+138762Y+172392X0160Y0200R180 S1      
317GND              VIA   -    MD0100PA00X+138460Y+172832X0200Y    R270 S0      
327GND              R4548 -2          A01X+138703Y+172832X0198Y0197R180 S1      
317GND              VIA   -    MD0080PA00X+136319Y+172184X0180Y         S0      
317GND              VIA   -    MD0080PA00X+135531Y+171790X0180Y         S0      
317GND              VIA   -    MD0080PA00X+135531Y+172244X0180Y         S0      
317GND              VIA   -    MD0080PA00X+135531Y+172697X0180Y         S0      
317GND              VIA   -    MD0080PA00X+136319Y+173091X0180Y         S0      
317GND              VIA   -    MD0080PA00X+136319Y+172638X0180Y         S0      
317GND              J107  -B7  MD0197PA00X+135295Y+172949X0357Y    R180 S3      
317GND              J107  -D8  MD0197PA00X+136083Y+171925X0357Y    R180 S3      
317GND              VIA   -    MD0080PA00X+133956Y+171790X0180Y         S0      
317GND              VIA   -    MD0080PA00X+133956Y+172244X0180Y         S0      
317GND              VIA   -    MD0080PA00X+133956Y+172697X0180Y         S0      
317GND              VIA   -    MD0080PA00X+134744Y+173091X0180Y         S0      
317GND              VIA   -    MD0080PA00X+134744Y+172638X0180Y         S0      
317GND              VIA   -    MD0080PA00X+134744Y+172184X0180Y         S0      
317GND              J107  -B5  MD0197PA00X+133720Y+172949X0357Y    R180 S3      
317GND              J107  -D6  MD0197PA00X+134508Y+171925X0357Y    R180 S3      
317GND              VIA   -    MD0080PA00X+132382Y+171790X0180Y         S0      
317GND              VIA   -    MD0080PA00X+132382Y+172244X0180Y         S0      
317GND              VIA   -    MD0080PA00X+132382Y+172697X0180Y         S0      
317GND              VIA   -    MD0080PA00X+133169Y+173091X0180Y         S0      
317GND              VIA   -    MD0080PA00X+133169Y+172638X0180Y         S0      
317GND              VIA   -    MD0080PA00X+133169Y+172184X0180Y         S0      
317GND              J107  -B3  MD0197PA00X+132146Y+172949X0357Y    R180 S3      
317GND              J107  -D4  MD0197PA00X+132933Y+171925X0357Y    R180 S3      
317GND              VIA   -    MD0080PA00X+130807Y+171790X0180Y         S0      
317GND              VIA   -    MD0080PA00X+130807Y+172244X0180Y         S0      
317GND              VIA   -    MD0080PA00X+130807Y+172697X0180Y         S0      
317GND              VIA   -    MD0080PA00X+131594Y+173091X0180Y         S0      
317GND              VIA   -    MD0080PA00X+131594Y+172638X0180Y         S0      
317GND              VIA   -    MD0080PA00X+131594Y+172184X0180Y         S0      
317GND              J107  -D2  MD0197PA00X+131358Y+171925X0357Y    R180 S3      
317GND              VIA   -    MD0080PA00X+129626Y+173091X0180Y         S0      
317GND              VIA   -    MD0080PA00X+129626Y+172638X0180Y         S0      
317GND              VIA   -    MD0080PA00X+129626Y+172184X0180Y         S0      
317GND              J108  -D8  MD0197PA00X+129390Y+171925X0357Y    R180 S3      
317GND              J107  -B1  MD0197PA00X+130571Y+172949X0357Y    R180 S3      
317GND              VIA   -    MD0080PA00X+128838Y+171790X0180Y         S0      
317GND              VIA   -    MD0080PA00X+128838Y+172244X0180Y         S0      
317GND              VIA   -    MD0080PA00X+128838Y+172697X0180Y         S0      
317GND              VIA   -    MD0080PA00X+128051Y+173091X0180Y         S0      
317GND              VIA   -    MD0080PA00X+128051Y+172638X0180Y         S0      
317GND              VIA   -    MD0080PA00X+128051Y+172184X0180Y         S0      
317GND              J108  -B7  MD0197PA00X+128602Y+172949X0357Y    R180 S3      
317GND              J108  -D6  MD0197PA00X+127815Y+171925X0357Y    R180 S3      
317GND              VIA   -    MD0080PA00X+127264Y+171790X0180Y         S0      
317GND              VIA   -    MD0080PA00X+127264Y+172244X0180Y         S0      
317GND              VIA   -    MD0080PA00X+127264Y+172697X0180Y         S0      
317GND              VIA   -    MD0080PA00X+126476Y+173091X0180Y         S0      
317GND              VIA   -    MD0080PA00X+126476Y+172638X0180Y         S0      
317GND              VIA   -    MD0080PA00X+126476Y+172184X0180Y         S0      
317GND              J108  -B5  MD0197PA00X+127027Y+172949X0357Y    R180 S3      
317GND              J108  -D4  MD0197PA00X+126240Y+171925X0357Y    R180 S3      
317GND              VIA   -    MD0080PA00X+125689Y+171790X0180Y         S0      
317GND              VIA   -    MD0080PA00X+125689Y+172244X0180Y         S0      
317GND              VIA   -    MD0080PA00X+125689Y+172697X0180Y         S0      
317GND              VIA   -    MD0080PA00X+124901Y+173091X0180Y         S0      
317GND              VIA   -    MD0080PA00X+124901Y+172638X0180Y         S0      
317GND              VIA   -    MD0080PA00X+124901Y+172184X0180Y         S0      
317GND              J108  -B3  MD0197PA00X+125453Y+172949X0357Y    R180 S3      
317GND              J108  -D2  MD0197PA00X+124665Y+171925X0357Y    R180 S3      
317GND              VIA   -    MD0080PA00X+124114Y+171790X0180Y         S0      
317GND              VIA   -    MD0080PA00X+124114Y+172244X0180Y         S0      
317GND              VIA   -    MD0080PA00X+124114Y+172697X0180Y         S0      
317GND              J108  -B1  MD0197PA00X+123878Y+172949X0357Y    R180 S3      
317GND              VIA   -    MD0100PA00X+121974Y+173101X0200Y         S0      
327GND              R4134 -2          A01X+121425Y+172086X0198Y0197R270 S1      
317GND              VIA   -    MD0100PA00X+121674Y+172086X0200Y    R090 S0      
327GND              C17   -2          A01X+121025Y+173101X0198Y0197R090 S1      
317GND              VIA   -    MD0100PA00X+120777Y+173101X0200Y    R270 S0      
327GND              Q129  -4          A01X+119431Y+172626X0170Y0200R270 S1      
317GND              VIA   -    M      A01X+119681Y+172626X0200Y         S2      
017GND              VIA   -    M      A18X+119681Y+172626X0260Y         S2      
017GND                    -    MD0100PA00X+119681Y+172626                       
327GND              Q129  -1          A01X+120179Y+172114X0170Y0200R270 S1      
317GND              VIA   -    M      A01X+119929Y+172114X0200Y    R180 S2      
017GND              VIA   -    M      A18X+119929Y+172114X0260Y    R180 S2      
017GND                    -    MD0100PA00X+119929Y+172114                       
317GND              VIA   -    MD0100PA00X+111200Y+171899X0200Y    R180 S0      
327GND              Q145  -4          A01X+111450Y+171899X0170Y0200R090 S1      
317GND              VIA   -    MD0100PA00X+110952Y+172411X0200Y         S0      
327GND              Q145  -1          A01X+110702Y+172411X0170Y0200R090 S1      
317GND              VIA   -    MD0100PA00X+109203Y+172084X0200Y         S0      
327GND              R4552 -2          A01X+109451Y+172599X0198Y0197R090 S1      
317GND              VIA   -    MD0100PA00X+109203Y+172599X0200Y    R270 S0      
317GND              VIA   -    MD0100PA00X+065967Y+172217X0200Y         S0      
327GND              Q102  -1   M      A01X+065717Y+172217X0170Y0200R090 S1      
317GND              VIA   -    MD0100PA00X+065967Y+173284X0200Y         S0      
327GND              Q67   -1   M      A01X+065717Y+173284X0170Y0200R090 S1      
317GND              VIA   -    MD0100PA00X+066215Y+172772X0200Y    R180 S0      
327GND              Q67   -4          A01X+066465Y+172772X0170Y0200R090 S1      
317GND              VIA   -    MD0080PA00X+061949Y+173091X0180Y         S0      
317GND              VIA   -    MD0080PA00X+061949Y+172638X0180Y         S0      
317GND              VIA   -    MD0080PA00X+061949Y+172184X0180Y         S0      
317GND              VIA   -    MD0080PA00X+061161Y+171790X0180Y         S0      
317GND              VIA   -    MD0080PA00X+061161Y+172244X0180Y         S0      
317GND              VIA   -    MD0080PA00X+061161Y+172697X0180Y         S0      
317GND              J109  -B7  MD0197PA00X+060925Y+172949X0357Y    R180 S3      
317GND              J109  -D8  MD0197PA00X+061713Y+171925X0357Y    R180 S3      
317GND              VIA   -    MD0080PA00X+059586Y+171790X0180Y         S0      
317GND              VIA   -    MD0080PA00X+059586Y+172244X0180Y         S0      
317GND              VIA   -    MD0080PA00X+059586Y+172697X0180Y         S0      
317GND              VIA   -    MD0080PA00X+060374Y+173091X0180Y         S0      
317GND              VIA   -    MD0080PA00X+060374Y+172638X0180Y         S0      
317GND              VIA   -    MD0080PA00X+060374Y+172184X0180Y         S0      
317GND              J109  -B5  MD0197PA00X+059350Y+172949X0357Y    R180 S3      
317GND              J109  -D6  MD0197PA00X+060138Y+171925X0357Y    R180 S3      
317GND              VIA   -    MD0080PA00X+058012Y+171790X0180Y         S0      
317GND              VIA   -    MD0080PA00X+058012Y+172244X0180Y         S0      
317GND              VIA   -    MD0080PA00X+058012Y+172697X0180Y         S0      
317GND              VIA   -    MD0080PA00X+058799Y+173091X0180Y         S0      
317GND              VIA   -    MD0080PA00X+058799Y+172638X0180Y         S0      
317GND              VIA   -    MD0080PA00X+058799Y+172184X0180Y         S0      
317GND              J109  -B3  MD0197PA00X+057776Y+172949X0357Y    R180 S3      
317GND              J109  -D4  MD0197PA00X+058563Y+171925X0357Y    R180 S3      
317GND              VIA   -    MD0080PA00X+057224Y+172184X0180Y         S0      
317GND              VIA   -    MD0080PA00X+056437Y+171790X0180Y         S0      
317GND              VIA   -    MD0080PA00X+056437Y+172244X0180Y         S0      
317GND              VIA   -    MD0080PA00X+056437Y+172697X0180Y         S0      
317GND              VIA   -    MD0080PA00X+057224Y+173091X0180Y         S0      
317GND              VIA   -    MD0080PA00X+057224Y+172638X0180Y         S0      
317GND              J109  -B1  MD0197PA00X+056201Y+172949X0357Y    R180 S3      
317GND              J109  -D2  MD0197PA00X+056988Y+171925X0357Y    R180 S3      
317GND              VIA   -    MD0080PA00X+055256Y+173091X0180Y         S0      
317GND              VIA   -    MD0080PA00X+055256Y+172638X0180Y         S0      
317GND              VIA   -    MD0080PA00X+055256Y+172184X0180Y         S0      
317GND              J110  -D8  MD0197PA00X+055020Y+171925X0357Y    R180 S3      
317GND              VIA   -    MD0080PA00X+054468Y+171790X0180Y         S0      
317GND              VIA   -    MD0080PA00X+054468Y+172244X0180Y         S0      
317GND              VIA   -    MD0080PA00X+054468Y+172697X0180Y         S0      
317GND              VIA   -    MD0080PA00X+053681Y+173091X0180Y         S0      
317GND              VIA   -    MD0080PA00X+053681Y+172638X0180Y         S0      
317GND              VIA   -    MD0080PA00X+053681Y+172184X0180Y         S0      
317GND              J110  -B7  MD0197PA00X+054232Y+172949X0357Y    R180 S3      
317GND              J110  -D6  MD0197PA00X+053445Y+171925X0357Y    R180 S3      
317GND              VIA   -    MD0080PA00X+052894Y+171790X0180Y         S0      
317GND              VIA   -    MD0080PA00X+052894Y+172244X0180Y         S0      
317GND              VIA   -    MD0080PA00X+052894Y+172697X0180Y         S0      
317GND              VIA   -    MD0080PA00X+052106Y+173091X0180Y         S0      
317GND              VIA   -    MD0080PA00X+052106Y+172638X0180Y         S0      
317GND              VIA   -    MD0080PA00X+052106Y+172184X0180Y         S0      
317GND              J110  -B5  MD0197PA00X+052657Y+172949X0357Y    R180 S3      
317GND              J110  -D4  MD0197PA00X+051870Y+171925X0357Y    R180 S3      
317GND              VIA   -    MD0080PA00X+051319Y+171790X0180Y         S0      
317GND              VIA   -    MD0080PA00X+051319Y+172244X0180Y         S0      
317GND              VIA   -    MD0080PA00X+051319Y+172697X0180Y         S0      
317GND              VIA   -    MD0080PA00X+050531Y+173091X0180Y         S0      
317GND              VIA   -    MD0080PA00X+050531Y+172638X0180Y         S0      
317GND              VIA   -    MD0080PA00X+050531Y+172184X0180Y         S0      
317GND              J110  -B3  MD0197PA00X+051083Y+172949X0357Y    R180 S3      
317GND              J110  -D2  MD0197PA00X+050295Y+171925X0357Y    R180 S3      
317GND              VIA   -    MD0080PA00X+049744Y+171790X0180Y         S0      
317GND              VIA   -    MD0080PA00X+049744Y+172244X0180Y         S0      
317GND              VIA   -    MD0080PA00X+049744Y+172697X0180Y         S0      
317GND              J110  -B1  MD0197PA00X+049508Y+172949X0357Y    R180 S3      
317GND              VIA   -    MD0100PA00X+046998Y+172481X0200Y         S0      
327GND              U257  -2          A01X+046998Y+172753X0170Y0240R180 S1      
317GND              VIA   -    MD0100PA00X+046742Y+172481X0200Y         S0      
327GND              U257  -3          A01X+046742Y+172753X0170Y0240R180 S1      
317GND              VIA   -    MD0080PA00X+035531Y+172184X0180Y         S0      
317GND              VIA   -    MD0080PA00X+035531Y+172638X0180Y         S0      
317GND              VIA   -    MD0080PA00X+035531Y+173091X0180Y         S0      
317GND              J111  -D8  MD0197PA00X+035295Y+171925X0357Y    R180 S3      
317GND              VIA   -    MD0080PA00X+033957Y+172184X0180Y         S0      
317GND              VIA   -    MD0080PA00X+033957Y+172638X0180Y         S0      
317GND              VIA   -    MD0080PA00X+033957Y+173091X0180Y         S0      
317GND              VIA   -    MD0080PA00X+034744Y+172697X0180Y         S0      
317GND              VIA   -    MD0080PA00X+034744Y+172244X0180Y         S0      
317GND              VIA   -    MD0080PA00X+034744Y+171790X0180Y         S0      
317GND              J111  -B7  MD0197PA00X+034508Y+172949X0357Y    R180 S3      
317GND              J111  -D6  MD0197PA00X+033720Y+171925X0357Y    R180 S3      
317GND              VIA   -    MD0080PA00X+032382Y+172638X0180Y         S0      
317GND              VIA   -    MD0080PA00X+032382Y+173091X0180Y         S0      
317GND              VIA   -    MD0080PA00X+033169Y+172697X0180Y         S0      
317GND              VIA   -    MD0080PA00X+033169Y+172244X0180Y         S0      
317GND              VIA   -    MD0080PA00X+033169Y+171790X0180Y         S0      
317GND              VIA   -    MD0080PA00X+032382Y+172184X0180Y         S0      
317GND              J111  -B5  MD0197PA00X+032933Y+172949X0357Y    R180 S3      
317GND              VIA   -    MD0080PA00X+031594Y+171790X0180Y         S0      
317GND              VIA   -    MD0080PA00X+030807Y+172184X0180Y         S0      
317GND              VIA   -    MD0080PA00X+030807Y+172638X0180Y         S0      
317GND              VIA   -    MD0080PA00X+030807Y+173091X0180Y         S0      
317GND              VIA   -    MD0080PA00X+031594Y+172697X0180Y         S0      
317GND              VIA   -    MD0080PA00X+031594Y+172244X0180Y         S0      
317GND              J111  -B3  MD0197PA00X+031358Y+172949X0357Y    R180 S3      
317GND              J111  -D4  MD0197PA00X+032146Y+171925X0357Y    R180 S3      
317GND              VIA   -    MD0080PA00X+030020Y+172697X0180Y         S0      
317GND              VIA   -    MD0080PA00X+030020Y+172244X0180Y         S0      
317GND              VIA   -    MD0080PA00X+030020Y+171790X0180Y         S0      
317GND              J111  -B1  MD0197PA00X+029784Y+172949X0357Y    R180 S3      
317GND              J111  -D2  MD0197PA00X+030571Y+171925X0357Y    R180 S3      
317GND              VIA   -    MD0080PA00X+028051Y+171790X0180Y         S0      
317GND              VIA   -    MD0080PA00X+028051Y+172244X0180Y         S0      
317GND              VIA   -    MD0080PA00X+028051Y+172697X0180Y         S0      
317GND              VIA   -    MD0080PA00X+028838Y+173091X0180Y         S0      
317GND              VIA   -    MD0080PA00X+028838Y+172638X0180Y         S0      
317GND              VIA   -    MD0080PA00X+028838Y+172184X0180Y         S0      
317GND              J112  -B7  MD0197PA00X+027815Y+172949X0357Y    R180 S3      
317GND              J112  -D8  MD0197PA00X+028602Y+171925X0357Y    R180 S3      
317GND              VIA   -    MD0080PA00X+026476Y+171790X0180Y         S0      
317GND              VIA   -    MD0080PA00X+026476Y+172244X0180Y         S0      
317GND              VIA   -    MD0080PA00X+026476Y+172697X0180Y         S0      
317GND              VIA   -    MD0080PA00X+027264Y+173091X0180Y         S0      
317GND              VIA   -    MD0080PA00X+027264Y+172638X0180Y         S0      
317GND              VIA   -    MD0080PA00X+027264Y+172184X0180Y         S0      
317GND              J112  -B5  MD0197PA00X+026240Y+172949X0357Y    R180 S3      
317GND              J112  -D6  MD0197PA00X+027028Y+171925X0357Y    R180 S3      
317GND              VIA   -    MD0080PA00X+024902Y+171790X0180Y         S0      
317GND              VIA   -    MD0080PA00X+024902Y+172244X0180Y         S0      
317GND              VIA   -    MD0080PA00X+024902Y+172697X0180Y         S0      
317GND              VIA   -    MD0080PA00X+025689Y+173091X0180Y         S0      
317GND              VIA   -    MD0080PA00X+025689Y+172638X0180Y         S0      
317GND              VIA   -    MD0080PA00X+025689Y+172184X0180Y         S0      
317GND              J112  -D4  MD0197PA00X+025453Y+171925X0357Y    R180 S3      
317GND              VIA   -    MD0080PA00X+023327Y+172697X0180Y         S0      
317GND              VIA   -    MD0080PA00X+023327Y+172244X0180Y         S0      
317GND              VIA   -    MD0080PA00X+023327Y+171790X0180Y         S0      
317GND              VIA   -    MD0080PA00X+024114Y+173091X0180Y         S0      
317GND              VIA   -    MD0080PA00X+024114Y+172638X0180Y         S0      
317GND              VIA   -    MD0080PA00X+024114Y+172184X0180Y         S0      
317GND              J112  -B3  MD0197PA00X+024665Y+172949X0357Y    R180 S3      
317GND              J112  -D2  MD0197PA00X+023878Y+171925X0357Y    R180 S3      
317GND              J112  -B1  MD0197PA00X+023090Y+172949X0357Y    R180 S3      
317GND              VIA   -    MD0080PA00X+161949Y+171280X0180Y         S0      
317GND              VIA   -    MD0080PA00X+162736Y+171220X0180Y         S0      
317GND              VIA   -    MD0080PA00X+162736Y+170767X0180Y         S0      
317GND              VIA   -    MD0080PA00X+162736Y+170256X0180Y         S0      
317GND              VIA   -    MD0080PA00X+162736Y+171674X0180Y         S0      
317GND              VIA   -    MD0080PA00X+161949Y+170373X0180Y         S0      
317GND              VIA   -    MD0080PA00X+161949Y+170827X0180Y         S0      
317GND              J105  -G8  MD0197PA00X+162500Y+170508X0357Y    R180 S3      
317GND              VIA   -    MD0080PA00X+161161Y+171674X0180Y         S0      
317GND              VIA   -    MD0080PA00X+160374Y+170373X0180Y         S0      
317GND              VIA   -    MD0080PA00X+160374Y+170827X0180Y         S0      
317GND              VIA   -    MD0080PA00X+160374Y+171280X0180Y         S0      
317GND              VIA   -    MD0080PA00X+161161Y+171220X0180Y         S0      
317GND              VIA   -    MD0080PA00X+161161Y+170767X0180Y         S0      
317GND              VIA   -    MD0080PA00X+161161Y+170256X0180Y         S0      
317GND              J105  -E7  MD0197PA00X+161713Y+171531X0357Y    R180 S3      
317GND              J105  -G6  MD0197PA00X+160925Y+170508X0357Y    R180 S3      
317GND              VIA   -    MD0080PA00X+159586Y+171220X0180Y         S0      
317GND              VIA   -    MD0080PA00X+159586Y+170767X0180Y         S0      
317GND              VIA   -    MD0080PA00X+159586Y+170256X0180Y         S0      
317GND              VIA   -    MD0080PA00X+159586Y+171674X0180Y         S0      
317GND              J105  -E5  MD0197PA00X+160138Y+171531X0357Y    R180 S3      
317GND              J105  -G4  MD0197PA00X+159350Y+170508X0357Y    R180 S3      
317GND              VIA   -    MD0080PA00X+158799Y+170373X0180Y         S0      
317GND              VIA   -    MD0080PA00X+158799Y+170827X0180Y         S0      
317GND              VIA   -    MD0080PA00X+158799Y+171280X0180Y         S0      
317GND              VIA   -    MD0080PA00X+158012Y+171220X0180Y         S0      
317GND              VIA   -    MD0080PA00X+158012Y+170767X0180Y         S0      
317GND              VIA   -    MD0080PA00X+158012Y+170256X0180Y         S0      
317GND              VIA   -    MD0080PA00X+158012Y+171674X0180Y         S0      
317GND              J105  -E3  MD0197PA00X+158563Y+171531X0357Y    R180 S3      
317GND              J105  -G2  MD0197PA00X+157776Y+170508X0357Y    R180 S3      
317GND              VIA   -    MD0080PA00X+156043Y+171220X0180Y         S0      
317GND              VIA   -    MD0080PA00X+156043Y+170767X0180Y         S0      
317GND              VIA   -    MD0080PA00X+156043Y+170256X0180Y         S0      
317GND              VIA   -    MD0080PA00X+156043Y+171674X0180Y         S0      
317GND              VIA   -    MD0080PA00X+157224Y+170373X0180Y         S0      
317GND              VIA   -    MD0080PA00X+157224Y+170827X0180Y         S0      
317GND              VIA   -    MD0080PA00X+157224Y+171280X0180Y         S0      
317GND              J105  -E1  MD0197PA00X+156988Y+171531X0357Y    R180 S3      
317GND              VIA   -    MD0080PA00X+155256Y+170373X0180Y         S0      
317GND              VIA   -    MD0080PA00X+155256Y+170827X0180Y         S0      
317GND              VIA   -    MD0080PA00X+155256Y+171280X0180Y         S0      
317GND              VIA   -    MD0080PA00X+154468Y+171220X0180Y         S0      
317GND              VIA   -    MD0080PA00X+154468Y+170767X0180Y         S0      
317GND              VIA   -    MD0080PA00X+154468Y+170256X0180Y         S0      
317GND              VIA   -    MD0080PA00X+154468Y+171674X0180Y         S0      
317GND              J106  -E7  MD0197PA00X+155020Y+171531X0357Y    R180 S3      
317GND              J106  -G8  MD0197PA00X+155807Y+170508X0357Y    R180 S3      
317GND              VIA   -    MD0080PA00X+152894Y+170767X0180Y         S0      
317GND              VIA   -    MD0080PA00X+152894Y+170256X0180Y         S0      
317GND              VIA   -    MD0080PA00X+152894Y+171674X0180Y         S0      
317GND              VIA   -    MD0080PA00X+153681Y+170373X0180Y         S0      
317GND              VIA   -    MD0080PA00X+153681Y+170827X0180Y         S0      
317GND              VIA   -    MD0080PA00X+153681Y+171280X0180Y         S0      
317GND              VIA   -    MD0080PA00X+152894Y+171220X0180Y         S0      
317GND              J106  -E5  MD0197PA00X+153445Y+171531X0357Y    R180 S3      
317GND              J106  -G6  MD0197PA00X+154232Y+170508X0357Y    R180 S3      
317GND              VIA   -    MD0080PA00X+152106Y+170373X0180Y         S0      
317GND              VIA   -    MD0080PA00X+152106Y+170827X0180Y         S0      
317GND              VIA   -    MD0080PA00X+152106Y+171280X0180Y         S0      
317GND              J106  -E3  MD0197PA00X+151870Y+171531X0357Y    R180 S3      
317GND              J106  -G4  MD0197PA00X+152657Y+170508X0357Y    R180 S3      
317GND              VIA   -    MD0080PA00X+150531Y+170373X0180Y         S0      
317GND              VIA   -    MD0080PA00X+150531Y+170827X0180Y         S0      
317GND              VIA   -    MD0080PA00X+150531Y+171280X0180Y         S0      
317GND              VIA   -    MD0080PA00X+151319Y+171220X0180Y         S0      
317GND              VIA   -    MD0080PA00X+151319Y+170767X0180Y         S0      
317GND              VIA   -    MD0080PA00X+151319Y+170256X0180Y         S0      
317GND              VIA   -    MD0080PA00X+151319Y+171674X0180Y         S0      
317GND              J106  -E1  MD0197PA00X+150295Y+171531X0357Y    R180 S3      
317GND              J106  -G2  MD0197PA00X+151083Y+170508X0357Y    R180 S3      
317GND              VIA   -    MD0100PA00X+138204Y+170804X0200Y    R270 S0      
327GND              R4555 -2          A01X+138447Y+170804X0198Y0197R180 S1      
317GND              VIA   -    MD0100PA00X+138204Y+171204X0200Y    R270 S0      
327GND              C8    -2          A01X+138447Y+171204X0198Y0197R180 S1      
317GND              VIA   -    MD0080PA00X+135531Y+170373X0180Y         S0      
317GND              VIA   -    MD0080PA00X+135531Y+170827X0180Y         S0      
317GND              VIA   -    MD0080PA00X+135531Y+171280X0180Y         S0      
317GND              VIA   -    MD0080PA00X+136319Y+171220X0180Y         S0      
317GND              VIA   -    MD0080PA00X+136319Y+170767X0180Y         S0      
317GND              VIA   -    MD0080PA00X+136319Y+170256X0180Y         S0      
317GND              VIA   -    MD0080PA00X+136319Y+171674X0180Y         S0      
317GND              J107  -E7  MD0197PA00X+135295Y+171531X0357Y    R180 S3      
317GND              J107  -G8  MD0197PA00X+136083Y+170508X0357Y    R180 S3      
317GND              VIA   -    MD0080PA00X+133956Y+170373X0180Y         S0      
317GND              VIA   -    MD0080PA00X+133956Y+170827X0180Y         S0      
317GND              VIA   -    MD0080PA00X+133956Y+171280X0180Y         S0      
317GND              VIA   -    MD0080PA00X+134744Y+171220X0180Y         S0      
317GND              VIA   -    MD0080PA00X+134744Y+170767X0180Y         S0      
317GND              VIA   -    MD0080PA00X+134744Y+170256X0180Y         S0      
317GND              VIA   -    MD0080PA00X+134744Y+171674X0180Y         S0      
317GND              J107  -E5  MD0197PA00X+133720Y+171531X0357Y    R180 S3      
317GND              J107  -G6  MD0197PA00X+134508Y+170508X0357Y    R180 S3      
317GND              VIA   -    MD0080PA00X+132382Y+170373X0180Y         S0      
317GND              VIA   -    MD0080PA00X+132382Y+170827X0180Y         S0      
317GND              VIA   -    MD0080PA00X+132382Y+171280X0180Y         S0      
317GND              VIA   -    MD0080PA00X+133169Y+171220X0180Y         S0      
317GND              VIA   -    MD0080PA00X+133169Y+170767X0180Y         S0      
317GND              VIA   -    MD0080PA00X+133169Y+170256X0180Y         S0      
317GND              VIA   -    MD0080PA00X+133169Y+171674X0180Y         S0      
317GND              J107  -E3  MD0197PA00X+132146Y+171531X0357Y    R180 S3      
317GND              J107  -G4  MD0197PA00X+132933Y+170508X0357Y    R180 S3      
317GND              VIA   -    MD0080PA00X+130807Y+170373X0180Y         S0      
317GND              VIA   -    MD0080PA00X+130807Y+170827X0180Y         S0      
317GND              VIA   -    MD0080PA00X+130807Y+171280X0180Y         S0      
317GND              VIA   -    MD0080PA00X+131594Y+171220X0180Y         S0      
317GND              VIA   -    MD0080PA00X+131594Y+170767X0180Y         S0      
317GND              VIA   -    MD0080PA00X+131594Y+170256X0180Y         S0      
317GND              VIA   -    MD0080PA00X+131594Y+171674X0180Y         S0      
317GND              J107  -G2  MD0197PA00X+131358Y+170508X0357Y    R180 S3      
317GND              VIA   -    MD0080PA00X+129626Y+171220X0180Y         S0      
317GND              VIA   -    MD0080PA00X+129626Y+170767X0180Y         S0      
317GND              VIA   -    MD0080PA00X+129626Y+170256X0180Y         S0      
317GND              VIA   -    MD0080PA00X+129626Y+171674X0180Y         S0      
317GND              J108  -G8  MD0197PA00X+129390Y+170508X0357Y    R180 S3      
317GND              J107  -E1  MD0197PA00X+130571Y+171531X0357Y    R180 S3      
317GND              VIA   -    MD0080PA00X+128838Y+170373X0180Y         S0      
317GND              VIA   -    MD0080PA00X+128838Y+170827X0180Y         S0      
317GND              VIA   -    MD0080PA00X+128838Y+171280X0180Y         S0      
317GND              VIA   -    MD0080PA00X+128051Y+171220X0180Y         S0      
317GND              VIA   -    MD0080PA00X+128051Y+170767X0180Y         S0      
317GND              VIA   -    MD0080PA00X+128051Y+170256X0180Y         S0      
317GND              VIA   -    MD0080PA00X+128051Y+171674X0180Y         S0      
317GND              J108  -E7  MD0197PA00X+128602Y+171531X0357Y    R180 S3      
317GND              J108  -G6  MD0197PA00X+127815Y+170508X0357Y    R180 S3      
317GND              VIA   -    MD0080PA00X+127264Y+170373X0180Y         S0      
317GND              VIA   -    MD0080PA00X+127264Y+170827X0180Y         S0      
317GND              VIA   -    MD0080PA00X+127264Y+171280X0180Y         S0      
317GND              VIA   -    MD0080PA00X+126476Y+171220X0180Y         S0      
317GND              VIA   -    MD0080PA00X+126476Y+170767X0180Y         S0      
317GND              VIA   -    MD0080PA00X+126476Y+170256X0180Y         S0      
317GND              VIA   -    MD0080PA00X+126476Y+171674X0180Y         S0      
317GND              J108  -E5  MD0197PA00X+127027Y+171531X0357Y    R180 S3      
317GND              J108  -G4  MD0197PA00X+126240Y+170508X0357Y    R180 S3      
317GND              VIA   -    MD0080PA00X+125689Y+170827X0180Y         S0      
317GND              VIA   -    MD0080PA00X+125689Y+171280X0180Y         S0      
317GND              VIA   -    MD0080PA00X+124901Y+171220X0180Y         S0      
317GND              VIA   -    MD0080PA00X+124901Y+170767X0180Y         S0      
317GND              VIA   -    MD0080PA00X+124901Y+170256X0180Y         S0      
317GND              VIA   -    MD0080PA00X+124901Y+171674X0180Y         S0      
317GND              VIA   -    MD0080PA00X+125689Y+170373X0180Y         S0      
317GND              J108  -E3  MD0197PA00X+125453Y+171531X0357Y    R180 S3      
317GND              J108  -G2  MD0197PA00X+124665Y+170508X0357Y    R180 S3      
317GND              VIA   -    MD0080PA00X+124114Y+170373X0180Y         S0      
317GND              VIA   -    MD0080PA00X+124114Y+170827X0180Y         S0      
317GND              VIA   -    MD0080PA00X+124114Y+171280X0180Y         S0      
317GND              J108  -E1  MD0197PA00X+123878Y+171531X0357Y    R180 S3      
317GND              VIA   -    MD0100PA00X+121974Y+171701X0200Y         S0      
327GND              R3430 -2          A01X+121425Y+170686X0198Y0197R270 S1      
317GND              VIA   -    MD0100PA00X+121688Y+170583X0200Y    R090 S0      
317GND              VIA   -    M      A01X+120777Y+171701X0200Y    R270 S2      
017GND              VIA   -    M      A18X+120777Y+171701X0260Y    R270 S2      
017GND                    -    MD0100PA00X+120777Y+171701                       
327GND              C1976 -2          A01X+121025Y+171701X0198Y0197R090 S1      
317GND              VIA   -    MD0100PA00X+120445Y+170714X0200Y    R180 S0      
327GND              Q104  -1          A01X+120175Y+170714X0170Y0200R270 S1      
317GND              VIA   -    M      A01X+119677Y+171226X0200Y         S2      
017GND              VIA   -    M      A18X+119677Y+171226X0260Y         S2      
017GND                    -    MD0100PA00X+119677Y+171226                       
327GND              Q104  -4          A01X+119427Y+171226X0170Y0200R270 S1      
317GND              VIA   -    MD0100PA00X+109549Y+170852X0200Y    R180 S0      
327GND              U308  -2          A01X+109549Y+171124X0170Y0240R180 S1      
317GND              VIA   -    MD0100PA00X+109203Y+171584X0200Y    R270 S0      
327GND              C70   -2          A01X+109451Y+171584X0198Y0197R270 S1      
317GND              VIA   -    MD0080PA00X+061949Y+171220X0180Y         S0      
317GND              VIA   -    MD0080PA00X+061949Y+170767X0180Y         S0      
317GND              VIA   -    MD0080PA00X+061949Y+170256X0180Y         S0      
317GND              VIA   -    MD0080PA00X+061949Y+171674X0180Y         S0      
317GND              VIA   -    MD0080PA00X+061161Y+170373X0180Y         S0      
317GND              VIA   -    MD0080PA00X+061161Y+170827X0180Y         S0      
317GND              VIA   -    MD0080PA00X+061161Y+171280X0180Y         S0      
317GND              J109  -E7  MD0197PA00X+060925Y+171531X0357Y    R180 S3      
317GND              J109  -G8  MD0197PA00X+061713Y+170508X0357Y    R180 S3      
317GND              VIA   -    MD0080PA00X+059586Y+170373X0180Y         S0      
317GND              VIA   -    MD0080PA00X+059586Y+170827X0180Y         S0      
317GND              VIA   -    MD0080PA00X+059586Y+171280X0180Y         S0      
317GND              VIA   -    MD0080PA00X+060374Y+171220X0180Y         S0      
317GND              VIA   -    MD0080PA00X+060374Y+170767X0180Y         S0      
317GND              VIA   -    MD0080PA00X+060374Y+170256X0180Y         S0      
317GND              VIA   -    MD0080PA00X+060374Y+171674X0180Y         S0      
317GND              J109  -E5  MD0197PA00X+059350Y+171531X0357Y    R180 S3      
317GND              J109  -G6  MD0197PA00X+060138Y+170508X0357Y    R180 S3      
317GND              VIA   -    MD0080PA00X+058012Y+170373X0180Y         S0      
317GND              VIA   -    MD0080PA00X+058012Y+170827X0180Y         S0      
317GND              VIA   -    MD0080PA00X+058012Y+171280X0180Y         S0      
317GND              VIA   -    MD0080PA00X+058799Y+171220X0180Y         S0      
317GND              VIA   -    MD0080PA00X+058799Y+170767X0180Y         S0      
317GND              VIA   -    MD0080PA00X+058799Y+170256X0180Y         S0      
317GND              VIA   -    MD0080PA00X+058799Y+171674X0180Y         S0      
317GND              J109  -E3  MD0197PA00X+057776Y+171531X0357Y    R180 S3      
317GND              J109  -G4  MD0197PA00X+058563Y+170508X0357Y    R180 S3      
317GND              VIA   -    MD0080PA00X+057224Y+171674X0180Y         S0      
317GND              VIA   -    MD0080PA00X+056437Y+170373X0180Y         S0      
317GND              VIA   -    MD0080PA00X+056437Y+170827X0180Y         S0      
317GND              VIA   -    MD0080PA00X+056437Y+171280X0180Y         S0      
317GND              VIA   -    MD0080PA00X+057224Y+171220X0180Y         S0      
317GND              VIA   -    MD0080PA00X+057224Y+170767X0180Y         S0      
317GND              VIA   -    MD0080PA00X+057224Y+170256X0180Y         S0      
317GND              J109  -E1  MD0197PA00X+056201Y+171531X0357Y    R180 S3      
317GND              J109  -G2  MD0197PA00X+056988Y+170508X0357Y    R180 S3      
317GND              VIA   -    MD0080PA00X+055256Y+171220X0180Y         S0      
317GND              VIA   -    MD0080PA00X+055256Y+170767X0180Y         S0      
317GND              VIA   -    MD0080PA00X+055256Y+170256X0180Y         S0      
317GND              VIA   -    MD0080PA00X+055256Y+171674X0180Y         S0      
317GND              J110  -G8  MD0197PA00X+055020Y+170508X0357Y    R180 S3      
317GND              VIA   -    MD0080PA00X+054468Y+170373X0180Y         S0      
317GND              VIA   -    MD0080PA00X+054468Y+170827X0180Y         S0      
317GND              VIA   -    MD0080PA00X+054468Y+171280X0180Y         S0      
317GND              VIA   -    MD0080PA00X+053681Y+171220X0180Y         S0      
317GND              VIA   -    MD0080PA00X+053681Y+170767X0180Y         S0      
317GND              VIA   -    MD0080PA00X+053681Y+170256X0180Y         S0      
317GND              VIA   -    MD0080PA00X+053681Y+171674X0180Y         S0      
317GND              J110  -E7  MD0197PA00X+054232Y+171531X0357Y    R180 S3      
317GND              J110  -G6  MD0197PA00X+053445Y+170508X0357Y    R180 S3      
317GND              VIA   -    MD0080PA00X+052894Y+170373X0180Y         S0      
317GND              VIA   -    MD0080PA00X+052894Y+170827X0180Y         S0      
317GND              VIA   -    MD0080PA00X+052894Y+171280X0180Y         S0      
317GND              VIA   -    MD0080PA00X+052106Y+171220X0180Y         S0      
317GND              VIA   -    MD0080PA00X+052106Y+170767X0180Y         S0      
317GND              VIA   -    MD0080PA00X+052106Y+170256X0180Y         S0      
317GND              VIA   -    MD0080PA00X+052106Y+171674X0180Y         S0      
317GND              J110  -E5  MD0197PA00X+052657Y+171531X0357Y    R180 S3      
317GND              J110  -G4  MD0197PA00X+051870Y+170508X0357Y    R180 S3      
317GND              VIA   -    MD0080PA00X+050531Y+170256X0180Y         S0      
317GND              VIA   -    MD0080PA00X+050531Y+171674X0180Y         S0      
317GND              VIA   -    MD0080PA00X+051319Y+170373X0180Y         S0      
317GND              VIA   -    MD0080PA00X+051319Y+170827X0180Y         S0      
317GND              VIA   -    MD0080PA00X+051319Y+171280X0180Y         S0      
317GND              VIA   -    MD0080PA00X+050531Y+171220X0180Y         S0      
317GND              VIA   -    MD0080PA00X+050531Y+170767X0180Y         S0      
317GND              J110  -E3  MD0197PA00X+051083Y+171531X0357Y    R180 S3      
317GND              J110  -G2  MD0197PA00X+050295Y+170508X0357Y    R180 S3      
317GND              VIA   -    MD0080PA00X+049744Y+170373X0180Y         S0      
317GND              VIA   -    MD0080PA00X+049744Y+170827X0180Y         S0      
317GND              VIA   -    MD0080PA00X+049744Y+171280X0180Y         S0      
317GND              J110  -E1  MD0197PA00X+049508Y+171531X0357Y    R180 S3      
317GND              VIA   -    MD0080PA00X+035531Y+170256X0180Y         S0      
317GND              VIA   -    MD0080PA00X+035531Y+170767X0180Y         S0      
317GND              VIA   -    MD0080PA00X+035531Y+171220X0180Y         S0      
317GND              VIA   -    MD0080PA00X+035531Y+171674X0180Y         S0      
317GND              J111  -G8  MD0197PA00X+035295Y+170508X0357Y    R180 S3      
317GND              VIA   -    MD0080PA00X+033957Y+170256X0180Y         S0      
317GND              VIA   -    MD0080PA00X+033957Y+170767X0180Y         S0      
317GND              VIA   -    MD0080PA00X+033957Y+171220X0180Y         S0      
317GND              VIA   -    MD0080PA00X+033957Y+171674X0180Y         S0      
317GND              VIA   -    MD0080PA00X+034744Y+171280X0180Y         S0      
317GND              VIA   -    MD0080PA00X+034744Y+170827X0180Y         S0      
317GND              VIA   -    MD0080PA00X+034744Y+170373X0180Y         S0      
317GND              J111  -E7  MD0197PA00X+034508Y+171531X0357Y    R180 S3      
317GND              J111  -G6  MD0197PA00X+033720Y+170508X0357Y    R180 S3      
317GND              VIA   -    MD0080PA00X+032382Y+170256X0180Y         S0      
317GND              VIA   -    MD0080PA00X+032382Y+170767X0180Y         S0      
317GND              VIA   -    MD0080PA00X+032382Y+171220X0180Y         S0      
317GND              VIA   -    MD0080PA00X+032382Y+171674X0180Y         S0      
317GND              VIA   -    MD0080PA00X+033169Y+171280X0180Y         S0      
317GND              VIA   -    MD0080PA00X+033169Y+170827X0180Y         S0      
317GND              VIA   -    MD0080PA00X+033169Y+170373X0180Y         S0      
317GND              J111  -E5  MD0197PA00X+032933Y+171531X0357Y    R180 S3      
317GND              VIA   -    MD0080PA00X+030807Y+170256X0180Y         S0      
317GND              VIA   -    MD0080PA00X+030807Y+170767X0180Y         S0      
317GND              VIA   -    MD0080PA00X+030807Y+171220X0180Y         S0      
317GND              VIA   -    MD0080PA00X+030807Y+171674X0180Y         S0      
317GND              VIA   -    MD0080PA00X+031594Y+171280X0180Y         S0      
317GND              VIA   -    MD0080PA00X+031594Y+170827X0180Y         S0      
317GND              VIA   -    MD0080PA00X+031594Y+170373X0180Y         S0      
317GND              J111  -E3  MD0197PA00X+031358Y+171531X0357Y    R180 S3      
317GND              J111  -G4  MD0197PA00X+032146Y+170508X0357Y    R180 S3      
317GND              VIA   -    MD0080PA00X+030020Y+171280X0180Y         S0      
317GND              VIA   -    MD0080PA00X+030020Y+170827X0180Y         S0      
317GND              VIA   -    MD0080PA00X+030020Y+170373X0180Y         S0      
317GND              J111  -E1  MD0197PA00X+029784Y+171531X0357Y    R180 S3      
317GND              J111  -G2  MD0197PA00X+030571Y+170508X0357Y    R180 S3      
317GND              VIA   -    MD0080PA00X+028051Y+170373X0180Y         S0      
317GND              VIA   -    MD0080PA00X+028051Y+170827X0180Y         S0      
317GND              VIA   -    MD0080PA00X+028051Y+171280X0180Y         S0      
317GND              VIA   -    MD0080PA00X+028838Y+170767X0180Y         S0      
317GND              VIA   -    MD0080PA00X+028838Y+170256X0180Y         S0      
317GND              VIA   -    MD0080PA00X+028838Y+171674X0180Y         S0      
317GND              VIA   -    MD0080PA00X+028838Y+171220X0180Y         S0      
317GND              J112  -E7  MD0197PA00X+027815Y+171531X0357Y    R180 S3      
317GND              J112  -G8  MD0197PA00X+028602Y+170508X0357Y    R180 S3      
317GND              VIA   -    MD0080PA00X+026476Y+170373X0180Y         S0      
317GND              VIA   -    MD0080PA00X+026476Y+170827X0180Y         S0      
317GND              VIA   -    MD0080PA00X+026476Y+171280X0180Y         S0      
317GND              VIA   -    MD0080PA00X+027264Y+171674X0180Y         S0      
317GND              VIA   -    MD0080PA00X+027264Y+171220X0180Y         S0      
317GND              VIA   -    MD0080PA00X+027264Y+170767X0180Y         S0      
317GND              VIA   -    MD0080PA00X+027264Y+170256X0180Y         S0      
317GND              J112  -E5  MD0197PA00X+026240Y+171531X0357Y    R180 S3      
317GND              J112  -G6  MD0197PA00X+027028Y+170508X0357Y    R180 S3      
317GND              VIA   -    MD0080PA00X+024902Y+170373X0180Y         S0      
317GND              VIA   -    MD0080PA00X+024902Y+170827X0180Y         S0      
317GND              VIA   -    MD0080PA00X+024902Y+171280X0180Y         S0      
317GND              VIA   -    MD0080PA00X+025689Y+171674X0180Y         S0      
317GND              VIA   -    MD0080PA00X+025689Y+171220X0180Y         S0      
317GND              VIA   -    MD0080PA00X+025689Y+170767X0180Y         S0      
317GND              VIA   -    MD0080PA00X+025689Y+170256X0180Y         S0      
317GND              J112  -G4  MD0197PA00X+025453Y+170508X0357Y    R180 S3      
317GND              VIA   -    MD0080PA00X+023327Y+171280X0180Y         S0      
317GND              VIA   -    MD0080PA00X+023327Y+170827X0180Y         S0      
317GND              VIA   -    MD0080PA00X+023327Y+170373X0180Y         S0      
317GND              VIA   -    MD0080PA00X+024114Y+171674X0180Y         S0      
317GND              VIA   -    MD0080PA00X+024114Y+171220X0180Y         S0      
317GND              VIA   -    MD0080PA00X+024114Y+170767X0180Y         S0      
317GND              VIA   -    MD0080PA00X+024114Y+170256X0180Y         S0      
317GND              J112  -E3  MD0197PA00X+024665Y+171531X0357Y    R180 S3      
317GND              J112  -G2  MD0197PA00X+023878Y+170508X0357Y    R180 S3      
317GND              J112  -E1  MD0197PA00X+023090Y+171531X0357Y    R180 S3      
317GND              VIA   -    MD0080PA00X+161949Y+168956X0180Y         S0      
317GND              VIA   -    MD0080PA00X+161949Y+169409X0180Y         S0      
317GND              VIA   -    MD0080PA00X+161949Y+169863X0180Y         S0      
317GND              VIA   -    MD0080PA00X+162736Y+169803X0180Y         S0      
317GND              VIA   -    MD0080PA00X+162736Y+169349X0180Y         S0      
317GND              VIA   -    MD0080PA00X+162736Y+168839X0180Y         S0      
317GND              J105  -J8  MD0197PA00X+162500Y+169090X0357Y    R180 S3      
317GND              VIA   -    MD0080PA00X+160374Y+168956X0180Y         S0      
317GND              VIA   -    MD0080PA00X+160374Y+169409X0180Y         S0      
317GND              VIA   -    MD0080PA00X+160374Y+169863X0180Y         S0      
317GND              VIA   -    MD0080PA00X+161161Y+169803X0180Y         S0      
317GND              VIA   -    MD0080PA00X+161161Y+169349X0180Y         S0      
317GND              VIA   -    MD0080PA00X+161161Y+168839X0180Y         S0      
317GND              J105  -H7  MD0197PA00X+161713Y+170114X0357Y    R180 S3      
317GND              J105  -J6  MD0197PA00X+160925Y+169090X0357Y    R180 S3      
317GND              VIA   -    MD0080PA00X+159586Y+169803X0180Y         S0      
317GND              VIA   -    MD0080PA00X+159586Y+169349X0180Y         S0      
317GND              VIA   -    MD0080PA00X+159586Y+168839X0180Y         S0      
317GND              J105  -H5  MD0197PA00X+160138Y+170114X0357Y    R180 S3      
317GND              J105  -J4  MD0197PA00X+159350Y+169090X0357Y    R180 S3      
317GND              VIA   -    MD0080PA00X+158799Y+168956X0180Y         S0      
317GND              VIA   -    MD0080PA00X+158799Y+169409X0180Y         S0      
317GND              VIA   -    MD0080PA00X+158799Y+169863X0180Y         S0      
317GND              VIA   -    MD0080PA00X+158012Y+169803X0180Y         S0      
317GND              VIA   -    MD0080PA00X+158012Y+169349X0180Y         S0      
317GND              VIA   -    MD0080PA00X+158012Y+168839X0180Y         S0      
317GND              J105  -H3  MD0197PA00X+158563Y+170114X0357Y    R180 S3      
317GND              J105  -J2  MD0197PA00X+157776Y+169090X0357Y    R180 S3      
317GND              VIA   -    MD0080PA00X+156043Y+169803X0180Y         S0      
317GND              VIA   -    MD0080PA00X+156043Y+169349X0180Y         S0      
317GND              VIA   -    MD0080PA00X+156043Y+168839X0180Y         S0      
317GND              VIA   -    MD0080PA00X+157224Y+168956X0180Y         S0      
317GND              VIA   -    MD0080PA00X+157224Y+169409X0180Y         S0      
317GND              VIA   -    MD0080PA00X+157224Y+169863X0180Y         S0      
317GND              J105  -H1  MD0197PA00X+156988Y+170114X0357Y    R180 S3      
317GND              VIA   -    MD0080PA00X+155256Y+168956X0180Y         S0      
317GND              VIA   -    MD0080PA00X+155256Y+169409X0180Y         S0      
317GND              VIA   -    MD0080PA00X+155256Y+169863X0180Y         S0      
317GND              VIA   -    MD0080PA00X+154468Y+169803X0180Y         S0      
317GND              VIA   -    MD0080PA00X+154468Y+169349X0180Y         S0      
317GND              VIA   -    MD0080PA00X+154468Y+168839X0180Y         S0      
317GND              J106  -H7  MD0197PA00X+155020Y+170114X0357Y    R180 S3      
317GND              J106  -J8  MD0197PA00X+155807Y+169090X0357Y    R180 S3      
317GND              VIA   -    MD0080PA00X+153681Y+168956X0180Y         S0      
317GND              VIA   -    MD0080PA00X+153681Y+169409X0180Y         S0      
317GND              VIA   -    MD0080PA00X+153681Y+169863X0180Y         S0      
317GND              VIA   -    MD0080PA00X+152894Y+169803X0180Y         S0      
317GND              VIA   -    MD0080PA00X+152894Y+169349X0180Y         S0      
317GND              VIA   -    MD0080PA00X+152894Y+168839X0180Y         S0      
317GND              J106  -H5  MD0197PA00X+153445Y+170114X0357Y    R180 S3      
317GND              J106  -J6  MD0197PA00X+154232Y+169090X0357Y    R180 S3      
317GND              VIA   -    MD0080PA00X+152106Y+168956X0180Y         S0      
317GND              VIA   -    MD0080PA00X+152106Y+169409X0180Y         S0      
317GND              VIA   -    MD0080PA00X+152106Y+169863X0180Y         S0      
317GND              J106  -H3  MD0197PA00X+151870Y+170114X0357Y    R180 S3      
317GND              J106  -J4  MD0197PA00X+152657Y+169090X0357Y    R180 S3      
317GND              VIA   -    MD0080PA00X+150531Y+168956X0180Y         S0      
317GND              VIA   -    MD0080PA00X+150531Y+169409X0180Y         S0      
317GND              VIA   -    MD0080PA00X+150531Y+169863X0180Y         S0      
317GND              VIA   -    MD0080PA00X+151319Y+169803X0180Y         S0      
317GND              VIA   -    MD0080PA00X+151319Y+169349X0180Y         S0      
317GND              VIA   -    MD0080PA00X+151319Y+168839X0180Y         S0      
317GND              J106  -H1  MD0197PA00X+150295Y+170114X0357Y    R180 S3      
317GND              J106  -J2  MD0197PA00X+151083Y+169090X0357Y    R180 S3      
317GND              VIA   -    MD0100PA00X+138892Y+168788X0200Y    R270 S0      
327GND              Q146  -4          A01X+138892Y+169038X0170Y0200R180 S1      
317GND              VIA   -    MD0080PA00X+135531Y+169863X0180Y         S0      
317GND              VIA   -    MD0080PA00X+136319Y+169803X0180Y         S0      
317GND              VIA   -    MD0080PA00X+136319Y+169349X0180Y         S0      
317GND              VIA   -    MD0080PA00X+136319Y+168839X0180Y         S0      
317GND              VIA   -    MD0080PA00X+135531Y+168956X0180Y         S0      
317GND              VIA   -    MD0080PA00X+135531Y+169409X0180Y         S0      
317GND              J107  -H7  MD0197PA00X+135295Y+170114X0357Y    R180 S3      
317GND              J107  -J8  MD0197PA00X+136083Y+169090X0357Y    R180 S3      
317GND              VIA   -    MD0080PA00X+133956Y+168956X0180Y         S0      
317GND              VIA   -    MD0080PA00X+133956Y+169409X0180Y         S0      
317GND              VIA   -    MD0080PA00X+133956Y+169863X0180Y         S0      
317GND              VIA   -    MD0080PA00X+134744Y+169803X0180Y         S0      
317GND              VIA   -    MD0080PA00X+134744Y+169349X0180Y         S0      
317GND              VIA   -    MD0080PA00X+134744Y+168839X0180Y         S0      
317GND              J107  -H5  MD0197PA00X+133720Y+170114X0357Y    R180 S3      
317GND              J107  -J6  MD0197PA00X+134508Y+169090X0357Y    R180 S3      
317GND              VIA   -    MD0080PA00X+132382Y+168956X0180Y         S0      
317GND              VIA   -    MD0080PA00X+132382Y+169409X0180Y         S0      
317GND              VIA   -    MD0080PA00X+132382Y+169863X0180Y         S0      
317GND              VIA   -    MD0080PA00X+133169Y+169803X0180Y         S0      
317GND              VIA   -    MD0080PA00X+133169Y+169349X0180Y         S0      
317GND              VIA   -    MD0080PA00X+133169Y+168839X0180Y         S0      
317GND              J107  -H3  MD0197PA00X+132146Y+170114X0357Y    R180 S3      
317GND              J107  -J4  MD0197PA00X+132933Y+169090X0357Y    R180 S3      
317GND              VIA   -    MD0080PA00X+130807Y+168956X0180Y         S0      
317GND              VIA   -    MD0080PA00X+130807Y+169409X0180Y         S0      
317GND              VIA   -    MD0080PA00X+130807Y+169863X0180Y         S0      
317GND              VIA   -    MD0080PA00X+131594Y+169803X0180Y         S0      
317GND              VIA   -    MD0080PA00X+131594Y+169349X0180Y         S0      
317GND              VIA   -    MD0080PA00X+131594Y+168839X0180Y         S0      
317GND              J107  -J2  MD0197PA00X+131358Y+169090X0357Y    R180 S3      
317GND              VIA   -    MD0080PA00X+129626Y+169803X0180Y         S0      
317GND              VIA   -    MD0080PA00X+129626Y+169349X0180Y         S0      
317GND              VIA   -    MD0080PA00X+129626Y+168839X0180Y         S0      
317GND              J108  -J8  MD0197PA00X+129390Y+169090X0357Y    R180 S3      
317GND              J107  -H1  MD0197PA00X+130571Y+170114X0357Y    R180 S3      
317GND              VIA   -    MD0080PA00X+128838Y+168956X0180Y         S0      
317GND              VIA   -    MD0080PA00X+128838Y+169409X0180Y         S0      
317GND              VIA   -    MD0080PA00X+128838Y+169863X0180Y         S0      
317GND              VIA   -    MD0080PA00X+128051Y+169803X0180Y         S0      
317GND              VIA   -    MD0080PA00X+128051Y+169349X0180Y         S0      
317GND              VIA   -    MD0080PA00X+128051Y+168839X0180Y         S0      
317GND              J108  -H7  MD0197PA00X+128602Y+170114X0357Y    R180 S3      
317GND              J108  -J6  MD0197PA00X+127815Y+169090X0357Y    R180 S3      
317GND              VIA   -    MD0080PA00X+127264Y+168956X0180Y         S0      
317GND              VIA   -    MD0080PA00X+127264Y+169409X0180Y         S0      
317GND              VIA   -    MD0080PA00X+127264Y+169863X0180Y         S0      
317GND              VIA   -    MD0080PA00X+126476Y+169803X0180Y         S0      
317GND              VIA   -    MD0080PA00X+126476Y+169349X0180Y         S0      
317GND              VIA   -    MD0080PA00X+126476Y+168839X0180Y         S0      
317GND              J108  -H5  MD0197PA00X+127027Y+170114X0357Y    R180 S3      
317GND              J108  -J4  MD0197PA00X+126240Y+169090X0357Y    R180 S3      
317GND              VIA   -    MD0080PA00X+125689Y+168956X0180Y         S0      
317GND              VIA   -    MD0080PA00X+125689Y+169409X0180Y         S0      
317GND              VIA   -    MD0080PA00X+125689Y+169863X0180Y         S0      
317GND              VIA   -    MD0080PA00X+124901Y+169803X0180Y         S0      
317GND              VIA   -    MD0080PA00X+124901Y+169349X0180Y         S0      
317GND              VIA   -    MD0080PA00X+124901Y+168839X0180Y         S0      
317GND              J108  -H3  MD0197PA00X+125453Y+170114X0357Y    R180 S3      
317GND              J108  -J2  MD0197PA00X+124665Y+169090X0357Y    R180 S3      
317GND              VIA   -    MD0080PA00X+124114Y+168956X0180Y         S0      
317GND              VIA   -    MD0080PA00X+124114Y+169409X0180Y         S0      
317GND              VIA   -    MD0080PA00X+124114Y+169863X0180Y         S0      
317GND              J108  -H1  MD0197PA00X+123878Y+170114X0357Y    R180 S3      
317GND              VIA   -    MD0100PA00X+120988Y+170036X0200Y    R090 S0      
317GND              VIA   -    MD0100PA00X+121495Y+170034X0200Y    R180 S0      
327GND              R4136 -2          A01X+121495Y+169786X0198Y0197     S1      
317GND              VIA   -    MD0100PA00X+120480Y+169138X0200Y         S0      
327GND              C19   -2          A01X+120480Y+169386X0198Y0197R180 S1      
317GND              VIA   -    MD0100PA00X+111395Y+171424X0200Y         S0      
317GND              VIA   -    MD0100PA00X+109298Y+169603X0200Y    R180 S0      
327GND              C69   -2          A01X+109549Y+169603X0198Y0197R270 S1      
317GND              VIA   -    MD0100PA00X+108903Y+169123X0200Y    R180 S0      
327GND              R4265 -2          A01X+109154Y+169123X0198Y0197R180 S1      
317GND              JP10  -3   MD0410PA00X+075718Y+170277X0610Y         S3      
317GND              VIA   -    MD0080PA00X+061949Y+169803X0180Y         S0      
317GND              VIA   -    MD0080PA00X+061949Y+169349X0180Y         S0      
317GND              VIA   -    MD0080PA00X+061949Y+168839X0180Y         S0      
317GND              VIA   -    MD0080PA00X+061161Y+168956X0180Y         S0      
317GND              VIA   -    MD0080PA00X+061161Y+169409X0180Y         S0      
317GND              VIA   -    MD0080PA00X+061161Y+169863X0180Y         S0      
317GND              J109  -H7  MD0197PA00X+060925Y+170114X0357Y    R180 S3      
317GND              J109  -J8  MD0197PA00X+061713Y+169090X0357Y    R180 S3      
317GND              VIA   -    MD0080PA00X+059586Y+168956X0180Y         S0      
317GND              VIA   -    MD0080PA00X+059586Y+169409X0180Y         S0      
317GND              VIA   -    MD0080PA00X+059586Y+169863X0180Y         S0      
317GND              VIA   -    MD0080PA00X+060374Y+169803X0180Y         S0      
317GND              VIA   -    MD0080PA00X+060374Y+169349X0180Y         S0      
317GND              VIA   -    MD0080PA00X+060374Y+168839X0180Y         S0      
317GND              J109  -H5  MD0197PA00X+059350Y+170114X0357Y    R180 S3      
317GND              J109  -J6  MD0197PA00X+060138Y+169090X0357Y    R180 S3      
317GND              VIA   -    MD0080PA00X+058012Y+168956X0180Y         S0      
317GND              VIA   -    MD0080PA00X+058012Y+169409X0180Y         S0      
317GND              VIA   -    MD0080PA00X+058012Y+169863X0180Y         S0      
317GND              VIA   -    MD0080PA00X+058799Y+169803X0180Y         S0      
317GND              VIA   -    MD0080PA00X+058799Y+169349X0180Y         S0      
317GND              VIA   -    MD0080PA00X+058799Y+168839X0180Y         S0      
317GND              J109  -H3  MD0197PA00X+057776Y+170114X0357Y    R180 S3      
317GND              J109  -J4  MD0197PA00X+058563Y+169090X0357Y    R180 S3      
317GND              VIA   -    MD0080PA00X+056437Y+169863X0180Y         S0      
317GND              VIA   -    MD0080PA00X+057224Y+169803X0180Y         S0      
317GND              VIA   -    MD0080PA00X+057224Y+169349X0180Y         S0      
317GND              VIA   -    MD0080PA00X+057224Y+168839X0180Y         S0      
317GND              VIA   -    MD0080PA00X+056437Y+168956X0180Y         S0      
317GND              VIA   -    MD0080PA00X+056437Y+169409X0180Y         S0      
317GND              J109  -H1  MD0197PA00X+056201Y+170114X0357Y    R180 S3      
317GND              J109  -J2  MD0197PA00X+056988Y+169090X0357Y    R180 S3      
317GND              VIA   -    MD0080PA00X+055256Y+169803X0180Y         S0      
317GND              VIA   -    MD0080PA00X+055256Y+169349X0180Y         S0      
317GND              VIA   -    MD0080PA00X+055256Y+168839X0180Y         S0      
317GND              J110  -J8  MD0197PA00X+055020Y+169090X0357Y    R180 S3      
317GND              VIA   -    MD0080PA00X+054468Y+168956X0180Y         S0      
317GND              VIA   -    MD0080PA00X+054468Y+169409X0180Y         S0      
317GND              VIA   -    MD0080PA00X+054468Y+169863X0180Y         S0      
317GND              VIA   -    MD0080PA00X+053681Y+169803X0180Y         S0      
317GND              VIA   -    MD0080PA00X+053681Y+169349X0180Y         S0      
317GND              VIA   -    MD0080PA00X+053681Y+168839X0180Y         S0      
317GND              J110  -H7  MD0197PA00X+054232Y+170114X0357Y    R180 S3      
317GND              J110  -J6  MD0197PA00X+053445Y+169090X0357Y    R180 S3      
317GND              VIA   -    MD0080PA00X+052894Y+168956X0180Y         S0      
317GND              VIA   -    MD0080PA00X+052894Y+169409X0180Y         S0      
317GND              VIA   -    MD0080PA00X+052894Y+169863X0180Y         S0      
317GND              VIA   -    MD0080PA00X+052106Y+169803X0180Y         S0      
317GND              VIA   -    MD0080PA00X+052106Y+169349X0180Y         S0      
317GND              VIA   -    MD0080PA00X+052106Y+168839X0180Y         S0      
317GND              J110  -H5  MD0197PA00X+052657Y+170114X0357Y    R180 S3      
317GND              J110  -J4  MD0197PA00X+051870Y+169090X0357Y    R180 S3      
317GND              VIA   -    MD0080PA00X+051319Y+168956X0180Y         S0      
317GND              VIA   -    MD0080PA00X+051319Y+169409X0180Y         S0      
317GND              VIA   -    MD0080PA00X+051319Y+169863X0180Y         S0      
317GND              VIA   -    MD0080PA00X+050531Y+169803X0180Y         S0      
317GND              VIA   -    MD0080PA00X+050531Y+169349X0180Y         S0      
317GND              VIA   -    MD0080PA00X+050531Y+168839X0180Y         S0      
317GND              J110  -H3  MD0197PA00X+051083Y+170114X0357Y    R180 S3      
317GND              J110  -J2  MD0197PA00X+050295Y+169090X0357Y    R180 S3      
317GND              VIA   -    MD0080PA00X+049744Y+168956X0180Y         S0      
317GND              VIA   -    MD0080PA00X+049744Y+169409X0180Y         S0      
317GND              VIA   -    MD0080PA00X+049744Y+169863X0180Y         S0      
317GND              J110  -H1  MD0197PA00X+049508Y+170114X0357Y    R180 S3      
317GND              VIA   -    MD0080PA00X+035531Y+169349X0180Y         S0      
317GND              VIA   -    MD0080PA00X+035531Y+169803X0180Y         S0      
317GND              VIA   -    MD0080PA00X+035531Y+168839X0180Y         S0      
317GND              J111  -J8  MD0197PA00X+035295Y+169090X0357Y    R180 S3      
317GND              VIA   -    MD0080PA00X+034744Y+168956X0180Y         S0      
317GND              VIA   -    MD0080PA00X+033957Y+168839X0180Y         S0      
317GND              VIA   -    MD0080PA00X+033957Y+169349X0180Y         S0      
317GND              VIA   -    MD0080PA00X+033957Y+169803X0180Y         S0      
317GND              VIA   -    MD0080PA00X+034744Y+169863X0180Y         S0      
317GND              VIA   -    MD0080PA00X+034744Y+169409X0180Y         S0      
317GND              J111  -H7  MD0197PA00X+034508Y+170114X0357Y    R180 S3      
317GND              J111  -J6  MD0197PA00X+033720Y+169090X0357Y    R180 S3      
317GND              VIA   -    MD0080PA00X+032382Y+168839X0180Y         S0      
317GND              VIA   -    MD0080PA00X+032382Y+169349X0180Y         S0      
317GND              VIA   -    MD0080PA00X+032382Y+169803X0180Y         S0      
317GND              VIA   -    MD0080PA00X+033169Y+169863X0180Y         S0      
317GND              VIA   -    MD0080PA00X+033169Y+169409X0180Y         S0      
317GND              VIA   -    MD0080PA00X+033169Y+168956X0180Y         S0      
317GND              J111  -H5  MD0197PA00X+032933Y+170114X0357Y    R180 S3      
317GND              VIA   -    MD0080PA00X+030807Y+168839X0180Y         S0      
317GND              VIA   -    MD0080PA00X+030807Y+169349X0180Y         S0      
317GND              VIA   -    MD0080PA00X+030807Y+169803X0180Y         S0      
317GND              VIA   -    MD0080PA00X+031594Y+169863X0180Y         S0      
317GND              VIA   -    MD0080PA00X+031594Y+169409X0180Y         S0      
317GND              VIA   -    MD0080PA00X+031594Y+168956X0180Y         S0      
317GND              J111  -H3  MD0197PA00X+031358Y+170114X0357Y    R180 S3      
317GND              J111  -J4  MD0197PA00X+032146Y+169090X0357Y    R180 S3      
317GND              VIA   -    MD0080PA00X+030020Y+169863X0180Y         S0      
317GND              VIA   -    MD0080PA00X+030020Y+169409X0180Y         S0      
317GND              VIA   -    MD0080PA00X+030020Y+168956X0180Y         S0      
317GND              J111  -H1  MD0197PA00X+029784Y+170114X0357Y    R180 S3      
317GND              J111  -J2  MD0197PA00X+030571Y+169090X0357Y    R180 S3      
317GND              VIA   -    MD0080PA00X+028051Y+168956X0180Y         S0      
317GND              VIA   -    MD0080PA00X+028051Y+169409X0180Y         S0      
317GND              VIA   -    MD0080PA00X+028051Y+169863X0180Y         S0      
317GND              VIA   -    MD0080PA00X+028838Y+169803X0180Y         S0      
317GND              VIA   -    MD0080PA00X+028838Y+169349X0180Y         S0      
317GND              VIA   -    MD0080PA00X+028838Y+168839X0180Y         S0      
317GND              J112  -H7  MD0197PA00X+027815Y+170114X0357Y    R180 S3      
317GND              J112  -J8  MD0197PA00X+028602Y+169090X0357Y    R180 S3      
317GND              VIA   -    MD0080PA00X+026476Y+168956X0180Y         S0      
317GND              VIA   -    MD0080PA00X+026476Y+169409X0180Y         S0      
317GND              VIA   -    MD0080PA00X+026476Y+169863X0180Y         S0      
317GND              VIA   -    MD0080PA00X+027264Y+169803X0180Y         S0      
317GND              VIA   -    MD0080PA00X+027264Y+169349X0180Y         S0      
317GND              VIA   -    MD0080PA00X+027264Y+168839X0180Y         S0      
317GND              J112  -H5  MD0197PA00X+026240Y+170114X0357Y    R180 S3      
317GND              J112  -J6  MD0197PA00X+027028Y+169090X0357Y    R180 S3      
317GND              VIA   -    MD0080PA00X+024902Y+168956X0180Y         S0      
317GND              VIA   -    MD0080PA00X+024902Y+169409X0180Y         S0      
317GND              VIA   -    MD0080PA00X+024902Y+169863X0180Y         S0      
317GND              VIA   -    MD0080PA00X+025689Y+169803X0180Y         S0      
317GND              VIA   -    MD0080PA00X+025689Y+169349X0180Y         S0      
317GND              VIA   -    MD0080PA00X+025689Y+168839X0180Y         S0      
317GND              J112  -J4  MD0197PA00X+025453Y+169090X0357Y    R180 S3      
317GND              VIA   -    MD0080PA00X+023327Y+169863X0180Y         S0      
317GND              VIA   -    MD0080PA00X+023327Y+169409X0180Y         S0      
317GND              VIA   -    MD0080PA00X+023327Y+168956X0180Y         S0      
317GND              VIA   -    MD0080PA00X+024114Y+169803X0180Y         S0      
317GND              VIA   -    MD0080PA00X+024114Y+169349X0180Y         S0      
317GND              VIA   -    MD0080PA00X+024114Y+168839X0180Y         S0      
317GND              J112  -H3  MD0197PA00X+024665Y+170114X0357Y    R180 S3      
317GND              J112  -J2  MD0197PA00X+023878Y+169090X0357Y    R180 S3      
317GND              J112  -H1  MD0197PA00X+023090Y+170114X0357Y    R180 S3      
317GND              VIA   -    MD0080PA00X+161949Y+167538X0180Y         S0      
317GND              VIA   -    MD0080PA00X+161949Y+167992X0180Y         S0      
317GND              VIA   -    MD0080PA00X+161949Y+168445X0180Y         S0      
317GND              VIA   -    MD0080PA00X+162736Y+168386X0180Y         S0      
317GND              VIA   -    MD0080PA00X+162736Y+167932X0180Y         S0      
317GND              J105  -M8  MD0197PA00X+162500Y+167673X0357Y    R180 S3      
317GND              VIA   -    MD0080PA00X+160374Y+167538X0180Y         S0      
317GND              VIA   -    MD0080PA00X+160374Y+167992X0180Y         S0      
317GND              VIA   -    MD0080PA00X+160374Y+168445X0180Y         S0      
317GND              VIA   -    MD0080PA00X+161161Y+168386X0180Y         S0      
317GND              VIA   -    MD0080PA00X+161161Y+167932X0180Y         S0      
317GND              J105  -K7  MD0197PA00X+161713Y+168697X0357Y    R180 S3      
317GND              J105  -M6  MD0197PA00X+160925Y+167673X0357Y    R180 S3      
317GND              VIA   -    MD0080PA00X+159586Y+168386X0180Y         S0      
317GND              VIA   -    MD0080PA00X+159586Y+167932X0180Y         S0      
317GND              J105  -K5  MD0197PA00X+160138Y+168697X0357Y    R180 S3      
317GND              J105  -M4  MD0197PA00X+159350Y+167673X0357Y    R180 S3      
317GND              VIA   -    MD0080PA00X+158799Y+167538X0180Y         S0      
317GND              VIA   -    MD0080PA00X+158799Y+167992X0180Y         S0      
317GND              VIA   -    MD0080PA00X+158799Y+168445X0180Y         S0      
317GND              VIA   -    MD0080PA00X+158012Y+168386X0180Y         S0      
317GND              VIA   -    MD0080PA00X+158012Y+167932X0180Y         S0      
317GND              J105  -K3  MD0197PA00X+158563Y+168697X0357Y    R180 S3      
317GND              J105  -M2  MD0197PA00X+157776Y+167673X0357Y    R180 S3      
317GND              VIA   -    MD0080PA00X+156043Y+168386X0180Y         S0      
317GND              VIA   -    MD0080PA00X+156043Y+167932X0180Y         S0      
317GND              VIA   -    MD0080PA00X+157224Y+167538X0180Y         S0      
317GND              VIA   -    MD0080PA00X+157224Y+167992X0180Y         S0      
317GND              VIA   -    MD0080PA00X+157224Y+168445X0180Y         S0      
317GND              J105  -K1  MD0197PA00X+156988Y+168697X0357Y    R180 S3      
317GND              VIA   -    MD0080PA00X+155256Y+167538X0180Y         S0      
317GND              VIA   -    MD0080PA00X+155256Y+167992X0180Y         S0      
317GND              VIA   -    MD0080PA00X+155256Y+168445X0180Y         S0      
317GND              VIA   -    MD0080PA00X+154468Y+168386X0180Y         S0      
317GND              VIA   -    MD0080PA00X+154468Y+167932X0180Y         S0      
317GND              J106  -K7  MD0197PA00X+155020Y+168697X0357Y    R180 S3      
317GND              J106  -M8  MD0197PA00X+155807Y+167673X0357Y    R180 S3      
317GND              VIA   -    MD0080PA00X+153681Y+167538X0180Y         S0      
317GND              VIA   -    MD0080PA00X+153681Y+167992X0180Y         S0      
317GND              VIA   -    MD0080PA00X+153681Y+168445X0180Y         S0      
317GND              VIA   -    MD0080PA00X+152894Y+168386X0180Y         S0      
317GND              VIA   -    MD0080PA00X+152894Y+167932X0180Y         S0      
317GND              J106  -K5  MD0197PA00X+153445Y+168697X0357Y    R180 S3      
317GND              J106  -M6  MD0197PA00X+154232Y+167673X0357Y    R180 S3      
317GND              VIA   -    MD0080PA00X+152106Y+167538X0180Y         S0      
317GND              VIA   -    MD0080PA00X+152106Y+167992X0180Y         S0      
317GND              VIA   -    MD0080PA00X+152106Y+168445X0180Y         S0      
317GND              J106  -K3  MD0197PA00X+151870Y+168697X0357Y    R180 S3      
317GND              J106  -M4  MD0197PA00X+152657Y+167673X0357Y    R180 S3      
317GND              VIA   -    MD0080PA00X+150531Y+167538X0180Y         S0      
317GND              VIA   -    MD0080PA00X+150531Y+167992X0180Y         S0      
317GND              VIA   -    MD0080PA00X+150531Y+168445X0180Y         S0      
317GND              VIA   -    MD0080PA00X+151319Y+168386X0180Y         S0      
317GND              VIA   -    MD0080PA00X+151319Y+167932X0180Y         S0      
317GND              J106  -K1  MD0197PA00X+150295Y+168697X0357Y    R180 S3      
317GND              J106  -M2  MD0197PA00X+151083Y+167673X0357Y    R180 S3      
317GND              VIA   -    MD0100PA00X+138380Y+168540X0200Y    R090 S0      
327GND              Q146  -1          A01X+138380Y+168290X0170Y0200R180 S1      
317GND              VIA   -    MD0080PA00X+135531Y+167538X0180Y         S0      
317GND              VIA   -    MD0080PA00X+135531Y+167992X0180Y         S0      
317GND              VIA   -    MD0080PA00X+135531Y+168445X0180Y         S0      
317GND              VIA   -    MD0080PA00X+136319Y+168386X0180Y         S0      
317GND              VIA   -    MD0080PA00X+136319Y+167932X0180Y         S0      
317GND              J107  -K7  MD0197PA00X+135295Y+168697X0357Y    R180 S3      
317GND              J107  -M8  MD0197PA00X+136083Y+167673X0357Y    R180 S3      
317GND              VIA   -    MD0080PA00X+133956Y+167538X0180Y         S0      
317GND              VIA   -    MD0080PA00X+133956Y+167992X0180Y         S0      
317GND              VIA   -    MD0080PA00X+133956Y+168445X0180Y         S0      
317GND              VIA   -    MD0080PA00X+134744Y+168386X0180Y         S0      
317GND              VIA   -    MD0080PA00X+134744Y+167932X0180Y         S0      
317GND              J107  -K5  MD0197PA00X+133720Y+168697X0357Y    R180 S3      
317GND              J107  -M6  MD0197PA00X+134508Y+167673X0357Y    R180 S3      
317GND              VIA   -    MD0080PA00X+132382Y+167538X0180Y         S0      
317GND              VIA   -    MD0080PA00X+132382Y+167992X0180Y         S0      
317GND              VIA   -    MD0080PA00X+132382Y+168445X0180Y         S0      
317GND              VIA   -    MD0080PA00X+133169Y+168386X0180Y         S0      
317GND              VIA   -    MD0080PA00X+133169Y+167932X0180Y         S0      
317GND              J107  -K3  MD0197PA00X+132146Y+168697X0357Y    R180 S3      
317GND              J107  -M4  MD0197PA00X+132933Y+167673X0357Y    R180 S3      
317GND              VIA   -    MD0080PA00X+130807Y+167538X0180Y         S0      
317GND              VIA   -    MD0080PA00X+130807Y+167992X0180Y         S0      
317GND              VIA   -    MD0080PA00X+130807Y+168445X0180Y         S0      
317GND              VIA   -    MD0080PA00X+131594Y+168386X0180Y         S0      
317GND              VIA   -    MD0080PA00X+131594Y+167932X0180Y         S0      
317GND              J107  -M2  MD0197PA00X+131358Y+167673X0357Y    R180 S3      
317GND              VIA   -    MD0080PA00X+129626Y+168386X0180Y         S0      
317GND              VIA   -    MD0080PA00X+129626Y+167932X0180Y         S0      
317GND              J108  -M8  MD0197PA00X+129390Y+167673X0357Y    R180 S3      
317GND              J107  -K1  MD0197PA00X+130571Y+168697X0357Y    R180 S3      
317GND              VIA   -    MD0080PA00X+128838Y+167538X0180Y         S0      
317GND              VIA   -    MD0080PA00X+128838Y+167992X0180Y         S0      
317GND              VIA   -    MD0080PA00X+128838Y+168445X0180Y         S0      
317GND              VIA   -    MD0080PA00X+128051Y+168386X0180Y         S0      
317GND              VIA   -    MD0080PA00X+128051Y+167932X0180Y         S0      
317GND              J108  -K7  MD0197PA00X+128602Y+168697X0357Y    R180 S3      
317GND              J108  -M6  MD0197PA00X+127815Y+167673X0357Y    R180 S3      
317GND              VIA   -    MD0080PA00X+127264Y+167538X0180Y         S0      
317GND              VIA   -    MD0080PA00X+127264Y+167992X0180Y         S0      
317GND              VIA   -    MD0080PA00X+127264Y+168445X0180Y         S0      
317GND              VIA   -    MD0080PA00X+126476Y+168386X0180Y         S0      
317GND              VIA   -    MD0080PA00X+126476Y+167932X0180Y         S0      
317GND              J108  -K5  MD0197PA00X+127027Y+168697X0357Y    R180 S3      
317GND              J108  -M4  MD0197PA00X+126240Y+167673X0357Y    R180 S3      
317GND              VIA   -    MD0080PA00X+125689Y+167538X0180Y         S0      
317GND              VIA   -    MD0080PA00X+125689Y+167992X0180Y         S0      
317GND              VIA   -    MD0080PA00X+125689Y+168445X0180Y         S0      
317GND              VIA   -    MD0080PA00X+124901Y+168386X0180Y         S0      
317GND              VIA   -    MD0080PA00X+124901Y+167932X0180Y         S0      
317GND              J108  -K3  MD0197PA00X+125453Y+168697X0357Y    R180 S3      
317GND              J108  -M2  MD0197PA00X+124665Y+167673X0357Y    R180 S3      
317GND              VIA   -    MD0080PA00X+124114Y+167538X0180Y         S0      
317GND              VIA   -    MD0080PA00X+124114Y+167992X0180Y         S0      
317GND              VIA   -    MD0080PA00X+124114Y+168445X0180Y         S0      
317GND              J108  -K1  MD0197PA00X+123878Y+168697X0357Y    R180 S3      
317GND              VIA   -    MD0100PA00X+121307Y+168290X0200Y    R270 S0      
327GND              Q133  -1          A01X+121307Y+168540X0170Y0200     S1      
317GND              VIA   -    MD0100PA00X+120795Y+168042X0200Y    R090 S0      
317GND              VIA   -    M      A01X+075756Y+168444X0200Y    R270 S2      
017GND              VIA   -    M      A18X+075756Y+168444X0260Y    R270 S2      
017GND                    -    MD0100PA00X+075756Y+168444                       
327GND              U190  -S          A01X+075756Y+168777X0320Y0360R180 S1      
317GND              VIA   -    MD0080PA00X+061949Y+168386X0180Y         S0      
317GND              VIA   -    MD0080PA00X+061949Y+167932X0180Y         S0      
317GND              VIA   -    MD0080PA00X+061161Y+167538X0180Y         S0      
317GND              VIA   -    MD0080PA00X+061161Y+167992X0180Y         S0      
317GND              VIA   -    MD0080PA00X+061161Y+168445X0180Y         S0      
317GND              J109  -K7  MD0197PA00X+060925Y+168697X0357Y    R180 S3      
317GND              J109  -M8  MD0197PA00X+061713Y+167673X0357Y    R180 S3      
317GND              VIA   -    MD0080PA00X+059586Y+167538X0180Y         S0      
317GND              VIA   -    MD0080PA00X+059586Y+167992X0180Y         S0      
317GND              VIA   -    MD0080PA00X+059586Y+168445X0180Y         S0      
317GND              VIA   -    MD0080PA00X+060374Y+168386X0180Y         S0      
317GND              VIA   -    MD0080PA00X+060374Y+167932X0180Y         S0      
317GND              J109  -K5  MD0197PA00X+059350Y+168697X0357Y    R180 S3      
317GND              J109  -M6  MD0197PA00X+060138Y+167673X0357Y    R180 S3      
317GND              VIA   -    MD0080PA00X+058012Y+167538X0180Y         S0      
317GND              VIA   -    MD0080PA00X+058012Y+167992X0180Y         S0      
317GND              VIA   -    MD0080PA00X+058012Y+168445X0180Y         S0      
317GND              VIA   -    MD0080PA00X+058799Y+168386X0180Y         S0      
317GND              VIA   -    MD0080PA00X+058799Y+167932X0180Y         S0      
317GND              J109  -K3  MD0197PA00X+057776Y+168697X0357Y    R180 S3      
317GND              J109  -M4  MD0197PA00X+058563Y+167673X0357Y    R180 S3      
317GND              VIA   -    MD0080PA00X+057224Y+167932X0180Y         S0      
317GND              VIA   -    MD0080PA00X+056437Y+167538X0180Y         S0      
317GND              VIA   -    MD0080PA00X+056437Y+167992X0180Y         S0      
317GND              VIA   -    MD0080PA00X+056437Y+168445X0180Y         S0      
317GND              VIA   -    MD0080PA00X+057224Y+168386X0180Y         S0      
317GND              J109  -K1  MD0197PA00X+056201Y+168697X0357Y    R180 S3      
317GND              J109  -M2  MD0197PA00X+056988Y+167673X0357Y    R180 S3      
317GND              VIA   -    MD0080PA00X+055256Y+168386X0180Y         S0      
317GND              VIA   -    MD0080PA00X+055256Y+167932X0180Y         S0      
317GND              J110  -M8  MD0197PA00X+055020Y+167673X0357Y    R180 S3      
317GND              VIA   -    MD0080PA00X+054468Y+167538X0180Y         S0      
317GND              VIA   -    MD0080PA00X+054468Y+167992X0180Y         S0      
317GND              VIA   -    MD0080PA00X+054468Y+168445X0180Y         S0      
317GND              VIA   -    MD0080PA00X+053681Y+168386X0180Y         S0      
317GND              VIA   -    MD0080PA00X+053681Y+167932X0180Y         S0      
317GND              J110  -K7  MD0197PA00X+054232Y+168697X0357Y    R180 S3      
317GND              J110  -M6  MD0197PA00X+053445Y+167673X0357Y    R180 S3      
317GND              VIA   -    MD0080PA00X+052894Y+167538X0180Y         S0      
317GND              VIA   -    MD0080PA00X+052894Y+167992X0180Y         S0      
317GND              VIA   -    MD0080PA00X+052894Y+168445X0180Y         S0      
317GND              VIA   -    MD0080PA00X+052106Y+168386X0180Y         S0      
317GND              VIA   -    MD0080PA00X+052106Y+167932X0180Y         S0      
317GND              J110  -K5  MD0197PA00X+052657Y+168697X0357Y    R180 S3      
317GND              J110  -M4  MD0197PA00X+051870Y+167673X0357Y    R180 S3      
317GND              VIA   -    MD0080PA00X+051319Y+167538X0180Y         S0      
317GND              VIA   -    MD0080PA00X+051319Y+167992X0180Y         S0      
317GND              VIA   -    MD0080PA00X+051319Y+168445X0180Y         S0      
317GND              VIA   -    MD0080PA00X+050531Y+168386X0180Y         S0      
317GND              VIA   -    MD0080PA00X+050531Y+167932X0180Y         S0      
317GND              J110  -K3  MD0197PA00X+051083Y+168697X0357Y    R180 S3      
317GND              J110  -M2  MD0197PA00X+050295Y+167673X0357Y    R180 S3      
317GND              VIA   -    MD0080PA00X+049744Y+167538X0180Y         S0      
317GND              VIA   -    MD0080PA00X+049744Y+167992X0180Y         S0      
317GND              VIA   -    MD0080PA00X+049744Y+168445X0180Y         S0      
317GND              J110  -K1  MD0197PA00X+049508Y+168697X0357Y    R180 S3      
317GND              VIA   -    M      A01X+047031Y+168900X0200Y         S2      
017GND              VIA   -    M      A18X+047031Y+168900X0260Y         S2      
017GND                    -    MD0100PA00X+047031Y+168900                       
327GND              U253  -2          A01X+047031Y+169222X0160Y0200R180 S1      
317GND              VIA   -    MD0100PA00X+037235Y+168328X0200Y         S0      
317GND              VIA   -    MD0080PA00X+035531Y+167932X0180Y         S0      
317GND              VIA   -    MD0080PA00X+035531Y+168386X0180Y         S0      
317GND              J111  -M8  MD0197PA00X+035295Y+167673X0357Y    R180 S3      
317GND              VIA   -    MD0080PA00X+033957Y+167932X0180Y         S0      
317GND              VIA   -    MD0080PA00X+033957Y+168386X0180Y         S0      
317GND              VIA   -    MD0080PA00X+034744Y+168445X0180Y         S0      
317GND              VIA   -    MD0080PA00X+034744Y+167992X0180Y         S0      
317GND              VIA   -    MD0080PA00X+034744Y+167538X0180Y         S0      
317GND              J111  -K7  MD0197PA00X+034508Y+168697X0357Y    R180 S3      
317GND              J111  -M6  MD0197PA00X+033720Y+167673X0357Y    R180 S3      
317GND              VIA   -    MD0080PA00X+032382Y+167932X0180Y         S0      
317GND              VIA   -    MD0080PA00X+032382Y+168386X0180Y         S0      
317GND              VIA   -    MD0080PA00X+033169Y+168445X0180Y         S0      
317GND              VIA   -    MD0080PA00X+033169Y+167992X0180Y         S0      
317GND              VIA   -    MD0080PA00X+033169Y+167538X0180Y         S0      
317GND              J111  -K5  MD0197PA00X+032933Y+168697X0357Y    R180 S3      
317GND              VIA   -    MD0080PA00X+030807Y+167932X0180Y         S0      
317GND              VIA   -    MD0080PA00X+030807Y+168386X0180Y         S0      
317GND              VIA   -    MD0080PA00X+031594Y+168445X0180Y         S0      
317GND              VIA   -    MD0080PA00X+031594Y+167992X0180Y         S0      
317GND              VIA   -    MD0080PA00X+031594Y+167538X0180Y         S0      
317GND              J111  -K3  MD0197PA00X+031358Y+168697X0357Y    R180 S3      
317GND              J111  -M4  MD0197PA00X+032146Y+167673X0357Y    R180 S3      
317GND              VIA   -    MD0080PA00X+030020Y+168445X0180Y         S0      
317GND              VIA   -    MD0080PA00X+030020Y+167992X0180Y         S0      
317GND              VIA   -    MD0080PA00X+030020Y+167538X0180Y         S0      
317GND              J111  -K1  MD0197PA00X+029784Y+168697X0357Y    R180 S3      
317GND              J111  -M2  MD0197PA00X+030571Y+167673X0357Y    R180 S3      
317GND              VIA   -    MD0080PA00X+028051Y+167538X0180Y         S0      
317GND              VIA   -    MD0080PA00X+028051Y+167992X0180Y         S0      
317GND              VIA   -    MD0080PA00X+028051Y+168445X0180Y         S0      
317GND              VIA   -    MD0080PA00X+028838Y+167932X0180Y         S0      
317GND              VIA   -    MD0080PA00X+028838Y+168386X0180Y         S0      
317GND              J112  -K7  MD0197PA00X+027815Y+168697X0357Y    R180 S3      
317GND              J112  -M8  MD0197PA00X+028602Y+167673X0357Y    R180 S3      
317GND              VIA   -    MD0080PA00X+026476Y+167538X0180Y         S0      
317GND              VIA   -    MD0080PA00X+026476Y+167992X0180Y         S0      
317GND              VIA   -    MD0080PA00X+026476Y+168445X0180Y         S0      
317GND              VIA   -    MD0080PA00X+027264Y+168386X0180Y         S0      
317GND              VIA   -    MD0080PA00X+027264Y+167932X0180Y         S0      
317GND              J112  -K5  MD0197PA00X+026240Y+168697X0357Y    R180 S3      
317GND              J112  -M6  MD0197PA00X+027028Y+167673X0357Y    R180 S3      
317GND              VIA   -    MD0080PA00X+024902Y+167538X0180Y         S0      
317GND              VIA   -    MD0080PA00X+024902Y+167992X0180Y         S0      
317GND              VIA   -    MD0080PA00X+024902Y+168445X0180Y         S0      
317GND              VIA   -    MD0080PA00X+025689Y+168386X0180Y         S0      
317GND              VIA   -    MD0080PA00X+025689Y+167932X0180Y         S0      
317GND              J112  -M4  MD0197PA00X+025453Y+167673X0357Y    R180 S3      
317GND              VIA   -    MD0080PA00X+023327Y+168445X0180Y         S0      
317GND              VIA   -    MD0080PA00X+023327Y+167992X0180Y         S0      
317GND              VIA   -    MD0080PA00X+023327Y+167538X0180Y         S0      
317GND              VIA   -    MD0080PA00X+024114Y+168386X0180Y         S0      
317GND              VIA   -    MD0080PA00X+024114Y+167932X0180Y         S0      
317GND              J112  -K3  MD0197PA00X+024665Y+168697X0357Y    R180 S3      
317GND              J112  -M2  MD0197PA00X+023878Y+167673X0357Y    R180 S3      
317GND              J112  -K1  MD0197PA00X+023090Y+168697X0357Y    R180 S3      
317GND              J105  -N7  MD0197PA00X+161713Y+167280X0357Y    R180 S3      
317GND              J105  -N5  MD0197PA00X+160138Y+167280X0357Y    R180 S3      
317GND              J105  -N3  MD0197PA00X+158563Y+167280X0357Y    R180 S3      
317GND              J105  -N1  MD0197PA00X+156988Y+167280X0357Y    R180 S3      
317GND              J106  -N7  MD0197PA00X+155020Y+167280X0357Y    R180 S3      
317GND              J106  -N5  MD0197PA00X+153445Y+167280X0357Y    R180 S3      
317GND              J106  -N3  MD0197PA00X+151870Y+167280X0357Y    R180 S3      
317GND              J106  -N1  MD0197PA00X+150295Y+167280X0357Y    R180 S3      
317GND              VIA   -    MD0100PA00X+138192Y+166791X0200Y         S0      
327GND              R4559 -2          A01X+138192Y+167039X0198Y0197R180 S1      
317GND              VIA   -    MD0100PA00X+139207Y+166791X0200Y         S0      
327GND              C18   -2          A01X+139207Y+167039X0198Y0197     S1      
317GND              J107  -N7  MD0197PA00X+135295Y+167280X0357Y    R180 S3      
317GND              J107  -N5  MD0197PA00X+133720Y+167280X0357Y    R180 S3      
317GND              J107  -N3  MD0197PA00X+132146Y+167280X0357Y    R180 S3      
317GND              J107  -N1  MD0197PA00X+130571Y+167280X0357Y    R180 S3      
317GND              J108  -N7  MD0197PA00X+128602Y+167280X0357Y    R180 S3      
317GND              J108  -N5  MD0197PA00X+127027Y+167280X0357Y    R180 S3      
317GND              J108  -N3  MD0197PA00X+125453Y+167280X0357Y    R180 S3      
317GND              J108  -N1  MD0197PA00X+123878Y+167280X0357Y    R180 S3      
317GND              VIA   -    MD0100PA00X+094780Y+166076X0200Y         S0      
327GND              C66   -2          A18X+094780Y+166319X0198Y0197R090 S2      
317GND              VIA   -    MD0100PA00X+093980Y+166076X0200Y         S0      
327GND              C74   -2          A18X+093980Y+166319X0198Y0197R090 S2      
317GND              VIA   -    MD0100PA00X+092129Y+166319X0200Y    R090 S0      
327GND              C64   -2          A18X+091878Y+166319X0198Y0197R090 S2      
317GND              VIA   -    MD0100PA00X+092380Y+166076X0200Y         S0      
327GND              C65   -2          A18X+092380Y+166319X0198Y0197R090 S2      
317GND              VIA   -    MD0100PA00X+093180Y+166076X0200Y         S0      
327GND              C67   -2          A18X+093180Y+166319X0198Y0197R090 S2      
317GND              VIA   -    MD0100PA00X+075541Y+167238X0200Y    R270 S0      
317GND              VIA   -    M      A01X+076203Y+166858X0200Y    R270 S2      
017GND              VIA   -    M      A18X+076203Y+166858X0260Y    R270 S2      
017GND                    -    MD0100PA00X+076203Y+166858                       
327GND              R2948 -2          A01X+076203Y+166616X0198Y0197R090 S1      
317GND              VIA   -    MD0100PA00X+075103Y+166858X0200Y    R090 S0      
317GND              VIA   -    M      A01X+075152Y+165916X0200Y    R180 S2      
017GND              VIA   -    M      A18X+075152Y+165916X0260Y    R180 S2      
017GND                    -    MD0100PA00X+075152Y+165916                       
327GND              C1775 -2          A01X+075403Y+165916X0198Y0197R090 S1      
317GND              J109  -N7  MD0197PA00X+060925Y+167280X0357Y    R180 S3      
317GND              J109  -N5  MD0197PA00X+059350Y+167280X0357Y    R180 S3      
317GND              J109  -N3  MD0197PA00X+057776Y+167280X0357Y    R180 S3      
317GND              J109  -N1  MD0197PA00X+056201Y+167280X0357Y    R180 S3      
317GND              J110  -N7  MD0197PA00X+054232Y+167280X0357Y    R180 S3      
317GND              J110  -N5  MD0197PA00X+052657Y+167280X0357Y    R180 S3      
317GND              J110  -N3  MD0197PA00X+051083Y+167280X0357Y    R180 S3      
317GND              J110  -N1  MD0197PA00X+049508Y+167280X0357Y    R180 S3      
317GND              VIA   -    MD0100PA00X+039982Y+166712X0200Y         S0      
327GND              R4187 -2          A01X+039982Y+166470X0198Y0197R090 S1      
317GND              VIA   -    MD0100PA00X+038982Y+166712X0200Y         S0      
327GND              R4203 -2          A01X+038982Y+166470X0198Y0197R090 S1      
317GND              VIA   -    MD0100PA00X+039482Y+166712X0200Y         S0      
327GND              R4195 -2          A01X+039482Y+166470X0198Y0197R090 S1      
317GND              VIA   -    MD0100PA00X+038550Y+166715X0200Y         S0      
327GND              C32   -2          A01X+038482Y+166470X0198Y0197R090 S1      
317GND              J111  -N7  MD0197PA00X+034508Y+167280X0357Y    R180 S3      
317GND              J111  -N5  MD0197PA00X+032933Y+167280X0357Y    R180 S3      
317GND              J111  -N3  MD0197PA00X+031358Y+167280X0357Y    R180 S3      
317GND              J111  -N1  MD0197PA00X+029784Y+167280X0357Y    R180 S3      
317GND              J112  -N7  MD0197PA00X+027815Y+167280X0357Y    R180 S3      
317GND              J112  -P8  MD0197PA00X+028602Y+166256X0357Y    R180 S3      
317GND              J112  -Q7  MD0197PA00X+027815Y+165862X0357Y    R180 S3      
317GND              J112  -N5  MD0197PA00X+026240Y+167280X0357Y    R180 S3      
317GND              J112  -P6  MD0197PA00X+027028Y+166256X0357Y    R180 S3      
317GND              J112  -Q5  MD0197PA00X+026240Y+165862X0357Y    R180 S3      
317GND              J112  -P4  MD0197PA00X+025453Y+166256X0357Y    R180 S3      
317GND              J112  -N3  MD0197PA00X+024665Y+167280X0357Y    R180 S3      
317GND              J112  -P2  MD0197PA00X+023878Y+166256X0357Y    R180 S3      
317GND              J112  -Q3  MD0197PA00X+024665Y+165862X0357Y    R180 S3      
317GND              J112  -N1  MD0197PA00X+023090Y+167280X0357Y    R180 S3      
317GND              J112  -Q1  MD0197PA00X+023090Y+165862X0357Y    R180 S3      
327GND              PD13  -A          A01X+099631Y+165910X0950Y1300R090 S1      
327GND              PD15  -A          A01X+096869Y+165913X0950Y1300R090 S1      
317GND              VIA   -    MD0100PA00X+097971Y+165938X0200Y         S0      
317GND              VIA   -    MD0100PA00X+097695Y+165938X0200Y         S0      
317GND              VIA   -    MD0100PA00X+097966Y+166202X0200Y         S0      
317GND              VIA   -    MD0100PA00X+097690Y+166202X0200Y         S0      
317GND              VIA   -    MD0100PA00X+097962Y+165618X0200Y         S0      
317GND              VIA   -    MD0100PA00X+097686Y+165618X0200Y         S0      
317GND              VIA   -    MD0100PA00X+095776Y+165618X0200Y         S0      
317GND              VIA   -    MD0100PA00X+096052Y+165618X0200Y         S0      
317GND              VIA   -    MD0100PA00X+095780Y+166202X0200Y         S0      
317GND              VIA   -    MD0100PA00X+096056Y+166202X0200Y         S0      
317GND              VIA   -    MD0100PA00X+096061Y+165938X0200Y         S0      
317GND              VIA   -    MD0100PA00X+098808Y+165610X0200Y         S0      
317GND              VIA   -    MD0100PA00X+098532Y+165610X0200Y         S0      
317GND              VIA   -    MD0100PA00X+098817Y+165930X0200Y         S0      
317GND              VIA   -    MD0100PA00X+098541Y+165930X0200Y         S0      
317GND              VIA   -    MD0100PA00X+098812Y+166194X0200Y         S0      
317GND              VIA   -    MD0100PA00X+098536Y+166194X0200Y         S0      
317GND              VIA   -    MD0100PA00X+100718Y+165610X0200Y         S0      
317GND              VIA   -    MD0100PA00X+100442Y+165610X0200Y         S0      
317GND              VIA   -    MD0100PA00X+100446Y+166194X0200Y         S0      
317GND              VIA   -    MD0100PA00X+100451Y+165930X0200Y         S0      
317GND              VIA   -    MD0100PA00X+100722Y+166194X0200Y         S0      
317GND              VIA   -    MD0100PA00X+100727Y+165930X0200Y         S0      
317GND              VIA   -    MD0100PA00X+095785Y+165938X0200Y         S0      
317GND              J112  -S8  MD0197PA00X+028602Y+164838X0357Y    R180 S3      
317GND              J112  -T7  MD0197PA00X+027815Y+164445X0357Y    R180 S3      
317GND              J112  -S6  MD0197PA00X+027028Y+164838X0357Y    R180 S3      
317GND              J112  -T5  MD0197PA00X+026240Y+164445X0357Y    R180 S3      
317GND              J112  -S4  MD0197PA00X+025453Y+164838X0357Y    R180 S3      
317GND              J112  -S2  MD0197PA00X+023878Y+164838X0357Y    R180 S3      
317GND              J112  -T3  MD0197PA00X+024665Y+164445X0357Y    R180 S3      
317GND              J112  -T1  MD0197PA00X+023090Y+164445X0357Y    R180 S3      
317GND              VIA   -    M      A01X+076151Y+163843X0200Y    R270 S2      
017GND              VIA   -    M      A18X+076151Y+163843X0260Y    R270 S2      
017GND                    -    MD0100PA00X+076151Y+163843                       
327GND              U278  -3          A01X+076151Y+164156X0220Y0320     S1      
317GND              VIA   -    M      A01X+074926Y+162821X0200Y    R270 S2      
017GND              VIA   -    M      A18X+074926Y+162821X0260Y    R270 S2      
017GND                    -    MD0100PA00X+074926Y+162821                       
327GND              R2941 -2          A01X+075177Y+162821X0198Y0197R270 S1      
317GND              VIA   -    MD0100PA00X+046604Y+166491X0200Y    R090 S0      
317GND              VIA   -    MD0100PA00X+042850Y+165000X0200Y    R090 S0      
317GND              VIA   -    MD0100PA00X+038732Y+162721X0200Y         S0      
317GND              VIA   -    MD0100PA00X+072288Y+161134X0200Y         S0      
327GND              PC2188-2          A01X+072529Y+161074X0198Y0197R180 S1      
317GND              VIA   -    M      A01X+069961Y+158052X0200Y         S2      
017GND              VIA   -    M      A18X+069961Y+158052X0260Y         S2      
017GND                    -    MD0100PA00X+069961Y+158052                       
327GND              PR3002-1          A01X+070204Y+158052X0198Y0197     S1      
317GND              VIA   -    MD0100PA00X+094520Y+145945X0200Y    R090 S0      
317GND              VIA   -    MD0100PA00X+095838Y+146245X0200Y    R090 S0      
317GND              VIA   -    MD0100PA00X+093951Y+146250X0200Y    R090 S0      
317GND              VIA   -    MD0100PA00X+095363Y+145676X0200Y    R090 S0      
317GND              VIA   -    MD0100PA00X+095669Y+145980X0200Y    R090 S0      
317GND              VIA   -    MD0100PA00X+093669Y+146233X0200Y    R090 S0      
317GND              VIA   -    MD0100PA00X+081177Y+138815X0200Y    R270 S0      
317GND              VIA   -    MD0100PA00X+081127Y+138275X0200Y    R270 S0      
327GND              R5028 -1          A18X+160283Y+130290X0198Y0197     S2      
327GND              R5026 -1          A18X+160597Y+130755X0198Y0197R180 S2      
317GND              VIA   -    MD0100PA00X+160351Y+130626X0200Y         S0      
317GND              VIA   -    MD0100PA00X+160545Y+128875X0200Y    R180 S0      
327GND              R440  -1          A18X+160275Y+128699X0198Y0197     S2      
327GND              R5056 -2          A18X+160865Y+128924X0198Y0197R090 S2      
317GND              VIA   -    MD0100PA00X+159454Y+129529X0200Y    R180 S0      
327GND              R748  -1          A18X+159205Y+129529X0198Y0197     S2      
317GND              VIA   -    MD0100PA00X+158301Y+128896X0200Y         S0      
317GND              J67   -G3  MD0480PA00X+178007Y+127770X0680Y1370R090 S3      
317GND              J20   -G3  MD0480PA00X+175037Y+127770X0680Y1370R090 S3      
317GND              J68   -G3  MD0480PA00X+172067Y+127770X0680Y1370R090 S3      
317GND              J18   -G3  MD0480PA00X+169097Y+127770X0680Y1370R090 S3      
317GND              J69   -G3  MD0480PA00X+166127Y+127770X0680Y1370R090 S3      
317GND              J16   -G3  MD0480PA00X+163157Y+127770X0680Y1370R090 S3      
327GND              R5027 -1          A18X+158552Y+126839X0198Y0197     S2      
317GND              VIA   -    MD0100PA00X+158684Y+127192X0200Y         S0      
327GND              R287  -1          A01X+157918Y+126536X0198Y0197R270 S1      
317GND              VIA   -    MD0100PA00X+156866Y+128346X0200Y    R180 S0      
327GND              R753  -1          A18X+156710Y+128611X0198Y0197R180 S2      
317GND              VIA   -    MD0100PA00X+165320Y+125545X0190Y         S0      
327GND              J69   -288        A01X+165320Y+125545X0205Y0590R090 S1      
317GND              VIA   -    MD0100PA00X+162350Y+125545X0190Y         S0      
327GND              J16   -288        A01X+162350Y+125545X0205Y0590R090 S1      
317GND              VIA   -    MD0100PA00X+155381Y+126449X0200Y         S0      
327GND              R750  -1          A18X+155133Y+126449X0198Y0197     S2      
317GND              VIA   -    MD0100PA00X+154706Y+125847X0200Y         S0      
327GND              R582  -1          A01X+154710Y+126627X0198Y0197     S1      
327GND              C5023 -2   M      A01X+154706Y+126231X0198Y0197R180 S1      
317GND              VIA   -    MD0100PA00X+119397Y+125545X0190Y         S0      
317GND              VIA   -    MD0100PA00X+116427Y+125545X0190Y         S0      
317GND              VIA   -    MD0100PA00X+067706Y+125545X0190Y         S0      
327GND              J27   -288        A01X+067706Y+125545X0205Y0590R090 S1      
317GND              VIA   -    MD0100PA00X+064735Y+125545X0190Y         S0      
327GND              J102  -288        A01X+064735Y+125545X0205Y0590R090 S1      
317GND              VIA   -    MD0100PA00X+060577Y+126710X0200Y    R180 S0      
327GND              C5024 -2   M      A01X+060335Y+126660X0198Y0197     S1      
327GND              R760  -1          A01X+060335Y+127460X0198Y0197R180 S1      
327GND              R584  -1   M      A01X+060335Y+127060X0198Y0197R180 S1      
327GND              R754  -1          A18X+060577Y+126970X0198Y0197R270 S2      
317GND              VIA   -    MD0100PA00X+057127Y+125949X0200Y    R180 S0      
327GND              R1502 -1          A18X+057327Y+126191X0198Y0197R180 S2      
317GND              VIA   -    MD0100PA00X+021783Y+125545X0190Y         S0      
327GND              J24   -288        A01X+021783Y+125545X0205Y0590R090 S1      
317GND              VIA   -    MD0100PA00X+018813Y+125545X0190Y         S0      
327GND              J26   -288        A01X+018813Y+125545X0205Y0590R090 S1      
317GND              VIA   -    MD0100PA00X+166934Y+125211X0190Y         S0      
327GND              J69   -143        A01X+166934Y+125211X0205Y0590R090 S1      
317GND              VIA   -    MD0100PA00X+166934Y+124541X0190Y         S0      
327GND              J69   -141        A01X+166934Y+124541X0205Y0590R090 S1      
317GND              VIA   -    MD0100PA00X+165865Y+124207X0190Y    R180 S0      
327GND              J69   -284        A01X+165320Y+124207X0205Y0590R090 S1      
317GND              VIA   -    MD0100PA00X+165320Y+124876X0190Y         S0      
327GND              J69   -286        A01X+165320Y+124876X0205Y0590R090 S1      
317GND              VIA   -    MD0100PA00X+163964Y+125211X0190Y         S0      
327GND              J16   -143        A01X+163964Y+125211X0205Y0590R090 S1      
317GND              VIA   -    MD0100PA00X+163964Y+124541X0190Y         S0      
327GND              J16   -141        A01X+163964Y+124541X0205Y0590R090 S1      
317GND              VIA   -    MD0100PA00X+162350Y+124876X0190Y         S0      
327GND              J16   -286        A01X+162350Y+124876X0205Y0590R090 S1      
317GND              VIA   -    MD0100PA00X+162895Y+124207X0190Y    R180 S0      
327GND              J16   -284        A01X+162350Y+124207X0205Y0590R090 S1      
317GND              VIA   -    MD0100PA00X+154085Y+124086X0200Y         S0      
317GND              VIA   -    MD0100PA00X+121011Y+125211X0190Y         S0      
317GND              VIA   -    MD0100PA00X+121011Y+124541X0190Y         S0      
327GND              J1    -141        A01X+121011Y+124541X0205Y0590R090 S1      
317GND              VIA   -    MD0100PA00X+119942Y+124207X0190Y    R180 S0      
327GND              J1    -284        A01X+119397Y+124207X0205Y0590R090 S1      
317GND              VIA   -    MD0100PA00X+119397Y+124876X0190Y         S0      
327GND              J1    -286        A01X+119397Y+124876X0205Y0590R090 S1      
317GND              VIA   -    MD0100PA00X+118041Y+125211X0190Y         S0      
317GND              VIA   -    MD0100PA00X+118041Y+124541X0190Y         S0      
327GND              J15   -141        A01X+118041Y+124541X0205Y0590R090 S1      
317GND              VIA   -    MD0100PA00X+116427Y+124876X0190Y         S0      
327GND              J15   -286        A01X+116427Y+124876X0205Y0590R090 S1      
317GND              VIA   -    MD0100PA00X+116972Y+124207X0190Y    R180 S0      
327GND              J15   -284        A01X+116427Y+124207X0205Y0590R090 S1      
317GND              VIA   -    MD0100PA00X+069320Y+125211X0190Y         S0      
327GND              J27   -143        A01X+069320Y+125211X0205Y0590R090 S1      
317GND              VIA   -    MD0100PA00X+069320Y+124542X0190Y         S0      
327GND              J27   -141        A01X+069320Y+124542X0205Y0590R090 S1      
317GND              VIA   -    MD0100PA00X+068250Y+124207X0190Y    R180 S0      
327GND              J27   -284        A01X+067706Y+124207X0205Y0590R090 S1      
317GND              VIA   -    MD0100PA00X+067706Y+124876X0190Y         S0      
327GND              J27   -286        A01X+067706Y+124876X0205Y0590R090 S1      
317GND              VIA   -    MD0100PA00X+066350Y+125211X0190Y         S0      
327GND              J102  -143        A01X+066350Y+125211X0205Y0590R090 S1      
317GND              VIA   -    MD0100PA00X+066350Y+124542X0190Y         S0      
327GND              J102  -141        A01X+066350Y+124542X0205Y0590R090 S1      
317GND              VIA   -    MD0100PA00X+065280Y+124207X0190Y    R180 S0      
327GND              J102  -284        A01X+064735Y+124207X0205Y0590R090 S1      
317GND              VIA   -    MD0100PA00X+064735Y+124876X0190Y         S0      
327GND              J102  -286        A01X+064735Y+124876X0205Y0590R090 S1      
317GND              VIA   -    MD0100PA00X+056158Y+124274X0200Y         S0      
327GND              R5030 -1          A18X+056158Y+124593X0198Y0197R180 S2      
317GND              VIA   -    MD0100PA00X+023397Y+125211X0190Y         S0      
327GND              J24   -143        A01X+023397Y+125211X0205Y0590R090 S1      
317GND              VIA   -    MD0100PA00X+023397Y+124542X0190Y         S0      
327GND              J24   -141        A01X+023397Y+124542X0205Y0590R090 S1      
317GND              VIA   -    MD0100PA00X+021783Y+124876X0190Y         S0      
327GND              J24   -286        A01X+021783Y+124876X0205Y0590R090 S1      
317GND              VIA   -    MD0100PA00X+022328Y+124207X0190Y    R180 S0      
327GND              J24   -284        A01X+021783Y+124207X0205Y0590R090 S1      
317GND              VIA   -    MD0100PA00X+020427Y+125211X0190Y         S0      
327GND              J26   -143        A01X+020427Y+125211X0205Y0590R090 S1      
317GND              VIA   -    MD0100PA00X+020427Y+124542X0190Y         S0      
327GND              J26   -141        A01X+020427Y+124542X0205Y0590R090 S1      
317GND              VIA   -    MD0100PA00X+018813Y+124876X0190Y         S0      
327GND              J26   -286        A01X+018813Y+124876X0205Y0590R090 S1      
317GND              VIA   -    MD0100PA00X+019358Y+124207X0190Y    R180 S0      
327GND              J26   -284        A01X+018813Y+124207X0205Y0590R090 S1      
317GND              VIA   -    MD0100PA00X+166389Y+123872X0190Y         S0      
327GND              J69   -139        A01X+166934Y+123872X0205Y0590R090 S1      
317GND              VIA   -    MD0100PA00X+166389Y+122868X0190Y         S0      
327GND              J69   -136        A01X+166934Y+122868X0205Y0590R090 S1      
317GND              VIA   -    MD0100PA00X+167374Y+123370X0190Y         S0      
317GND              VIA   -    MD0100PA00X+165320Y+122534X0190Y         S0      
327GND              J69   -279        A01X+165320Y+122534X0205Y0590R090 S1      
317GND              VIA   -    MD0100PA00X+165865Y+123203X0190Y    R180 S0      
327GND              J69   -281        A01X+165320Y+123203X0205Y0590R090 S1      
317GND              VIA   -    MD0100PA00X+165760Y+123705X0190Y         S0      
317GND              VIA   -    MD0100PA00X+163419Y+123872X0190Y         S0      
327GND              J16   -139        A01X+163964Y+123872X0205Y0590R090 S1      
317GND              VIA   -    MD0100PA00X+163419Y+122868X0190Y         S0      
327GND              J16   -136        A01X+163964Y+122868X0205Y0590R090 S1      
317GND              VIA   -    MD0100PA00X+164404Y+123370X0190Y         S0      
317GND              VIA   -    MD0100PA00X+162350Y+122534X0190Y         S0      
327GND              J16   -279        A01X+162350Y+122534X0205Y0590R090 S1      
317GND              VIA   -    MD0100PA00X+162895Y+123203X0190Y    R180 S0      
327GND              J16   -281        A01X+162350Y+123203X0205Y0590R090 S1      
317GND              VIA   -    MD0100PA00X+162790Y+123705X0190Y         S0      
317GND              VIA   -    MD0100PA00X+154023Y+122765X0200Y    R180 S0      
317GND              VIA   -    MD0100PA00X+153123Y+122765X0200Y    R180 S0      
317GND              VIA   -    MD0100PA00X+120466Y+123872X0190Y         S0      
327GND              J1    -139        A01X+121011Y+123872X0205Y0590R090 S1      
317GND              VIA   -    MD0100PA00X+120466Y+122868X0190Y         S0      
327GND              J1    -136        A01X+121011Y+122868X0205Y0590R090 S1      
317GND              VIA   -    MD0100PA00X+120571Y+123370X0190Y         S0      
317GND              VIA   -    MD0100PA00X+119942Y+123203X0190Y    R180 S0      
327GND              J1    -281        A01X+119397Y+123203X0205Y0590R090 S1      
317GND              VIA   -    MD0100PA00X+119397Y+122534X0190Y         S0      
327GND              J1    -279        A01X+119397Y+122534X0205Y0590R090 S1      
317GND              VIA   -    MD0100PA00X+118957Y+123705X0190Y         S0      
317GND              VIA   -    MD0100PA00X+117496Y+122868X0190Y         S0      
327GND              J15   -136        A01X+118041Y+122868X0205Y0590R090 S1      
317GND              VIA   -    MD0100PA00X+117496Y+123872X0190Y         S0      
327GND              J15   -139        A01X+118041Y+123872X0205Y0590R090 S1      
317GND              VIA   -    MD0100PA00X+117601Y+123370X0190Y         S0      
317GND              VIA   -    MD0100PA00X+116427Y+122534X0190Y         S0      
327GND              J15   -279        A01X+116427Y+122534X0205Y0590R090 S1      
317GND              VIA   -    MD0100PA00X+116972Y+123203X0190Y    R180 S0      
327GND              J15   -281        A01X+116427Y+123203X0205Y0590R090 S1      
317GND              VIA   -    MD0100PA00X+115987Y+123705X0190Y         S0      
317GND              VIA   -    MD0100PA00X+069760Y+123370X0190Y         S0      
317GND              VIA   -    MD0100PA00X+068775Y+122868X0190Y         S0      
327GND              J27   -136        A01X+069320Y+122868X0205Y0590R090 S1      
317GND              VIA   -    MD0100PA00X+068775Y+123872X0190Y         S0      
327GND              J27   -139        A01X+069320Y+123872X0205Y0590R090 S1      
317GND              VIA   -    MD0100PA00X+068250Y+123203X0190Y    R180 S0      
327GND              J27   -281        A01X+067706Y+123203X0205Y0590R090 S1      
317GND              VIA   -    MD0100PA00X+068146Y+123705X0190Y         S0      
317GND              VIA   -    MD0100PA00X+067706Y+122534X0190Y         S0      
327GND              J27   -279        A01X+067706Y+122534X0205Y0590R090 S1      
317GND              VIA   -    MD0100PA00X+066790Y+123370X0190Y         S0      
317GND              VIA   -    MD0100PA00X+065805Y+122868X0190Y         S0      
327GND              J102  -136        A01X+066350Y+122868X0205Y0590R090 S1      
317GND              VIA   -    MD0100PA00X+065805Y+123872X0190Y         S0      
327GND              J102  -139        A01X+066350Y+123872X0205Y0590R090 S1      
317GND              VIA   -    MD0100PA00X+065280Y+123203X0190Y    R180 S0      
327GND              J102  -281        A01X+064735Y+123203X0205Y0590R090 S1      
317GND              VIA   -    MD0100PA00X+065175Y+123705X0190Y         S0      
317GND              VIA   -    MD0100PA00X+064735Y+122534X0190Y         S0      
327GND              J102  -279        A01X+064735Y+122534X0205Y0590R090 S1      
317GND              VIA   -    MD0100PA00X+021783Y+122534X0190Y         S0      
327GND              J24   -279        A01X+021783Y+122534X0205Y0590R090 S1      
317GND              VIA   -    MD0100PA00X+022852Y+123872X0190Y         S0      
327GND              J24   -139        A01X+023397Y+123872X0205Y0590R090 S1      
317GND              VIA   -    MD0100PA00X+022328Y+123203X0190Y    R180 S0      
327GND              J24   -281        A01X+021783Y+123203X0205Y0590R090 S1      
317GND              VIA   -    MD0100PA00X+022852Y+122868X0190Y         S0      
327GND              J24   -136        A01X+023397Y+122868X0205Y0590R090 S1      
317GND              VIA   -    MD0100PA00X+022957Y+123370X0190Y         S0      
317GND              VIA   -    MD0100PA00X+021343Y+123705X0190Y         S0      
317GND              VIA   -    MD0100PA00X+018813Y+122534X0190Y         S0      
327GND              J26   -279        A01X+018813Y+122534X0205Y0590R090 S1      
317GND              VIA   -    MD0100PA00X+019882Y+123872X0190Y         S0      
327GND              J26   -139        A01X+020427Y+123872X0205Y0590R090 S1      
317GND              VIA   -    MD0100PA00X+019358Y+123203X0190Y    R180 S0      
327GND              J26   -281        A01X+018813Y+123203X0205Y0590R090 S1      
317GND              VIA   -    MD0100PA00X+019882Y+122868X0190Y         S0      
327GND              J26   -136        A01X+020427Y+122868X0205Y0590R090 S1      
317GND              VIA   -    MD0100PA00X+019987Y+123370X0190Y         S0      
317GND              VIA   -    MD0100PA00X+018373Y+123705X0190Y         S0      
317GND              VIA   -    MD0100PA00X+166934Y+122199X0190Y         S0      
327GND              J69   -134        A01X+166934Y+122199X0205Y0590R090 S1      
317GND              VIA   -    MD0100PA00X+166934Y+121530X0190Y         S0      
327GND              J69   -132        A01X+166934Y+121530X0205Y0590R090 S1      
317GND              VIA   -    MD0100PA00X+165320Y+121864X0190Y         S0      
327GND              J69   -277        A01X+165320Y+121864X0205Y0590R090 S1      
317GND              VIA   -    MD0100PA00X+165320Y+121195X0190Y         S0      
327GND              J69   -275        A01X+165320Y+121195X0205Y0590R090 S1      
317GND              VIA   -    MD0100PA00X+163964Y+122199X0190Y         S0      
327GND              J16   -134        A01X+163964Y+122199X0205Y0590R090 S1      
317GND              VIA   -    MD0100PA00X+163964Y+121530X0190Y         S0      
327GND              J16   -132        A01X+163964Y+121530X0205Y0590R090 S1      
317GND              VIA   -    MD0100PA00X+162350Y+121864X0190Y         S0      
327GND              J16   -277        A01X+162350Y+121864X0205Y0590R090 S1      
317GND              VIA   -    MD0100PA00X+162350Y+121195X0190Y         S0      
327GND              J16   -275        A01X+162350Y+121195X0205Y0590R090 S1      
317GND              VIA   -    MD0100PA00X+154988Y+122129X0200Y    R180 S0      
317GND              VIA   -    MD0100PA00X+132643Y+121433X0200Y    R270 S0      
317GND              VIA   -    MD0100PA00X+133686Y+122212X0200Y    R090 S0      
327GND              R393  -2          A18X+133798Y+121895X0198Y0197R270 S2      
317GND              VIA   -    MD0100PA00X+133120Y+121149X0200Y         S0      
327GND              R747  -1          A18X+133360Y+121149X0198Y0197R180 S2      
317GND              VIA   -    MD0100PA00X+132948Y+122216X0200Y         S0      
327GND              R394  -2          A18X+132948Y+121895X0198Y0197R270 S2      
317GND              VIA   -    MD0100PA00X+121011Y+122199X0190Y         S0      
327GND              J1    -134        A01X+121011Y+122199X0205Y0590R090 S1      
317GND              VIA   -    MD0100PA00X+121011Y+121530X0190Y         S0      
327GND              J1    -132        A01X+121011Y+121530X0205Y0590R090 S1      
317GND              VIA   -    MD0100PA00X+119397Y+121864X0190Y         S0      
327GND              J1    -277        A01X+119397Y+121864X0205Y0590R090 S1      
317GND              VIA   -    MD0100PA00X+119397Y+121195X0190Y         S0      
327GND              J1    -275        A01X+119397Y+121195X0205Y0590R090 S1      
317GND              VIA   -    MD0100PA00X+118041Y+122199X0190Y         S0      
327GND              J15   -134        A01X+118041Y+122199X0205Y0590R090 S1      
317GND              VIA   -    MD0100PA00X+118041Y+121530X0190Y         S0      
327GND              J15   -132        A01X+118041Y+121530X0205Y0590R090 S1      
317GND              VIA   -    MD0100PA00X+116427Y+121864X0190Y         S0      
327GND              J15   -277        A01X+116427Y+121864X0205Y0590R090 S1      
317GND              VIA   -    MD0100PA00X+116427Y+121195X0190Y         S0      
327GND              J15   -275        A01X+116427Y+121195X0205Y0590R090 S1      
317GND              VIA   -    MD0100PA00X+069320Y+122199X0190Y         S0      
327GND              J27   -134        A01X+069320Y+122199X0205Y0590R090 S1      
317GND              VIA   -    MD0100PA00X+069320Y+121530X0190Y         S0      
327GND              J27   -132        A01X+069320Y+121530X0205Y0590R090 S1      
317GND              VIA   -    MD0100PA00X+067706Y+121864X0190Y         S0      
327GND              J27   -277        A01X+067706Y+121864X0205Y0590R090 S1      
317GND              VIA   -    MD0100PA00X+067706Y+121195X0190Y         S0      
327GND              J27   -275        A01X+067706Y+121195X0205Y0590R090 S1      
317GND              VIA   -    MD0100PA00X+066350Y+122199X0190Y         S0      
327GND              J102  -134        A01X+066350Y+122199X0205Y0590R090 S1      
317GND              VIA   -    MD0100PA00X+066350Y+121530X0190Y         S0      
327GND              J102  -132        A01X+066350Y+121530X0205Y0590R090 S1      
317GND              VIA   -    MD0100PA00X+064735Y+121864X0190Y         S0      
327GND              J102  -277        A01X+064735Y+121864X0205Y0590R090 S1      
317GND              VIA   -    MD0100PA00X+064735Y+121195X0190Y         S0      
327GND              J102  -275        A01X+064735Y+121195X0205Y0590R090 S1      
317GND              VIA   -    MD0100PA00X+035294Y+121451X0200Y    R180 S0      
317GND              VIA   -    MD0100PA00X+023397Y+122199X0190Y         S0      
327GND              J24   -134        A01X+023397Y+122199X0205Y0590R090 S1      
317GND              VIA   -    MD0100PA00X+023397Y+121530X0190Y         S0      
327GND              J24   -132        A01X+023397Y+121530X0205Y0590R090 S1      
317GND              VIA   -    MD0100PA00X+021783Y+121864X0190Y         S0      
327GND              J24   -277        A01X+021783Y+121864X0205Y0590R090 S1      
317GND              VIA   -    MD0100PA00X+021783Y+121195X0190Y         S0      
327GND              J24   -275        A01X+021783Y+121195X0205Y0590R090 S1      
317GND              VIA   -    MD0100PA00X+020427Y+122199X0190Y         S0      
327GND              J26   -134        A01X+020427Y+122199X0205Y0590R090 S1      
317GND              VIA   -    MD0100PA00X+020427Y+121530X0190Y         S0      
327GND              J26   -132        A01X+020427Y+121530X0205Y0590R090 S1      
317GND              VIA   -    MD0100PA00X+018813Y+121864X0190Y         S0      
327GND              J26   -277        A01X+018813Y+121864X0205Y0590R090 S1      
317GND              VIA   -    MD0100PA00X+018813Y+121195X0190Y         S0      
327GND              J26   -275        A01X+018813Y+121195X0205Y0590R090 S1      
317GND              VIA   -    MD0100PA00X+166934Y+120860X0190Y         S0      
327GND              J69   -130        A01X+166934Y+120860X0205Y0590R090 S1      
317GND              VIA   -    MD0100PA00X+166389Y+120191X0190Y         S0      
327GND              J69   -128        A01X+166934Y+120191X0205Y0590R090 S1      
317GND              VIA   -    MD0100PA00X+167374Y+119689X0190Y         S0      
317GND              VIA   -    MD0100PA00X+165865Y+119522X0190Y    R180 S0      
327GND              J69   -270        A01X+165320Y+119522X0205Y0590R090 S1      
317GND              VIA   -    MD0100PA00X+165865Y+120526X0190Y    R180 S0      
327GND              J69   -273        A01X+165320Y+120526X0205Y0590R090 S1      
317GND              VIA   -    MD0100PA00X+165760Y+120024X0190Y         S0      
317GND              VIA   -    MD0100PA00X+163964Y+120860X0190Y         S0      
327GND              J16   -130        A01X+163964Y+120860X0205Y0590R090 S1      
317GND              VIA   -    MD0100PA00X+163419Y+120191X0190Y         S0      
327GND              J16   -128        A01X+163964Y+120191X0205Y0590R090 S1      
317GND              VIA   -    MD0100PA00X+164404Y+119689X0190Y         S0      
317GND              VIA   -    MD0100PA00X+162895Y+120526X0190Y    R180 S0      
327GND              J16   -273        A01X+162350Y+120526X0205Y0590R090 S1      
317GND              VIA   -    MD0100PA00X+162895Y+119522X0190Y    R180 S0      
327GND              J16   -270        A01X+162350Y+119522X0205Y0590R090 S1      
317GND              VIA   -    MD0100PA00X+162790Y+120024X0190Y         S0      
317GND              VIA   -    MD0100PA00X+121011Y+120860X0190Y         S0      
327GND              J1    -130        A01X+121011Y+120860X0205Y0590R090 S1      
317GND              VIA   -    MD0100PA00X+120466Y+120191X0190Y         S0      
327GND              J1    -128        A01X+121011Y+120191X0205Y0590R090 S1      
317GND              VIA   -    MD0100PA00X+120571Y+119689X0190Y         S0      
317GND              VIA   -    MD0100PA00X+119942Y+120526X0190Y    R180 S0      
327GND              J1    -273        A01X+119397Y+120526X0205Y0590R090 S1      
317GND              VIA   -    MD0100PA00X+119942Y+119522X0190Y    R180 S0      
327GND              J1    -270        A01X+119397Y+119522X0205Y0590R090 S1      
317GND              VIA   -    MD0100PA00X+118957Y+120024X0190Y         S0      
317GND              VIA   -    MD0100PA00X+118041Y+120860X0190Y         S0      
327GND              J15   -130        A01X+118041Y+120860X0205Y0590R090 S1      
317GND              VIA   -    MD0100PA00X+117496Y+120191X0190Y         S0      
327GND              J15   -128        A01X+118041Y+120191X0205Y0590R090 S1      
317GND              VIA   -    MD0100PA00X+117601Y+119689X0190Y         S0      
317GND              VIA   -    MD0100PA00X+116972Y+119522X0190Y    R180 S0      
327GND              J15   -270        A01X+116427Y+119522X0205Y0590R090 S1      
317GND              VIA   -    MD0100PA00X+116972Y+120526X0190Y    R180 S0      
327GND              J15   -273        A01X+116427Y+120526X0205Y0590R090 S1      
317GND              VIA   -    MD0100PA00X+115987Y+120024X0190Y         S0      
317GND              VIA   -    MD0100PA00X+069760Y+119689X0190Y         S0      
317GND              VIA   -    MD0100PA00X+069320Y+120860X0190Y         S0      
327GND              J27   -130        A01X+069320Y+120860X0205Y0590R090 S1      
317GND              VIA   -    MD0100PA00X+068775Y+120191X0190Y         S0      
327GND              J27   -128        A01X+069320Y+120191X0205Y0590R090 S1      
317GND              VIA   -    MD0100PA00X+068250Y+119522X0190Y    R180 S0      
327GND              J27   -270        A01X+067706Y+119522X0205Y0590R090 S1      
317GND              VIA   -    MD0100PA00X+068250Y+120526X0190Y    R180 S0      
327GND              J27   -273        A01X+067706Y+120526X0205Y0590R090 S1      
317GND              VIA   -    MD0100PA00X+068146Y+120024X0190Y         S0      
317GND              VIA   -    MD0100PA00X+066790Y+119689X0190Y         S0      
317GND              VIA   -    MD0100PA00X+066350Y+120860X0190Y         S0      
327GND              J102  -130        A01X+066350Y+120860X0205Y0590R090 S1      
317GND              VIA   -    MD0100PA00X+065805Y+120191X0190Y         S0      
327GND              J102  -128        A01X+066350Y+120191X0205Y0590R090 S1      
317GND              VIA   -    MD0100PA00X+065280Y+119522X0190Y    R180 S0      
327GND              J102  -270        A01X+064735Y+119522X0205Y0590R090 S1      
317GND              VIA   -    MD0100PA00X+065280Y+120526X0190Y    R180 S0      
327GND              J102  -273        A01X+064735Y+120526X0205Y0590R090 S1      
317GND              VIA   -    MD0100PA00X+065175Y+120024X0190Y         S0      
317GND              VIA   -    MD0100PA00X+036784Y+120951X0200Y    R180 S0      
327GND              R491  -1          A18X+037032Y+121154X0198Y0197R180 S2      
317GND              VIA   -    MD0100PA00X+036778Y+119965X0200Y         S0      
327GND              R5031 -1          A18X+037036Y+119965X0198Y0197R180 S2      
317GND              VIA   -    MD0100PA00X+023397Y+120860X0190Y         S0      
327GND              J24   -130        A01X+023397Y+120860X0205Y0590R090 S1      
317GND              VIA   -    MD0100PA00X+022328Y+119522X0190Y    R180 S0      
327GND              J24   -270        A01X+021783Y+119522X0205Y0590R090 S1      
317GND              VIA   -    MD0100PA00X+022328Y+120526X0190Y    R180 S0      
327GND              J24   -273        A01X+021783Y+120526X0205Y0590R090 S1      
317GND              VIA   -    MD0100PA00X+022852Y+120191X0190Y         S0      
327GND              J24   -128        A01X+023397Y+120191X0205Y0590R090 S1      
317GND              VIA   -    MD0100PA00X+022957Y+119689X0190Y         S0      
317GND              VIA   -    MD0100PA00X+020427Y+120860X0190Y         S0      
327GND              J26   -130        A01X+020427Y+120860X0205Y0590R090 S1      
317GND              VIA   -    MD0100PA00X+021343Y+120024X0190Y         S0      
317GND              VIA   -    MD0100PA00X+019358Y+119522X0190Y    R180 S0      
327GND              J26   -270        A01X+018813Y+119522X0205Y0590R090 S1      
317GND              VIA   -    MD0100PA00X+019358Y+120526X0190Y    R180 S0      
327GND              J26   -273        A01X+018813Y+120526X0205Y0590R090 S1      
317GND              VIA   -    MD0100PA00X+019882Y+120191X0190Y         S0      
327GND              J26   -128        A01X+020427Y+120191X0205Y0590R090 S1      
317GND              VIA   -    MD0100PA00X+019987Y+119689X0190Y         S0      
317GND              VIA   -    MD0100PA00X+018373Y+120024X0190Y         S0      
317GND              VIA   -    MD0100PA00X+166934Y+118518X0190Y         S0      
327GND              J69   -123        A01X+166934Y+118518X0205Y0590R090 S1      
317GND              VIA   -    MD0100PA00X+166389Y+119187X0190Y         S0      
327GND              J69   -125        A01X+166934Y+119187X0205Y0590R090 S1      
317GND              VIA   -    MD0100PA00X+165320Y+118183X0190Y         S0      
327GND              J69   -266        A01X+165320Y+118183X0205Y0590R090 S1      
317GND              VIA   -    MD0100PA00X+165320Y+118852X0190Y         S0      
327GND              J69   -268        A01X+165320Y+118852X0205Y0590R090 S1      
317GND              VIA   -    MD0100PA00X+163964Y+118518X0190Y         S0      
327GND              J16   -123        A01X+163964Y+118518X0205Y0590R090 S1      
317GND              VIA   -    MD0100PA00X+163419Y+119187X0190Y         S0      
327GND              J16   -125        A01X+163964Y+119187X0205Y0590R090 S1      
317GND              VIA   -    MD0100PA00X+162350Y+118852X0190Y         S0      
327GND              J16   -268        A01X+162350Y+118852X0205Y0590R090 S1      
317GND              VIA   -    MD0100PA00X+162350Y+118183X0190Y         S0      
327GND              J16   -266        A01X+162350Y+118183X0205Y0590R090 S1      
317GND              VIA   -    MD0100PA00X+121011Y+118518X0190Y         S0      
327GND              J1    -123        A01X+121011Y+118518X0205Y0590R090 S1      
317GND              VIA   -    MD0100PA00X+120466Y+119187X0190Y         S0      
327GND              J1    -125        A01X+121011Y+119187X0205Y0590R090 S1      
317GND              VIA   -    MD0100PA00X+119397Y+118852X0190Y         S0      
327GND              J1    -268        A01X+119397Y+118852X0205Y0590R090 S1      
317GND              VIA   -    MD0100PA00X+119397Y+118183X0190Y         S0      
327GND              J1    -266        A01X+119397Y+118183X0205Y0590R090 S1      
317GND              VIA   -    MD0100PA00X+118041Y+118518X0190Y         S0      
327GND              J15   -123        A01X+118041Y+118518X0205Y0590R090 S1      
317GND              VIA   -    MD0100PA00X+117496Y+119187X0190Y         S0      
327GND              J15   -125        A01X+118041Y+119187X0205Y0590R090 S1      
317GND              VIA   -    MD0100PA00X+116427Y+118852X0190Y         S0      
327GND              J15   -268        A01X+116427Y+118852X0205Y0590R090 S1      
317GND              VIA   -    MD0100PA00X+116427Y+118183X0190Y         S0      
327GND              J15   -266        A01X+116427Y+118183X0205Y0590R090 S1      
317GND              VIA   -    MD0100PA00X+069320Y+118518X0190Y         S0      
327GND              J27   -123        A01X+069320Y+118518X0205Y0590R090 S1      
317GND              VIA   -    MD0100PA00X+068775Y+119187X0190Y         S0      
327GND              J27   -125        A01X+069320Y+119187X0205Y0590R090 S1      
317GND              VIA   -    MD0100PA00X+067706Y+118852X0190Y         S0      
327GND              J27   -268        A01X+067706Y+118852X0205Y0590R090 S1      
317GND              VIA   -    MD0100PA00X+067706Y+118183X0190Y         S0      
327GND              J27   -266        A01X+067706Y+118183X0205Y0590R090 S1      
317GND              VIA   -    MD0100PA00X+066350Y+118518X0190Y         S0      
327GND              J102  -123        A01X+066350Y+118518X0205Y0590R090 S1      
317GND              VIA   -    MD0100PA00X+065805Y+119187X0190Y         S0      
327GND              J102  -125        A01X+066350Y+119187X0205Y0590R090 S1      
317GND              VIA   -    MD0100PA00X+064735Y+118852X0190Y         S0      
327GND              J102  -268        A01X+064735Y+118852X0205Y0590R090 S1      
317GND              VIA   -    MD0100PA00X+064735Y+118183X0190Y         S0      
327GND              J102  -266        A01X+064735Y+118183X0205Y0590R090 S1      
317GND              VIA   -    MD0100PA00X+037808Y+118495X0200Y         S0      
327GND              R5032 -1          A18X+037358Y+118786X0198Y0197     S2      
317GND              VIA   -    MD0100PA00X+036446Y+118811X0200Y         S0      
327GND              R521  -2          A18X+036179Y+118786X0198Y0197R180 S2      
317GND              VIA   -    MD0100PA00X+036479Y+119392X0200Y         S0      
327GND              R519  -2          A18X+036179Y+119392X0198Y0197R180 S2      
317GND              VIA   -    MD0100PA00X+023397Y+118518X0190Y         S0      
327GND              J24   -123        A01X+023397Y+118518X0205Y0590R090 S1      
317GND              VIA   -    MD0100PA00X+021783Y+118852X0190Y         S0      
327GND              J24   -268        A01X+021783Y+118852X0205Y0590R090 S1      
317GND              VIA   -    MD0100PA00X+021783Y+118183X0190Y         S0      
327GND              J24   -266        A01X+021783Y+118183X0205Y0590R090 S1      
317GND              VIA   -    MD0100PA00X+022852Y+119187X0190Y         S0      
327GND              J24   -125        A01X+023397Y+119187X0205Y0590R090 S1      
317GND              VIA   -    MD0100PA00X+020427Y+118518X0190Y         S0      
327GND              J26   -123        A01X+020427Y+118518X0205Y0590R090 S1      
317GND              VIA   -    MD0100PA00X+018813Y+118852X0190Y         S0      
327GND              J26   -268        A01X+018813Y+118852X0205Y0590R090 S1      
317GND              VIA   -    MD0100PA00X+018813Y+118183X0190Y         S0      
327GND              J26   -266        A01X+018813Y+118183X0205Y0590R090 S1      
317GND              VIA   -    MD0100PA00X+019882Y+119187X0190Y         S0      
327GND              J26   -125        A01X+020427Y+119187X0205Y0590R090 S1      
317GND              VIA   -    MD0100PA00X+166934Y+117848X0190Y         S0      
327GND              J69   -121        A01X+166934Y+117848X0205Y0590R090 S1      
317GND              VIA   -    MD0100PA00X+166934Y+117179X0190Y         S0      
327GND              J69   -119        A01X+166934Y+117179X0205Y0590R090 S1      
317GND              VIA   -    MD0100PA00X+165320Y+117514X0190Y         S0      
327GND              J69   -264        A01X+165320Y+117514X0205Y0590R090 S1      
317GND              VIA   -    MD0100PA00X+165865Y+116844X0190Y    R180 S0      
327GND              J69   -262        A01X+165320Y+116844X0205Y0590R090 S1      
317GND              VIA   -    MD0100PA00X+163964Y+117848X0190Y         S0      
327GND              J16   -121        A01X+163964Y+117848X0205Y0590R090 S1      
317GND              VIA   -    MD0100PA00X+163964Y+117179X0190Y         S0      
327GND              J16   -119        A01X+163964Y+117179X0205Y0590R090 S1      
317GND              VIA   -    MD0100PA00X+162350Y+117514X0190Y         S0      
327GND              J16   -264        A01X+162350Y+117514X0205Y0590R090 S1      
317GND              VIA   -    MD0100PA00X+162895Y+116844X0190Y    R180 S0      
327GND              J16   -262        A01X+162350Y+116844X0205Y0590R090 S1      
317GND              VIA   -    MD0100PA00X+133814Y+118164X0200Y         S0      
317GND              VIA   -    MD0100PA00X+133798Y+117800X0200Y         S0      
317GND              VIA   -    MD0100PA00X+121011Y+117848X0190Y         S0      
327GND              J1    -121        A01X+121011Y+117848X0205Y0590R090 S1      
317GND              VIA   -    MD0100PA00X+121011Y+117179X0190Y         S0      
327GND              J1    -119        A01X+121011Y+117179X0205Y0590R090 S1      
317GND              VIA   -    MD0100PA00X+119397Y+117514X0190Y         S0      
327GND              J1    -264        A01X+119397Y+117514X0205Y0590R090 S1      
317GND              VIA   -    MD0100PA00X+119942Y+116844X0190Y    R180 S0      
327GND              J1    -262        A01X+119397Y+116844X0205Y0590R090 S1      
317GND              VIA   -    MD0100PA00X+118041Y+117848X0190Y         S0      
327GND              J15   -121        A01X+118041Y+117848X0205Y0590R090 S1      
317GND              VIA   -    MD0100PA00X+118041Y+117179X0190Y         S0      
327GND              J15   -119        A01X+118041Y+117179X0205Y0590R090 S1      
317GND              VIA   -    MD0100PA00X+116427Y+117514X0190Y         S0      
327GND              J15   -264        A01X+116427Y+117514X0205Y0590R090 S1      
317GND              VIA   -    MD0100PA00X+116972Y+116844X0190Y    R180 S0      
327GND              J15   -262        A01X+116427Y+116844X0205Y0590R090 S1      
317GND              VIA   -    MD0100PA00X+069320Y+117849X0190Y         S0      
327GND              J27   -121        A01X+069320Y+117849X0205Y0590R090 S1      
317GND              VIA   -    MD0100PA00X+069320Y+117179X0190Y         S0      
327GND              J27   -119        A01X+069320Y+117179X0205Y0590R090 S1      
317GND              VIA   -    MD0100PA00X+068250Y+116845X0190Y    R180 S0      
327GND              J27   -262        A01X+067706Y+116845X0205Y0590R090 S1      
317GND              VIA   -    MD0100PA00X+067706Y+117514X0190Y         S0      
327GND              J27   -264        A01X+067706Y+117514X0205Y0590R090 S1      
317GND              VIA   -    MD0100PA00X+066350Y+117849X0190Y         S0      
327GND              J102  -121        A01X+066350Y+117849X0205Y0590R090 S1      
317GND              VIA   -    MD0100PA00X+066350Y+117179X0190Y         S0      
327GND              J102  -119        A01X+066350Y+117179X0205Y0590R090 S1      
317GND              VIA   -    MD0100PA00X+065280Y+116845X0190Y    R180 S0      
327GND              J102  -262        A01X+064735Y+116845X0205Y0590R090 S1      
317GND              VIA   -    MD0100PA00X+064735Y+117514X0190Y         S0      
327GND              J102  -264        A01X+064735Y+117514X0205Y0590R090 S1      
317GND              VIA   -    MD0100PA00X+023397Y+117849X0190Y         S0      
327GND              J24   -121        A01X+023397Y+117849X0205Y0590R090 S1      
317GND              VIA   -    MD0100PA00X+023397Y+117179X0190Y         S0      
327GND              J24   -119        A01X+023397Y+117179X0205Y0590R090 S1      
317GND              VIA   -    MD0100PA00X+021783Y+117514X0190Y         S0      
327GND              J24   -264        A01X+021783Y+117514X0205Y0590R090 S1      
317GND              VIA   -    MD0100PA00X+022328Y+116845X0190Y    R180 S0      
327GND              J24   -262        A01X+021783Y+116845X0205Y0590R090 S1      
317GND              VIA   -    MD0100PA00X+020427Y+117849X0190Y         S0      
327GND              J26   -121        A01X+020427Y+117849X0205Y0590R090 S1      
317GND              VIA   -    MD0100PA00X+020427Y+117179X0190Y         S0      
327GND              J26   -119        A01X+020427Y+117179X0205Y0590R090 S1      
317GND              VIA   -    MD0100PA00X+018813Y+117514X0190Y         S0      
327GND              J26   -264        A01X+018813Y+117514X0205Y0590R090 S1      
317GND              VIA   -    MD0100PA00X+019358Y+116845X0190Y    R180 S0      
327GND              J26   -262        A01X+018813Y+116845X0205Y0590R090 S1      
317GND              VIA   -    MD0100PA00X+166389Y+116510X0190Y         S0      
327GND              J69   -117        A01X+166934Y+116510X0205Y0590R090 S1      
317GND              VIA   -    MD0100PA00X+166389Y+115506X0190Y         S0      
327GND              J69   -114        A01X+166934Y+115506X0205Y0590R090 S1      
317GND              VIA   -    MD0100PA00X+167374Y+116008X0190Y         S0      
317GND              VIA   -    MD0100PA00X+165320Y+115171X0190Y         S0      
327GND              J69   -257        A01X+165320Y+115171X0205Y0590R090 S1      
317GND              VIA   -    MD0100PA00X+165865Y+115841X0190Y    R180 S0      
327GND              J69   -259        A01X+165320Y+115841X0205Y0590R090 S1      
317GND              VIA   -    MD0100PA00X+165760Y+116343X0190Y         S0      
317GND              VIA   -    MD0100PA00X+163419Y+116510X0190Y         S0      
327GND              J16   -117        A01X+163964Y+116510X0205Y0590R090 S1      
317GND              VIA   -    MD0100PA00X+163419Y+115506X0190Y         S0      
327GND              J16   -114        A01X+163964Y+115506X0205Y0590R090 S1      
317GND              VIA   -    MD0100PA00X+164404Y+116008X0190Y         S0      
317GND              VIA   -    MD0100PA00X+162350Y+115171X0190Y         S0      
327GND              J16   -257        A01X+162350Y+115171X0205Y0590R090 S1      
317GND              VIA   -    MD0100PA00X+162895Y+115841X0190Y    R180 S0      
327GND              J16   -259        A01X+162350Y+115841X0205Y0590R090 S1      
317GND              VIA   -    MD0100PA00X+162790Y+116343X0190Y         S0      
317GND              VIA   -    MD0100PA00X+149439Y+117874X0200Y         S0      
317GND              VIA   -    MD0100PA00X+150447Y+117826X0200Y         S0      
317GND              VIA   -    MD0100PA00X+151347Y+117826X0200Y         S0      
317GND              VIA   -    MD0100PA00X+153432Y+121683X0200Y    R180 S0      
317GND              VIA   -    MD0100PA00X+155530Y+124256X0200Y         S0      
317GND              VIA   -    MD0100PA00X+155537Y+124808X0200Y         S0      
317GND              VIA   -    MD0100PA00X+155557Y+123597X0200Y         S0      
317GND              VIA   -    MD0100PA00X+154988Y+121729X0200Y    R180 S0      
317GND              VIA   -    MD0100PA00X+156427Y+125316X0200Y         S0      
317GND              VIA   -    MD0100PA00X+158133Y+125286X0200Y         S0      
317GND              VIA   -    MD0100PA00X+157537Y+125277X0200Y         S0      
317GND              VIA   -    MD0100PA00X+159010Y+124677X0200Y         S0      
317GND              VIA   -    MD0100PA00X+158956Y+125278X0200Y         S0      
317GND              VIA   -    MD0100PA00X+120466Y+116510X0190Y         S0      
327GND              J1    -117        A01X+121011Y+116510X0205Y0590R090 S1      
317GND              VIA   -    MD0100PA00X+120466Y+115506X0190Y         S0      
327GND              J1    -114        A01X+121011Y+115506X0205Y0590R090 S1      
317GND              VIA   -    MD0100PA00X+120571Y+116008X0190Y         S0      
317GND              VIA   -    MD0100PA00X+119397Y+115171X0190Y         S0      
327GND              J1    -257        A01X+119397Y+115171X0205Y0590R090 S1      
317GND              VIA   -    MD0100PA00X+119942Y+115841X0190Y    R180 S0      
327GND              J1    -259        A01X+119397Y+115841X0205Y0590R090 S1      
317GND              VIA   -    MD0100PA00X+118957Y+116343X0190Y         S0      
317GND              VIA   -    MD0100PA00X+117496Y+116510X0190Y         S0      
327GND              J15   -117        A01X+118041Y+116510X0205Y0590R090 S1      
317GND              VIA   -    MD0100PA00X+117496Y+115506X0190Y         S0      
327GND              J15   -114        A01X+118041Y+115506X0205Y0590R090 S1      
317GND              VIA   -    MD0100PA00X+117601Y+116008X0190Y         S0      
317GND              VIA   -    MD0100PA00X+116427Y+115171X0190Y         S0      
327GND              J15   -257        A01X+116427Y+115171X0205Y0590R090 S1      
317GND              VIA   -    MD0100PA00X+116972Y+115841X0190Y    R180 S0      
327GND              J15   -259        A01X+116427Y+115841X0205Y0590R090 S1      
317GND              VIA   -    MD0100PA00X+115987Y+116343X0190Y         S0      
317GND              VIA   -    MD0100PA00X+069760Y+116008X0190Y         S0      
317GND              VIA   -    MD0100PA00X+068775Y+116510X0190Y         S0      
327GND              J27   -117        A01X+069320Y+116510X0205Y0590R090 S1      
317GND              VIA   -    MD0100PA00X+068775Y+115506X0190Y         S0      
327GND              J27   -114        A01X+069320Y+115506X0205Y0590R090 S1      
317GND              VIA   -    MD0100PA00X+068250Y+115841X0190Y    R180 S0      
327GND              J27   -259        A01X+067706Y+115841X0205Y0590R090 S1      
317GND              VIA   -    MD0100PA00X+068146Y+116343X0190Y         S0      
317GND              VIA   -    MD0100PA00X+067706Y+115171X0190Y         S0      
327GND              J27   -257        A01X+067706Y+115171X0205Y0590R090 S1      
317GND              VIA   -    MD0100PA00X+066790Y+116008X0190Y         S0      
317GND              VIA   -    MD0100PA00X+065805Y+116510X0190Y         S0      
327GND              J102  -117        A01X+066350Y+116510X0205Y0590R090 S1      
317GND              VIA   -    MD0100PA00X+065805Y+115506X0190Y         S0      
327GND              J102  -114        A01X+066350Y+115506X0205Y0590R090 S1      
317GND              VIA   -    MD0100PA00X+065280Y+115841X0190Y    R180 S0      
327GND              J102  -259        A01X+064735Y+115841X0205Y0590R090 S1      
317GND              VIA   -    MD0100PA00X+065175Y+116343X0190Y         S0      
317GND              VIA   -    MD0100PA00X+064735Y+115171X0190Y         S0      
327GND              J102  -257        A01X+064735Y+115171X0205Y0590R090 S1      
327GND              C239  -2          A18X+061217Y+124271X0198Y0197R090 S2      
327GND              C238  -2          A18X+059797Y+124391X0198Y0197R090 S2      
327GND              Y4    -2          A18X+059113Y+125072X0480Y0590R090 S2      
327GND              Y4    -4          A18X+058279Y+124442X0480Y0590R090 S2      
317GND              VIA   -    MD0100PA00X+055117Y+116768X0200Y    R180 S0      
317GND              VIA   -    MD0100PA00X+058363Y+125508X0200Y         S0      
317GND              VIA   -    MD0100PA00X+058863Y+125508X0200Y         S0      
317GND              VIA   -    MD0100PA00X+057807Y+124442X0200Y         S0      
317GND              VIA   -    MD0100PA00X+057883Y+123808X0200Y         S0      
327GND              C236  -2   M      A18X+058158Y+123808X0198Y0197     S2      
317GND              VIA   -    MD0100PA00X+058550Y+122954X0200Y    R180 S0      
317GND              VIA   -    MD0100PA00X+057883Y+121859X0200Y    R180 S0      
317GND              VIA   -    MD0100PA00X+059595Y+125858X0200Y         S0      
317GND              VIA   -    MD0100PA00X+060395Y+125858X0200Y         S0      
317GND              VIA   -    MD0100PA00X+059966Y+124173X0200Y         S0      
317GND              VIA   -    MD0100PA00X+059560Y+125108X0200Y         S0      
317GND              VIA   -    MD0100PA00X+059567Y+124569X0200Y         S0      
317GND              VIA   -    MD0100PA00X+059433Y+123808X0200Y         S0      
327GND              C237  -2   M      A18X+059173Y+123808X0198Y0197R180 S2      
317GND              VIA   -    MD0100PA00X+059276Y+122069X0200Y    R180 S0      
317GND              VIA   -    MD0100PA00X+061245Y+125858X0200Y         S0      
317GND              VIA   -    MD0100PA00X+060916Y+124023X0200Y         S0      
317GND              VIA   -    MD0100PA00X+061295Y+125208X0200Y         S0      
317GND              VIA   -    MD0100PA00X+061287Y+124849X0200Y         S0      
317GND              VIA   -    MD0100PA00X+021783Y+115171X0190Y         S0      
327GND              J24   -257        A01X+021783Y+115171X0205Y0590R090 S1      
317GND              VIA   -    MD0100PA00X+022852Y+116510X0190Y         S0      
327GND              J24   -117        A01X+023397Y+116510X0205Y0590R090 S1      
317GND              VIA   -    MD0100PA00X+022328Y+115841X0190Y    R180 S0      
327GND              J24   -259        A01X+021783Y+115841X0205Y0590R090 S1      
317GND              VIA   -    MD0100PA00X+022852Y+115506X0190Y         S0      
327GND              J24   -114        A01X+023397Y+115506X0205Y0590R090 S1      
317GND              VIA   -    MD0100PA00X+022957Y+116008X0190Y         S0      
317GND              VIA   -    MD0100PA00X+021343Y+116343X0190Y         S0      
317GND              VIA   -    MD0100PA00X+018813Y+115171X0190Y         S0      
327GND              J26   -257        A01X+018813Y+115171X0205Y0590R090 S1      
317GND              VIA   -    MD0100PA00X+019882Y+116510X0190Y         S0      
327GND              J26   -117        A01X+020427Y+116510X0205Y0590R090 S1      
317GND              VIA   -    MD0100PA00X+019358Y+115841X0190Y    R180 S0      
327GND              J26   -259        A01X+018813Y+115841X0205Y0590R090 S1      
317GND              VIA   -    MD0100PA00X+019882Y+115506X0190Y         S0      
327GND              J26   -114        A01X+020427Y+115506X0205Y0590R090 S1      
317GND              VIA   -    MD0100PA00X+019987Y+116008X0190Y         S0      
317GND              VIA   -    MD0100PA00X+018373Y+116343X0190Y         S0      
317GND              VIA   -    MD0100PA00X+166934Y+114837X0190Y         S0      
327GND              J69   -112        A01X+166934Y+114837X0205Y0590R090 S1      
317GND              VIA   -    MD0100PA00X+166934Y+114167X0190Y         S0      
327GND              J69   -110        A01X+166934Y+114167X0205Y0590R090 S1      
317GND              VIA   -    MD0100PA00X+165320Y+114502X0190Y         S0      
327GND              J69   -255        A01X+165320Y+114502X0205Y0590R090 S1      
317GND              VIA   -    MD0100PA00X+165320Y+113833X0190Y         S0      
327GND              J69   -253        A01X+165320Y+113833X0205Y0590R090 S1      
317GND              VIA   -    MD0100PA00X+163964Y+114837X0190Y         S0      
327GND              J16   -112        A01X+163964Y+114837X0205Y0590R090 S1      
317GND              VIA   -    MD0100PA00X+163964Y+114167X0190Y         S0      
327GND              J16   -110        A01X+163964Y+114167X0205Y0590R090 S1      
317GND              VIA   -    MD0100PA00X+162350Y+114502X0190Y         S0      
327GND              J16   -255        A01X+162350Y+114502X0205Y0590R090 S1      
317GND              VIA   -    MD0100PA00X+162350Y+113833X0190Y         S0      
327GND              J16   -253        A01X+162350Y+113833X0205Y0590R090 S1      
317GND              VIA   -    MD0100PA00X+121011Y+114837X0190Y         S0      
327GND              J1    -112        A01X+121011Y+114837X0205Y0590R090 S1      
317GND              VIA   -    MD0100PA00X+121011Y+114167X0190Y         S0      
327GND              J1    -110        A01X+121011Y+114167X0205Y0590R090 S1      
317GND              VIA   -    MD0100PA00X+119397Y+114502X0190Y         S0      
327GND              J1    -255        A01X+119397Y+114502X0205Y0590R090 S1      
317GND              VIA   -    MD0100PA00X+119397Y+113833X0190Y         S0      
327GND              J1    -253        A01X+119397Y+113833X0205Y0590R090 S1      
317GND              VIA   -    MD0100PA00X+118041Y+114837X0190Y         S0      
327GND              J15   -112        A01X+118041Y+114837X0205Y0590R090 S1      
317GND              VIA   -    MD0100PA00X+118041Y+114167X0190Y         S0      
327GND              J15   -110        A01X+118041Y+114167X0205Y0590R090 S1      
317GND              VIA   -    MD0100PA00X+116427Y+114502X0190Y         S0      
327GND              J15   -255        A01X+116427Y+114502X0205Y0590R090 S1      
317GND              VIA   -    MD0100PA00X+116427Y+113833X0190Y         S0      
327GND              J15   -253        A01X+116427Y+113833X0205Y0590R090 S1      
317GND              VIA   -    MD0100PA00X+069320Y+114837X0190Y         S0      
327GND              J27   -112        A01X+069320Y+114837X0205Y0590R090 S1      
317GND              VIA   -    MD0100PA00X+069320Y+114168X0190Y         S0      
327GND              J27   -110        A01X+069320Y+114168X0205Y0590R090 S1      
317GND              VIA   -    MD0100PA00X+067706Y+114502X0190Y         S0      
327GND              J27   -255        A01X+067706Y+114502X0205Y0590R090 S1      
317GND              VIA   -    MD0100PA00X+067706Y+113833X0190Y         S0      
327GND              J27   -253        A01X+067706Y+113833X0205Y0590R090 S1      
317GND              VIA   -    MD0100PA00X+066350Y+114837X0190Y         S0      
327GND              J102  -112        A01X+066350Y+114837X0205Y0590R090 S1      
317GND              VIA   -    MD0100PA00X+066350Y+114168X0190Y         S0      
327GND              J102  -110        A01X+066350Y+114168X0205Y0590R090 S1      
317GND              VIA   -    MD0100PA00X+064735Y+114502X0190Y         S0      
327GND              J102  -255        A01X+064735Y+114502X0205Y0590R090 S1      
317GND              VIA   -    MD0100PA00X+064735Y+113833X0190Y         S0      
327GND              J102  -253        A01X+064735Y+113833X0205Y0590R090 S1      
317GND              VIA   -    MD0100PA00X+023397Y+114837X0190Y         S0      
327GND              J24   -112        A01X+023397Y+114837X0205Y0590R090 S1      
317GND              VIA   -    MD0100PA00X+023397Y+114168X0190Y         S0      
327GND              J24   -110        A01X+023397Y+114168X0205Y0590R090 S1      
317GND              VIA   -    MD0100PA00X+021783Y+114502X0190Y         S0      
327GND              J24   -255        A01X+021783Y+114502X0205Y0590R090 S1      
317GND              VIA   -    MD0100PA00X+021783Y+113833X0190Y         S0      
327GND              J24   -253        A01X+021783Y+113833X0205Y0590R090 S1      
317GND              VIA   -    MD0100PA00X+020427Y+114837X0190Y         S0      
327GND              J26   -112        A01X+020427Y+114837X0205Y0590R090 S1      
317GND              VIA   -    MD0100PA00X+020427Y+114168X0190Y         S0      
327GND              J26   -110        A01X+020427Y+114168X0205Y0590R090 S1      
317GND              VIA   -    MD0100PA00X+018813Y+114502X0190Y         S0      
327GND              J26   -255        A01X+018813Y+114502X0205Y0590R090 S1      
317GND              VIA   -    MD0100PA00X+018813Y+113833X0190Y         S0      
327GND              J26   -253        A01X+018813Y+113833X0205Y0590R090 S1      
317GND              VIA   -    MD0100PA00X+166934Y+113498X0190Y         S0      
327GND              J69   -108        A01X+166934Y+113498X0205Y0590R090 S1      
317GND              VIA   -    MD0100PA00X+166389Y+112829X0190Y         S0      
327GND              J69   -106        A01X+166934Y+112829X0205Y0590R090 S1      
317GND              VIA   -    MD0100PA00X+167374Y+112327X0190Y         S0      
317GND              VIA   -    MD0100PA00X+165865Y+113163X0190Y    R180 S0      
327GND              J69   -251        A01X+165320Y+113163X0205Y0590R090 S1      
317GND              VIA   -    MD0100PA00X+165865Y+112160X0190Y    R180 S0      
327GND              J69   -248        A01X+165320Y+112160X0205Y0590R090 S1      
317GND              VIA   -    MD0100PA00X+165760Y+112662X0190Y         S0      
317GND              VIA   -    MD0100PA00X+163964Y+113498X0190Y         S0      
327GND              J16   -108        A01X+163964Y+113498X0205Y0590R090 S1      
317GND              VIA   -    MD0100PA00X+163419Y+112829X0190Y         S0      
327GND              J16   -106        A01X+163964Y+112829X0205Y0590R090 S1      
317GND              VIA   -    MD0100PA00X+164404Y+112327X0190Y         S0      
317GND              VIA   -    MD0100PA00X+162895Y+113163X0190Y    R180 S0      
327GND              J16   -251        A01X+162350Y+113163X0205Y0590R090 S1      
317GND              VIA   -    MD0100PA00X+162895Y+112160X0190Y    R180 S0      
327GND              J16   -248        A01X+162350Y+112160X0205Y0590R090 S1      
317GND              VIA   -    MD0100PA00X+162790Y+112662X0190Y         S0      
317GND              VIA   -    MD0100PA00X+121011Y+113498X0190Y         S0      
327GND              J1    -108        A01X+121011Y+113498X0205Y0590R090 S1      
317GND              VIA   -    MD0100PA00X+120466Y+112829X0190Y         S0      
327GND              J1    -106        A01X+121011Y+112829X0205Y0590R090 S1      
317GND              VIA   -    MD0100PA00X+120571Y+112327X0190Y         S0      
317GND              VIA   -    MD0100PA00X+119942Y+113163X0190Y    R180 S0      
327GND              J1    -251        A01X+119397Y+113163X0205Y0590R090 S1      
317GND              VIA   -    MD0100PA00X+119942Y+112160X0190Y    R180 S0      
327GND              J1    -248        A01X+119397Y+112160X0205Y0590R090 S1      
317GND              VIA   -    MD0100PA00X+118957Y+112662X0190Y         S0      
317GND              VIA   -    MD0100PA00X+118041Y+113498X0190Y         S0      
327GND              J15   -108        A01X+118041Y+113498X0205Y0590R090 S1      
317GND              VIA   -    MD0100PA00X+117496Y+112829X0190Y         S0      
327GND              J15   -106        A01X+118041Y+112829X0205Y0590R090 S1      
317GND              VIA   -    MD0100PA00X+117601Y+112327X0190Y         S0      
317GND              VIA   -    MD0100PA00X+116972Y+113163X0190Y    R180 S0      
327GND              J15   -251        A01X+116427Y+113163X0205Y0590R090 S1      
317GND              VIA   -    MD0100PA00X+116972Y+112160X0190Y    R180 S0      
327GND              J15   -248        A01X+116427Y+112160X0205Y0590R090 S1      
317GND              VIA   -    MD0100PA00X+115987Y+112662X0190Y         S0      
317GND              VIA   -    MD0100PA00X+069760Y+112327X0190Y         S0      
317GND              VIA   -    MD0100PA00X+069320Y+113498X0190Y         S0      
327GND              J27   -108        A01X+069320Y+113498X0205Y0590R090 S1      
317GND              VIA   -    MD0100PA00X+068775Y+112829X0190Y         S0      
327GND              J27   -106        A01X+069320Y+112829X0205Y0590R090 S1      
317GND              VIA   -    MD0100PA00X+068250Y+113164X0190Y    R180 S0      
327GND              J27   -251        A01X+067706Y+113164X0205Y0590R090 S1      
317GND              VIA   -    MD0100PA00X+068250Y+112160X0190Y    R180 S0      
327GND              J27   -248        A01X+067706Y+112160X0205Y0590R090 S1      
317GND              VIA   -    MD0100PA00X+068146Y+112662X0190Y         S0      
317GND              VIA   -    MD0100PA00X+066790Y+112327X0190Y         S0      
317GND              VIA   -    MD0100PA00X+066350Y+113498X0190Y         S0      
327GND              J102  -108        A01X+066350Y+113498X0205Y0590R090 S1      
317GND              VIA   -    MD0100PA00X+065805Y+112829X0190Y         S0      
327GND              J102  -106        A01X+066350Y+112829X0205Y0590R090 S1      
317GND              VIA   -    MD0100PA00X+065280Y+113164X0190Y    R180 S0      
327GND              J102  -251        A01X+064735Y+113164X0205Y0590R090 S1      
317GND              VIA   -    MD0100PA00X+065280Y+112160X0190Y    R180 S0      
327GND              J102  -248        A01X+064735Y+112160X0205Y0590R090 S1      
317GND              VIA   -    MD0100PA00X+065175Y+112662X0190Y         S0      
317GND              VIA   -    MD0100PA00X+023397Y+113498X0190Y         S0      
327GND              J24   -108        A01X+023397Y+113498X0205Y0590R090 S1      
317GND              VIA   -    MD0100PA00X+022328Y+113164X0190Y    R180 S0      
327GND              J24   -251        A01X+021783Y+113164X0205Y0590R090 S1      
317GND              VIA   -    MD0100PA00X+022852Y+112829X0190Y         S0      
327GND              J24   -106        A01X+023397Y+112829X0205Y0590R090 S1      
317GND              VIA   -    MD0100PA00X+022328Y+112160X0190Y    R180 S0      
327GND              J24   -248        A01X+021783Y+112160X0205Y0590R090 S1      
317GND              VIA   -    MD0100PA00X+022957Y+112327X0190Y         S0      
317GND              VIA   -    MD0100PA00X+020427Y+113498X0190Y         S0      
327GND              J26   -108        A01X+020427Y+113498X0205Y0590R090 S1      
317GND              VIA   -    MD0100PA00X+021343Y+112662X0190Y         S0      
317GND              VIA   -    MD0100PA00X+019358Y+113164X0190Y    R180 S0      
327GND              J26   -251        A01X+018813Y+113164X0205Y0590R090 S1      
317GND              VIA   -    MD0100PA00X+019882Y+112829X0190Y         S0      
327GND              J26   -106        A01X+020427Y+112829X0205Y0590R090 S1      
317GND              VIA   -    MD0100PA00X+019358Y+112160X0190Y    R180 S0      
327GND              J26   -248        A01X+018813Y+112160X0205Y0590R090 S1      
317GND              VIA   -    MD0100PA00X+019987Y+112327X0190Y         S0      
317GND              VIA   -    MD0100PA00X+018373Y+112662X0190Y         S0      
317GND              VIA   -    MD0100PA00X+166934Y+111156X0190Y         S0      
327GND              J69   -101        A01X+166934Y+111156X0205Y0590R090 S1      
317GND              VIA   -    MD0100PA00X+166389Y+111825X0190Y         S0      
327GND              J69   -103        A01X+166934Y+111825X0205Y0590R090 S1      
317GND              VIA   -    MD0100PA00X+165320Y+111490X0190Y         S0      
327GND              J69   -246        A01X+165320Y+111490X0205Y0590R090 S1      
317GND              VIA   -    MD0100PA00X+165320Y+110821X0190Y         S0      
327GND              J69   -244        A01X+165320Y+110821X0205Y0590R090 S1      
317GND              VIA   -    MD0100PA00X+163964Y+111156X0190Y         S0      
327GND              J16   -101        A01X+163964Y+111156X0205Y0590R090 S1      
317GND              VIA   -    MD0100PA00X+163419Y+111825X0190Y         S0      
327GND              J16   -103        A01X+163964Y+111825X0205Y0590R090 S1      
317GND              VIA   -    MD0100PA00X+162350Y+111490X0190Y         S0      
327GND              J16   -246        A01X+162350Y+111490X0205Y0590R090 S1      
317GND              VIA   -    MD0100PA00X+162350Y+110821X0190Y         S0      
327GND              J16   -244        A01X+162350Y+110821X0205Y0590R090 S1      
317GND              VIA   -    MD0100PA00X+121011Y+111156X0190Y         S0      
327GND              J1    -101        A01X+121011Y+111156X0205Y0590R090 S1      
317GND              VIA   -    MD0100PA00X+120466Y+111825X0190Y         S0      
327GND              J1    -103        A01X+121011Y+111825X0205Y0590R090 S1      
317GND              VIA   -    MD0100PA00X+119397Y+111490X0190Y         S0      
327GND              J1    -246        A01X+119397Y+111490X0205Y0590R090 S1      
317GND              VIA   -    MD0100PA00X+119397Y+110821X0190Y         S0      
327GND              J1    -244        A01X+119397Y+110821X0205Y0590R090 S1      
317GND              VIA   -    MD0100PA00X+118041Y+111156X0190Y         S0      
327GND              J15   -101        A01X+118041Y+111156X0205Y0590R090 S1      
317GND              VIA   -    MD0100PA00X+117496Y+111825X0190Y         S0      
327GND              J15   -103        A01X+118041Y+111825X0205Y0590R090 S1      
317GND              VIA   -    MD0100PA00X+116427Y+111490X0190Y         S0      
327GND              J15   -246        A01X+116427Y+111490X0205Y0590R090 S1      
317GND              VIA   -    MD0100PA00X+116427Y+110821X0190Y         S0      
327GND              J15   -244        A01X+116427Y+110821X0205Y0590R090 S1      
317GND              VIA   -    MD0100PA00X+069320Y+111156X0190Y         S0      
327GND              J27   -101        A01X+069320Y+111156X0205Y0590R090 S1      
317GND              VIA   -    MD0100PA00X+068775Y+111825X0190Y         S0      
327GND              J27   -103        A01X+069320Y+111825X0205Y0590R090 S1      
317GND              VIA   -    MD0100PA00X+067706Y+111490X0190Y         S0      
327GND              J27   -246        A01X+067706Y+111490X0205Y0590R090 S1      
317GND              VIA   -    MD0100PA00X+067706Y+110821X0190Y         S0      
327GND              J27   -244        A01X+067706Y+110821X0205Y0590R090 S1      
317GND              VIA   -    MD0100PA00X+066350Y+111156X0190Y         S0      
327GND              J102  -101        A01X+066350Y+111156X0205Y0590R090 S1      
317GND              VIA   -    MD0100PA00X+065805Y+111825X0190Y         S0      
327GND              J102  -103        A01X+066350Y+111825X0205Y0590R090 S1      
317GND              VIA   -    MD0100PA00X+064735Y+111490X0190Y         S0      
327GND              J102  -246        A01X+064735Y+111490X0205Y0590R090 S1      
317GND              VIA   -    MD0100PA00X+064735Y+110821X0190Y         S0      
327GND              J102  -244        A01X+064735Y+110821X0205Y0590R090 S1      
317GND              VIA   -    MD0100PA00X+023397Y+111156X0190Y         S0      
327GND              J24   -101        A01X+023397Y+111156X0205Y0590R090 S1      
317GND              VIA   -    MD0100PA00X+021783Y+111490X0190Y         S0      
327GND              J24   -246        A01X+021783Y+111490X0205Y0590R090 S1      
317GND              VIA   -    MD0100PA00X+021783Y+110821X0190Y         S0      
327GND              J24   -244        A01X+021783Y+110821X0205Y0590R090 S1      
317GND              VIA   -    MD0100PA00X+022852Y+111825X0190Y         S0      
327GND              J24   -103        A01X+023397Y+111825X0205Y0590R090 S1      
317GND              VIA   -    MD0100PA00X+020427Y+111156X0190Y         S0      
327GND              J26   -101        A01X+020427Y+111156X0205Y0590R090 S1      
317GND              VIA   -    MD0100PA00X+018813Y+111490X0190Y         S0      
327GND              J26   -246        A01X+018813Y+111490X0205Y0590R090 S1      
317GND              VIA   -    MD0100PA00X+018813Y+110821X0190Y         S0      
327GND              J26   -244        A01X+018813Y+110821X0205Y0590R090 S1      
317GND              VIA   -    MD0100PA00X+019882Y+111825X0190Y         S0      
327GND              J26   -103        A01X+020427Y+111825X0205Y0590R090 S1      
317GND              VIA   -    MD0100PA00X+166934Y+110486X0190Y         S0      
327GND              J69   -99         A01X+166934Y+110486X0205Y0590R090 S1      
317GND              VIA   -    MD0100PA00X+166934Y+109817X0190Y         S0      
327GND              J69   -97         A01X+166934Y+109817X0205Y0590R090 S1      
317GND              VIA   -    MD0100PA00X+166389Y+109148X0190Y         S0      
327GND              J69   -95         A01X+166934Y+109148X0205Y0590R090 S1      
317GND              VIA   -    MD0100PA00X+165320Y+110152X0190Y         S0      
327GND              J69   -242        A01X+165320Y+110152X0205Y0590R090 S1      
317GND              VIA   -    MD0100PA00X+165865Y+109482X0190Y    R180 S0      
327GND              J69   -240        A01X+165320Y+109482X0205Y0590R090 S1      
317GND              VIA   -    MD0100PA00X+163964Y+110486X0190Y         S0      
327GND              J16   -99         A01X+163964Y+110486X0205Y0590R090 S1      
317GND              VIA   -    MD0100PA00X+163964Y+109817X0190Y         S0      
327GND              J16   -97         A01X+163964Y+109817X0205Y0590R090 S1      
317GND              VIA   -    MD0100PA00X+163419Y+109148X0190Y         S0      
327GND              J16   -95         A01X+163964Y+109148X0205Y0590R090 S1      
317GND              VIA   -    MD0100PA00X+162350Y+110152X0190Y         S0      
327GND              J16   -242        A01X+162350Y+110152X0205Y0590R090 S1      
317GND              VIA   -    MD0100PA00X+162895Y+109482X0190Y    R180 S0      
327GND              J16   -240        A01X+162350Y+109482X0205Y0590R090 S1      
317GND              VIA   -    MD0100PA00X+121011Y+110486X0190Y         S0      
327GND              J1    -99         A01X+121011Y+110486X0205Y0590R090 S1      
317GND              VIA   -    MD0100PA00X+121011Y+109817X0190Y         S0      
327GND              J1    -97         A01X+121011Y+109817X0205Y0590R090 S1      
317GND              VIA   -    MD0100PA00X+120466Y+109148X0190Y         S0      
327GND              J1    -95         A01X+121011Y+109148X0205Y0590R090 S1      
317GND              VIA   -    MD0100PA00X+119397Y+110152X0190Y         S0      
327GND              J1    -242        A01X+119397Y+110152X0205Y0590R090 S1      
317GND              VIA   -    MD0100PA00X+119942Y+109482X0190Y    R180 S0      
327GND              J1    -240        A01X+119397Y+109482X0205Y0590R090 S1      
317GND              VIA   -    MD0100PA00X+118041Y+110486X0190Y         S0      
327GND              J15   -99         A01X+118041Y+110486X0205Y0590R090 S1      
317GND              VIA   -    MD0100PA00X+118041Y+109817X0190Y         S0      
327GND              J15   -97         A01X+118041Y+109817X0205Y0590R090 S1      
317GND              VIA   -    MD0100PA00X+117496Y+109148X0190Y         S0      
327GND              J15   -95         A01X+118041Y+109148X0205Y0590R090 S1      
317GND              VIA   -    MD0100PA00X+116427Y+110152X0190Y         S0      
327GND              J15   -242        A01X+116427Y+110152X0205Y0590R090 S1      
317GND              VIA   -    MD0100PA00X+116972Y+109482X0190Y    R180 S0      
327GND              J15   -240        A01X+116427Y+109482X0205Y0590R090 S1      
317GND              VIA   -    MD0100PA00X+069320Y+110486X0190Y         S0      
327GND              J27   -99         A01X+069320Y+110486X0205Y0590R090 S1      
317GND              VIA   -    MD0100PA00X+069320Y+109817X0190Y         S0      
327GND              J27   -97         A01X+069320Y+109817X0205Y0590R090 S1      
317GND              VIA   -    MD0100PA00X+068775Y+109148X0190Y         S0      
327GND              J27   -95         A01X+069320Y+109148X0205Y0590R090 S1      
317GND              VIA   -    MD0100PA00X+068250Y+109482X0190Y    R180 S0      
327GND              J27   -240        A01X+067706Y+109482X0205Y0590R090 S1      
317GND              VIA   -    MD0100PA00X+067706Y+110152X0190Y         S0      
327GND              J27   -242        A01X+067706Y+110152X0205Y0590R090 S1      
317GND              VIA   -    MD0100PA00X+066350Y+110486X0190Y         S0      
327GND              J102  -99         A01X+066350Y+110486X0205Y0590R090 S1      
317GND              VIA   -    MD0100PA00X+066350Y+109817X0190Y         S0      
327GND              J102  -97         A01X+066350Y+109817X0205Y0590R090 S1      
317GND              VIA   -    MD0100PA00X+065805Y+109148X0190Y         S0      
327GND              J102  -95         A01X+066350Y+109148X0205Y0590R090 S1      
317GND              VIA   -    MD0100PA00X+065280Y+109482X0190Y    R180 S0      
327GND              J102  -240        A01X+064735Y+109482X0205Y0590R090 S1      
317GND              VIA   -    MD0100PA00X+064735Y+110152X0190Y         S0      
327GND              J102  -242        A01X+064735Y+110152X0205Y0590R090 S1      
317GND              VIA   -    MD0100PA00X+023397Y+110486X0190Y         S0      
327GND              J24   -99         A01X+023397Y+110486X0205Y0590R090 S1      
317GND              VIA   -    MD0100PA00X+023397Y+109817X0190Y         S0      
327GND              J24   -97         A01X+023397Y+109817X0205Y0590R090 S1      
317GND              VIA   -    MD0100PA00X+022328Y+109482X0190Y    R180 S0      
327GND              J24   -240        A01X+021783Y+109482X0205Y0590R090 S1      
317GND              VIA   -    MD0100PA00X+022852Y+109148X0190Y         S0      
327GND              J24   -95         A01X+023397Y+109148X0205Y0590R090 S1      
317GND              VIA   -    MD0100PA00X+021783Y+110152X0190Y         S0      
327GND              J24   -242        A01X+021783Y+110152X0205Y0590R090 S1      
317GND              VIA   -    MD0100PA00X+020427Y+110486X0190Y         S0      
327GND              J26   -99         A01X+020427Y+110486X0205Y0590R090 S1      
317GND              VIA   -    MD0100PA00X+020427Y+109817X0190Y         S0      
327GND              J26   -97         A01X+020427Y+109817X0205Y0590R090 S1      
317GND              VIA   -    MD0100PA00X+018813Y+110152X0190Y         S0      
327GND              J26   -242        A01X+018813Y+110152X0205Y0590R090 S1      
317GND              VIA   -    MD0100PA00X+019358Y+109482X0190Y    R180 S0      
327GND              J26   -240        A01X+018813Y+109482X0205Y0590R090 S1      
317GND              VIA   -    MD0100PA00X+019882Y+109148X0190Y         S0      
327GND              J26   -95         A01X+020427Y+109148X0205Y0590R090 S1      
317GND              VIA   -    MD0100PA00X+166389Y+108144X0190Y         S0      
327GND              J69   -92         A01X+166934Y+108144X0205Y0590R090 S1      
317GND              VIA   -    MD0100PA00X+167374Y+108646X0190Y         S0      
317GND              VIA   -    MD0100PA00X+165320Y+107809X0190Y         S0      
327GND              J69   -235        A01X+165320Y+107809X0205Y0590R090 S1      
317GND              VIA   -    MD0100PA00X+165865Y+108478X0190Y    R180 S0      
327GND              J69   -237        A01X+165320Y+108478X0205Y0590R090 S1      
317GND              VIA   -    MD0100PA00X+165760Y+108980X0190Y         S0      
317GND              VIA   -    MD0100PA00X+163419Y+108144X0190Y         S0      
327GND              J16   -92         A01X+163964Y+108144X0205Y0590R090 S1      
317GND              VIA   -    MD0100PA00X+164404Y+108646X0190Y         S0      
317GND              VIA   -    MD0100PA00X+162350Y+107809X0190Y         S0      
327GND              J16   -235        A01X+162350Y+107809X0205Y0590R090 S1      
317GND              VIA   -    MD0100PA00X+162895Y+108478X0190Y    R180 S0      
327GND              J16   -237        A01X+162350Y+108478X0205Y0590R090 S1      
317GND              VIA   -    MD0100PA00X+162790Y+108980X0190Y         S0      
317GND              VIA   -    MD0100PA00X+120466Y+108144X0190Y         S0      
327GND              J1    -92         A01X+121011Y+108144X0205Y0590R090 S1      
317GND              VIA   -    MD0100PA00X+120571Y+108646X0190Y         S0      
317GND              VIA   -    MD0100PA00X+119397Y+107809X0190Y         S0      
327GND              J1    -235        A01X+119397Y+107809X0205Y0590R090 S1      
317GND              VIA   -    MD0100PA00X+119942Y+108478X0190Y    R180 S0      
327GND              J1    -237        A01X+119397Y+108478X0205Y0590R090 S1      
317GND              VIA   -    MD0100PA00X+118957Y+108980X0190Y         S0      
317GND              VIA   -    MD0100PA00X+117496Y+108144X0190Y         S0      
327GND              J15   -92         A01X+118041Y+108144X0205Y0590R090 S1      
317GND              VIA   -    MD0100PA00X+117601Y+108646X0190Y         S0      
317GND              VIA   -    MD0100PA00X+116427Y+107809X0190Y         S0      
327GND              J15   -235        A01X+116427Y+107809X0205Y0590R090 S1      
317GND              VIA   -    MD0100PA00X+116972Y+108478X0190Y    R180 S0      
327GND              J15   -237        A01X+116427Y+108478X0205Y0590R090 S1      
317GND              VIA   -    MD0100PA00X+115987Y+108980X0190Y         S0      
317GND              VIA   -    MD0100PA00X+069760Y+108646X0190Y         S0      
317GND              VIA   -    MD0100PA00X+068775Y+108144X0190Y         S0      
327GND              J27   -92         A01X+069320Y+108144X0205Y0590R090 S1      
317GND              VIA   -    MD0100PA00X+068250Y+108478X0190Y    R180 S0      
327GND              J27   -237        A01X+067706Y+108478X0205Y0590R090 S1      
317GND              VIA   -    MD0100PA00X+068146Y+108980X0190Y         S0      
317GND              VIA   -    MD0100PA00X+067706Y+107809X0190Y         S0      
327GND              J27   -235        A01X+067706Y+107809X0205Y0590R090 S1      
317GND              VIA   -    MD0100PA00X+066790Y+108646X0190Y         S0      
317GND              VIA   -    MD0100PA00X+065805Y+108144X0190Y         S0      
327GND              J102  -92         A01X+066350Y+108144X0205Y0590R090 S1      
317GND              VIA   -    MD0100PA00X+065280Y+108478X0190Y    R180 S0      
327GND              J102  -237        A01X+064735Y+108478X0205Y0590R090 S1      
317GND              VIA   -    MD0100PA00X+065175Y+108980X0190Y         S0      
317GND              VIA   -    MD0100PA00X+064735Y+107809X0190Y         S0      
327GND              J102  -235        A01X+064735Y+107809X0205Y0590R090 S1      
317GND              VIA   -    MD0100PA00X+021783Y+107809X0190Y         S0      
327GND              J24   -235        A01X+021783Y+107809X0205Y0590R090 S1      
317GND              VIA   -    MD0100PA00X+022852Y+108144X0190Y         S0      
327GND              J24   -92         A01X+023397Y+108144X0205Y0590R090 S1      
317GND              VIA   -    MD0100PA00X+022328Y+108478X0190Y    R180 S0      
327GND              J24   -237        A01X+021783Y+108478X0205Y0590R090 S1      
317GND              VIA   -    MD0100PA00X+022957Y+108646X0190Y         S0      
317GND              VIA   -    MD0100PA00X+021343Y+108980X0190Y         S0      
317GND              VIA   -    MD0100PA00X+018813Y+107809X0190Y         S0      
327GND              J26   -235        A01X+018813Y+107809X0205Y0590R090 S1      
317GND              VIA   -    MD0100PA00X+019882Y+108144X0190Y         S0      
327GND              J26   -92         A01X+020427Y+108144X0205Y0590R090 S1      
317GND              VIA   -    MD0100PA00X+019358Y+108478X0190Y    R180 S0      
327GND              J26   -237        A01X+018813Y+108478X0205Y0590R090 S1      
317GND              VIA   -    MD0100PA00X+019987Y+108646X0190Y         S0      
317GND              VIA   -    MD0100PA00X+018373Y+108980X0190Y         S0      
317GND              VIA   -    MD0100PA00X+166934Y+107474X0190Y         S0      
327GND              J69   -90         A01X+166934Y+107474X0205Y0590R090 S1      
317GND              VIA   -    MD0100PA00X+166934Y+106805X0190Y         S0      
327GND              J69   -88         A01X+166934Y+106805X0205Y0590R090 S1      
317GND              VIA   -    MD0100PA00X+165320Y+107140X0190Y         S0      
327GND              J69   -233        A01X+165320Y+107140X0205Y0590R090 S1      
317GND              VIA   -    MD0100PA00X+165320Y+106136X0190Y         S0      
327GND              J69   -230        A01X+165320Y+106136X0205Y0590R090 S1      
317GND              VIA   -    MD0100PA00X+163964Y+107474X0190Y         S0      
327GND              J16   -90         A01X+163964Y+107474X0205Y0590R090 S1      
317GND              VIA   -    MD0100PA00X+163964Y+106805X0190Y         S0      
327GND              J16   -88         A01X+163964Y+106805X0205Y0590R090 S1      
317GND              VIA   -    MD0100PA00X+162350Y+107140X0190Y         S0      
327GND              J16   -233        A01X+162350Y+107140X0205Y0590R090 S1      
317GND              VIA   -    MD0100PA00X+162350Y+106136X0190Y         S0      
327GND              J16   -230        A01X+162350Y+106136X0205Y0590R090 S1      
317GND              VIA   -    MD0100PA00X+121011Y+107474X0190Y         S0      
327GND              J1    -90         A01X+121011Y+107474X0205Y0590R090 S1      
317GND              VIA   -    MD0100PA00X+121011Y+106805X0190Y         S0      
327GND              J1    -88         A01X+121011Y+106805X0205Y0590R090 S1      
317GND              VIA   -    MD0100PA00X+119397Y+107140X0190Y         S0      
327GND              J1    -233        A01X+119397Y+107140X0205Y0590R090 S1      
317GND              VIA   -    MD0100PA00X+119397Y+106136X0190Y         S0      
327GND              J1    -230        A01X+119397Y+106136X0205Y0590R090 S1      
317GND              VIA   -    MD0100PA00X+118041Y+107474X0190Y         S0      
327GND              J15   -90         A01X+118041Y+107474X0205Y0590R090 S1      
317GND              VIA   -    MD0100PA00X+118041Y+106805X0190Y         S0      
327GND              J15   -88         A01X+118041Y+106805X0205Y0590R090 S1      
317GND              VIA   -    MD0100PA00X+116427Y+107140X0190Y         S0      
327GND              J15   -233        A01X+116427Y+107140X0205Y0590R090 S1      
317GND              VIA   -    MD0100PA00X+116427Y+106136X0190Y         S0      
327GND              J15   -230        A01X+116427Y+106136X0205Y0590R090 S1      
317GND              VIA   -    MD0100PA00X+069320Y+107474X0190Y         S0      
327GND              J27   -90         A01X+069320Y+107474X0205Y0590R090 S1      
317GND              VIA   -    MD0100PA00X+069320Y+106805X0190Y         S0      
327GND              J27   -88         A01X+069320Y+106805X0205Y0590R090 S1      
317GND              VIA   -    MD0100PA00X+067706Y+107140X0190Y         S0      
327GND              J27   -233        A01X+067706Y+107140X0205Y0590R090 S1      
317GND              VIA   -    MD0100PA00X+067706Y+106136X0190Y         S0      
327GND              J27   -230        A01X+067706Y+106136X0205Y0590R090 S1      
317GND              VIA   -    MD0100PA00X+066350Y+107474X0190Y         S0      
327GND              J102  -90         A01X+066350Y+107474X0205Y0590R090 S1      
317GND              VIA   -    MD0100PA00X+066350Y+106805X0190Y         S0      
327GND              J102  -88         A01X+066350Y+106805X0205Y0590R090 S1      
317GND              VIA   -    MD0100PA00X+064735Y+107140X0190Y         S0      
327GND              J102  -233        A01X+064735Y+107140X0205Y0590R090 S1      
317GND              VIA   -    MD0100PA00X+064735Y+106136X0190Y         S0      
327GND              J102  -230        A01X+064735Y+106136X0205Y0590R090 S1      
317GND              VIA   -    MD0100PA00X+023397Y+107474X0190Y         S0      
327GND              J24   -90         A01X+023397Y+107474X0205Y0590R090 S1      
317GND              VIA   -    MD0100PA00X+023397Y+106805X0190Y         S0      
327GND              J24   -88         A01X+023397Y+106805X0205Y0590R090 S1      
317GND              VIA   -    MD0100PA00X+021783Y+107140X0190Y         S0      
327GND              J24   -233        A01X+021783Y+107140X0205Y0590R090 S1      
317GND              VIA   -    MD0100PA00X+021783Y+106136X0190Y         S0      
327GND              J24   -230        A01X+021783Y+106136X0205Y0590R090 S1      
317GND              VIA   -    MD0100PA00X+020427Y+107474X0190Y         S0      
327GND              J26   -90         A01X+020427Y+107474X0205Y0590R090 S1      
317GND              VIA   -    MD0100PA00X+020427Y+106805X0190Y         S0      
327GND              J26   -88         A01X+020427Y+106805X0205Y0590R090 S1      
317GND              VIA   -    MD0100PA00X+018813Y+107140X0190Y         S0      
327GND              J26   -233        A01X+018813Y+107140X0205Y0590R090 S1      
317GND              VIA   -    MD0100PA00X+018813Y+106136X0190Y         S0      
327GND              J26   -230        A01X+018813Y+106136X0205Y0590R090 S1      
317GND              VIA   -    MD0100PA00X+166934Y+105801X0190Y         S0      
327GND              J69   -85         A01X+166934Y+105801X0205Y0590R090 S1      
317GND              VIA   -    MD0100PA00X+166934Y+105132X0190Y         S0      
327GND              J69   -83         A01X+166934Y+105132X0205Y0590R090 S1      
317GND              VIA   -    MD0100PA00X+165320Y+105467X0190Y         S0      
327GND              J69   -228        A01X+165320Y+105467X0205Y0590R090 S1      
317GND              VIA   -    MD0100PA00X+165320Y+104797X0190Y         S0      
327GND              J69   -226        A01X+165320Y+104797X0205Y0590R090 S1      
317GND              VIA   -    MD0100PA00X+163964Y+105801X0190Y         S0      
327GND              J16   -85         A01X+163964Y+105801X0205Y0590R090 S1      
317GND              VIA   -    MD0100PA00X+163964Y+105132X0190Y         S0      
327GND              J16   -83         A01X+163964Y+105132X0205Y0590R090 S1      
317GND              VIA   -    MD0100PA00X+162350Y+105467X0190Y         S0      
327GND              J16   -228        A01X+162350Y+105467X0205Y0590R090 S1      
317GND              VIA   -    MD0100PA00X+162350Y+104797X0190Y         S0      
327GND              J16   -226        A01X+162350Y+104797X0205Y0590R090 S1      
317GND              VIA   -    MD0100PA00X+141730Y+105514X0190Y    R270 S0      
317GND              VIA   -    MD0100PA00X+121011Y+105801X0190Y         S0      
327GND              J1    -85         A01X+121011Y+105801X0205Y0590R090 S1      
317GND              VIA   -    MD0100PA00X+121011Y+105132X0190Y         S0      
327GND              J1    -83         A01X+121011Y+105132X0205Y0590R090 S1      
317GND              VIA   -    MD0100PA00X+119397Y+105467X0190Y         S0      
327GND              J1    -228        A01X+119397Y+105467X0205Y0590R090 S1      
317GND              VIA   -    MD0100PA00X+119397Y+104797X0190Y         S0      
327GND              J1    -226        A01X+119397Y+104797X0205Y0590R090 S1      
317GND              VIA   -    MD0100PA00X+118041Y+105801X0190Y         S0      
327GND              J15   -85         A01X+118041Y+105801X0205Y0590R090 S1      
317GND              VIA   -    MD0100PA00X+118041Y+105132X0190Y         S0      
327GND              J15   -83         A01X+118041Y+105132X0205Y0590R090 S1      
317GND              VIA   -    MD0100PA00X+116427Y+105467X0190Y         S0      
327GND              J15   -228        A01X+116427Y+105467X0205Y0590R090 S1      
317GND              VIA   -    MD0100PA00X+116427Y+104797X0190Y         S0      
327GND              J15   -226        A01X+116427Y+104797X0205Y0590R090 S1      
317GND              VIA   -    MD0100PA00X+069320Y+105801X0190Y         S0      
327GND              J27   -85         A01X+069320Y+105801X0205Y0590R090 S1      
317GND              VIA   -    MD0100PA00X+069320Y+105132X0190Y         S0      
327GND              J27   -83         A01X+069320Y+105132X0205Y0590R090 S1      
317GND              VIA   -    MD0100PA00X+067706Y+105467X0190Y         S0      
327GND              J27   -228        A01X+067706Y+105467X0205Y0590R090 S1      
317GND              VIA   -    MD0100PA00X+066350Y+105801X0190Y         S0      
327GND              J102  -85         A01X+066350Y+105801X0205Y0590R090 S1      
317GND              VIA   -    MD0100PA00X+066350Y+105132X0190Y         S0      
327GND              J102  -83         A01X+066350Y+105132X0205Y0590R090 S1      
317GND              VIA   -    MD0100PA00X+064735Y+105467X0190Y         S0      
327GND              J102  -228        A01X+064735Y+105467X0205Y0590R090 S1      
317GND              VIA   -    MD0100PA00X+064735Y+104797X0190Y         S0      
327GND              J102  -226        A01X+064735Y+104797X0205Y0590R090 S1      
317GND              VIA   -    MD0100PA00X+044116Y+105514X0190Y    R270 S0      
317GND              VIA   -    MD0100PA00X+023397Y+105801X0190Y         S0      
327GND              J24   -85         A01X+023397Y+105801X0205Y0590R090 S1      
317GND              VIA   -    MD0100PA00X+023397Y+105132X0190Y         S0      
327GND              J24   -83         A01X+023397Y+105132X0205Y0590R090 S1      
317GND              VIA   -    MD0100PA00X+021783Y+105467X0190Y         S0      
327GND              J24   -228        A01X+021783Y+105467X0205Y0590R090 S1      
317GND              VIA   -    MD0100PA00X+021783Y+104797X0190Y         S0      
327GND              J24   -226        A01X+021783Y+104797X0205Y0590R090 S1      
317GND              VIA   -    MD0100PA00X+020427Y+105801X0190Y         S0      
327GND              J26   -85         A01X+020427Y+105801X0205Y0590R090 S1      
317GND              VIA   -    MD0100PA00X+020427Y+105132X0190Y         S0      
327GND              J26   -83         A01X+020427Y+105132X0205Y0590R090 S1      
317GND              VIA   -    MD0100PA00X+018813Y+105467X0190Y         S0      
327GND              J26   -228        A01X+018813Y+105467X0205Y0590R090 S1      
317GND              VIA   -    MD0100PA00X+018813Y+104797X0190Y         S0      
327GND              J26   -226        A01X+018813Y+104797X0205Y0590R090 S1      
317GND              VIA   -    MD0100PA00X+166934Y+104463X0190Y         S0      
327GND              J69   -81         A01X+166934Y+104463X0205Y0590R090 S1      
317GND              VIA   -    MD0100PA00X+166934Y+103793X0190Y         S0      
327GND              J69   -79         A01X+166934Y+103793X0205Y0590R090 S1      
317GND              VIA   -    MD0100PA00X+166934Y+103124X0190Y         S0      
327GND              J69   -77         A01X+166934Y+103124X0205Y0590R090 S1      
317GND              VIA   -    MD0100PA00X+165320Y+104128X0190Y         S0      
327GND              J69   -224        A01X+165320Y+104128X0205Y0590R090 S1      
317GND              VIA   -    MD0100PA00X+165320Y+103459X0190Y         S0      
327GND              J69   -222        A01X+165320Y+103459X0205Y0590R090 S1      
317GND              VIA   -    MD0100PA00X+163964Y+104463X0190Y         S0      
327GND              J16   -81         A01X+163964Y+104463X0205Y0590R090 S1      
317GND              VIA   -    MD0100PA00X+163964Y+103793X0190Y         S0      
327GND              J16   -79         A01X+163964Y+103793X0205Y0590R090 S1      
317GND              VIA   -    MD0100PA00X+163964Y+103124X0190Y         S0      
327GND              J16   -77         A01X+163964Y+103124X0205Y0590R090 S1      
317GND              VIA   -    MD0100PA00X+162350Y+104128X0190Y         S0      
327GND              J16   -224        A01X+162350Y+104128X0205Y0590R090 S1      
317GND              VIA   -    MD0100PA00X+162350Y+103459X0190Y         S0      
327GND              J16   -222        A01X+162350Y+103459X0205Y0590R090 S1      
317GND              VIA   -    MD0100PA00X+143851Y+103220X0190Y    R270 S0      
317GND              VIA   -    MD0100PA00X+141543Y+103876X0190Y         S0      
317GND              VIA   -    MD0100PA00X+141543Y+104276X0190Y         S0      
317GND              VIA   -    MD0100PA00X+139146Y+103220X0190Y    R270 S0      
317GND              VIA   -    MD0100PA00X+121011Y+104463X0190Y         S0      
327GND              J1    -81         A01X+121011Y+104463X0205Y0590R090 S1      
317GND              VIA   -    MD0100PA00X+121011Y+103793X0190Y         S0      
327GND              J1    -79         A01X+121011Y+103793X0205Y0590R090 S1      
317GND              VIA   -    MD0100PA00X+121011Y+103124X0190Y         S0      
327GND              J1    -77         A01X+121011Y+103124X0205Y0590R090 S1      
317GND              VIA   -    MD0100PA00X+119397Y+104128X0190Y         S0      
327GND              J1    -224        A01X+119397Y+104128X0205Y0590R090 S1      
317GND              VIA   -    MD0100PA00X+119397Y+103459X0190Y         S0      
327GND              J1    -222        A01X+119397Y+103459X0205Y0590R090 S1      
317GND              VIA   -    MD0100PA00X+118041Y+104463X0190Y         S0      
327GND              J15   -81         A01X+118041Y+104463X0205Y0590R090 S1      
317GND              VIA   -    MD0100PA00X+118041Y+103793X0190Y         S0      
327GND              J15   -79         A01X+118041Y+103793X0205Y0590R090 S1      
317GND              VIA   -    MD0100PA00X+118041Y+103124X0190Y         S0      
327GND              J15   -77         A01X+118041Y+103124X0205Y0590R090 S1      
317GND              VIA   -    MD0100PA00X+116427Y+104128X0190Y         S0      
327GND              J15   -224        A01X+116427Y+104128X0205Y0590R090 S1      
317GND              VIA   -    MD0100PA00X+116427Y+103459X0190Y         S0      
327GND              J15   -222        A01X+116427Y+103459X0205Y0590R090 S1      
317GND              VIA   -    MD0100PA00X+064735Y+104128X0190Y         S0      
327GND              J102  -224        A01X+064735Y+104128X0205Y0590R090 S1      
317GND              VIA   -    MD0100PA00X+064735Y+103459X0190Y         S0      
327GND              J102  -222        A01X+064735Y+103459X0205Y0590R090 S1      
317GND              VIA   -    MD0100PA00X+046236Y+103221X0190Y    R270 S0      
317GND              VIA   -    MD0100PA00X+043928Y+104277X0190Y         S0      
317GND              VIA   -    MD0100PA00X+043928Y+103877X0190Y         S0      
317GND              VIA   -    MD0100PA00X+041532Y+103221X0190Y    R270 S0      
317GND              VIA   -    MD0100PA00X+023397Y+104463X0190Y         S0      
327GND              J24   -81         A01X+023397Y+104463X0205Y0590R090 S1      
317GND              VIA   -    MD0100PA00X+023397Y+103793X0190Y         S0      
327GND              J24   -79         A01X+023397Y+103793X0205Y0590R090 S1      
317GND              VIA   -    MD0100PA00X+023397Y+103124X0190Y         S0      
327GND              J24   -77         A01X+023397Y+103124X0205Y0590R090 S1      
317GND              VIA   -    MD0100PA00X+021783Y+104128X0190Y         S0      
327GND              J24   -224        A01X+021783Y+104128X0205Y0590R090 S1      
317GND              VIA   -    MD0100PA00X+021783Y+103459X0190Y         S0      
327GND              J24   -222        A01X+021783Y+103459X0205Y0590R090 S1      
317GND              VIA   -    MD0100PA00X+020427Y+104463X0190Y         S0      
327GND              J26   -81         A01X+020427Y+104463X0205Y0590R090 S1      
317GND              VIA   -    MD0100PA00X+020427Y+103793X0190Y         S0      
327GND              J26   -79         A01X+020427Y+103793X0205Y0590R090 S1      
317GND              VIA   -    MD0100PA00X+020427Y+103124X0190Y         S0      
327GND              J26   -77         A01X+020427Y+103124X0205Y0590R090 S1      
317GND              VIA   -    MD0100PA00X+018813Y+104128X0190Y         S0      
327GND              J26   -224        A01X+018813Y+104128X0205Y0590R090 S1      
317GND              VIA   -    MD0100PA00X+018813Y+103459X0190Y         S0      
327GND              J26   -222        A01X+018813Y+103459X0205Y0590R090 S1      
317GND              J69   -G2  MD0480PA00X+166127Y+102140X0680Y1370R090 S3      
317GND              J16   -G2  MD0480PA00X+163157Y+102140X0680Y1370R090 S3      
317GND              VIA   -    MD0100PA00X+146793Y+102256X0190Y         S0      
317GND              VIA   -    MD0100PA00X+146793Y+101902X0190Y         S0      
317GND              VIA   -    MD0100PA00X+146093Y+102256X0190Y         S0      
317GND              VIA   -    MD0100PA00X+146093Y+101902X0190Y         S0      
317GND              VIA   -    MD0100PA00X+145334Y+102256X0190Y         S0      
317GND              VIA   -    MD0100PA00X+145334Y+101902X0190Y         S0      
317GND              VIA   -    MD0100PA00X+143361Y+102883X0190Y    R180 S0      
317GND              VIA   -    MD0100PA00X+142613Y+102883X0190Y    R180 S0      
317GND              VIA   -    MD0100PA00X+143355Y+102301X0190Y    R180 S0      
317GND              VIA   -    MD0100PA00X+143851Y+102846X0190Y    R270 S0      
317GND              VIA   -    MD0100PA00X+143355Y+101888X0190Y    R180 S0      
317GND              VIA   -    MD0100PA00X+143851Y+101724X0190Y    R270 S0      
317GND              VIA   -    MD0100PA00X+142987Y+102883X0190Y    R180 S0      
317GND              VIA   -    MD0100PA00X+143851Y+102098X0190Y    R270 S0      
317GND              VIA   -    MD0100PA00X+143851Y+102472X0190Y    R270 S0      
317GND              VIA   -    MD0100PA00X+141446Y+101888X0190Y    R180 S0      
317GND              VIA   -    MD0100PA00X+142239Y+102883X0190Y    R180 S0      
317GND              VIA   -    MD0100PA00X+142332Y+101888X0190Y    R180 S0      
317GND              VIA   -    MD0100PA00X+142332Y+102301X0190Y    R180 S0      
317GND              VIA   -    MD0100PA00X+141491Y+102883X0190Y    R180 S0      
317GND              VIA   -    MD0100PA00X+141117Y+102883X0190Y    R180 S0      
317GND              VIA   -    MD0100PA00X+141865Y+102883X0190Y    R180 S0      
317GND              VIA   -    MD0100PA00X+141446Y+102301X0190Y    R180 S0      
317GND              VIA   -    MD0100PA00X+140369Y+102883X0190Y    R180 S0      
317GND              VIA   -    MD0100PA00X+140462Y+101888X0190Y    R180 S0      
317GND              VIA   -    MD0100PA00X+139506Y+101724X0190Y    R270 S0      
317GND              VIA   -    MD0100PA00X+139506Y+102846X0190Y    R270 S0      
317GND              VIA   -    MD0100PA00X+139506Y+102472X0190Y    R270 S0      
317GND              VIA   -    MD0100PA00X+139506Y+102098X0190Y    R270 S0      
317GND              VIA   -    MD0100PA00X+140462Y+102301X0190Y    R180 S0      
317GND              VIA   -    MD0100PA00X+140743Y+102883X0190Y    R180 S0      
317GND              VIA   -    MD0100PA00X+139995Y+102883X0190Y    R180 S0      
317GND              VIA   -    MD0100PA00X+138108Y+101902X0190Y    R180 S0      
317GND              VIA   -    MD0100PA00X+138108Y+102256X0190Y    R180 S0      
317GND              VIA   -    MD0100PA00X+136612Y+101902X0190Y    R180 S0      
317GND              VIA   -    MD0100PA00X+136612Y+102256X0190Y    R180 S0      
317GND              VIA   -    MD0100PA00X+137360Y+102256X0190Y    R180 S0      
317GND              VIA   -    MD0100PA00X+137360Y+101902X0190Y    R180 S0      
317GND              J1    -G2  MD0480PA00X+120204Y+102140X0680Y1370R090 S3      
317GND              J15   -G2  MD0480PA00X+117234Y+102140X0680Y1370R090 S3      
317GND              VIA   -    MD0100PA00X+049228Y+102256X0190Y         S0      
317GND              VIA   -    MD0100PA00X+049228Y+101902X0190Y         S0      
317GND              VIA   -    MD0100PA00X+048478Y+102256X0190Y         S0      
317GND              VIA   -    MD0100PA00X+047720Y+102256X0190Y         S0      
317GND              VIA   -    MD0100PA00X+048478Y+101902X0190Y         S0      
317GND              VIA   -    MD0100PA00X+047720Y+101902X0190Y         S0      
317GND              VIA   -    MD0100PA00X+045747Y+102883X0190Y    R180 S0      
317GND              VIA   -    MD0100PA00X+045741Y+102301X0190Y    R180 S0      
317GND              VIA   -    MD0100PA00X+046236Y+101724X0190Y    R270 S0      
317GND              VIA   -    MD0100PA00X+046236Y+102473X0190Y    R270 S0      
317GND              VIA   -    MD0100PA00X+046236Y+102847X0190Y    R270 S0      
317GND              VIA   -    MD0100PA00X+045741Y+101888X0190Y    R180 S0      
317GND              VIA   -    MD0100PA00X+046236Y+102099X0190Y    R270 S0      
317GND              VIA   -    MD0100PA00X+044717Y+101888X0190Y    R180 S0      
317GND              VIA   -    MD0100PA00X+044251Y+102883X0190Y    R180 S0      
317GND              VIA   -    MD0100PA00X+044717Y+102301X0190Y    R180 S0      
317GND              VIA   -    MD0100PA00X+044999Y+102883X0190Y    R180 S0      
317GND              VIA   -    MD0100PA00X+045373Y+102883X0190Y    R180 S0      
317GND              VIA   -    MD0100PA00X+044625Y+102883X0190Y    R180 S0      
317GND              VIA   -    MD0100PA00X+043129Y+102883X0190Y    R180 S0      
317GND              VIA   -    MD0100PA00X+042847Y+102301X0190Y    R180 S0      
317GND              VIA   -    MD0100PA00X+042847Y+101888X0190Y    R180 S0      
317GND              VIA   -    MD0100PA00X+043832Y+101888X0190Y    R180 S0      
317GND              VIA   -    MD0100PA00X+043503Y+102883X0190Y    R180 S0      
317GND              VIA   -    MD0100PA00X+042755Y+102883X0190Y    R180 S0      
317GND              VIA   -    MD0100PA00X+043832Y+102301X0190Y    R180 S0      
317GND              VIA   -    MD0100PA00X+043877Y+102883X0190Y    R180 S0      
317GND              VIA   -    MD0100PA00X+042381Y+102883X0190Y    R180 S0      
317GND              VIA   -    MD0100PA00X+041892Y+101724X0190Y    R270 S0      
317GND              VIA   -    MD0100PA00X+041892Y+102847X0190Y    R270 S0      
317GND              VIA   -    MD0100PA00X+041892Y+102099X0190Y    R270 S0      
317GND              VIA   -    MD0100PA00X+041892Y+102473X0190Y    R270 S0      
317GND              VIA   -    MD0100PA00X+039746Y+101902X0190Y    R180 S0      
317GND              VIA   -    MD0100PA00X+040494Y+102256X0190Y    R180 S0      
317GND              VIA   -    MD0100PA00X+040494Y+101902X0190Y    R180 S0      
317GND              VIA   -    MD0100PA00X+039746Y+102256X0190Y    R180 S0      
317GND              VIA   -    MD0100PA00X+038998Y+101902X0190Y    R180 S0      
317GND              VIA   -    MD0100PA00X+038998Y+102256X0190Y    R180 S0      
317GND              J24   -G2  MD0480PA00X+022590Y+102140X0680Y1370R090 S3      
317GND              J26   -G2  MD0480PA00X+019620Y+102140X0680Y1370R090 S3      
317GND              VIA   -    MD0100PA00X+166934Y+100447X0190Y         S0      
327GND              J69   -75         A01X+166934Y+100447X0205Y0590R090 S1      
317GND              VIA   -    MD0100PA00X+165320Y+100447X0190Y         S0      
327GND              J69   -219        A01X+165320Y+100447X0205Y0590R090 S1      
317GND              VIA   -    MD0100PA00X+163964Y+100447X0190Y         S0      
327GND              J16   -75         A01X+163964Y+100447X0205Y0590R090 S1      
317GND              VIA   -    MD0100PA00X+162350Y+100447X0190Y         S0      
327GND              J16   -219        A01X+162350Y+100447X0205Y0590R090 S1      
317GND              VIA   -    MD0100PA00X+146793Y+101547X0190Y         S0      
317GND              VIA   -    MD0100PA00X+146093Y+101547X0190Y         S0      
317GND              VIA   -    MD0100PA00X+145334Y+101547X0190Y         S0      
317GND              VIA   -    MD0100PA00X+143355Y+101474X0190Y    R180 S0      
317GND              VIA   -    MD0100PA00X+143851Y+101350X0190Y    R270 S0      
317GND              VIA   -    MD0100PA00X+143851Y+100976X0190Y    R270 S0      
317GND              VIA   -    MD0100PA00X+142987Y+100940X0190Y    R180 S0      
317GND              VIA   -    MD0100PA00X+142613Y+100940X0190Y    R180 S0      
317GND              VIA   -    MD0100PA00X+143361Y+100940X0190Y    R180 S0      
317GND              VIA   -    MD0100PA00X+143851Y+100602X0190Y    R270 S0      
317GND              VIA   -    MD0100PA00X+141446Y+101474X0190Y    R180 S0      
317GND              VIA   -    MD0100PA00X+142332Y+101474X0190Y    R180 S0      
317GND              VIA   -    MD0100PA00X+141117Y+100940X0190Y    R180 S0      
317GND              VIA   -    MD0100PA00X+141491Y+100940X0190Y    R180 S0      
317GND              VIA   -    MD0100PA00X+142239Y+100940X0190Y    R180 S0      
317GND              VIA   -    MD0100PA00X+141810Y+100176X0190Y    R180 S0      
317GND              VIA   -    MD0100PA00X+141865Y+100940X0190Y    R180 S0      
317GND              VIA   -    MD0100PA00X+140462Y+101474X0190Y    R180 S0      
317GND              VIA   -    MD0100PA00X+139506Y+101350X0190Y    R270 S0      
317GND              VIA   -    MD0100PA00X+139995Y+100940X0190Y    R180 S0      
317GND              VIA   -    MD0100PA00X+140743Y+100940X0190Y    R180 S0      
317GND              VIA   -    MD0100PA00X+140369Y+100940X0190Y    R180 S0      
317GND              VIA   -    MD0100PA00X+139506Y+100602X0190Y    R270 S0      
317GND              VIA   -    MD0100PA00X+139506Y+100976X0190Y    R270 S0      
317GND              VIA   -    MD0100PA00X+138108Y+101547X0190Y    R180 S0      
317GND              VIA   -    MD0100PA00X+137360Y+101547X0190Y    R180 S0      
317GND              VIA   -    MD0100PA00X+136612Y+101547X0190Y    R180 S0      
317GND              VIA   -    MD0100PA00X+121011Y+100447X0190Y         S0      
327GND              J1    -75         A01X+121011Y+100447X0205Y0590R090 S1      
317GND              VIA   -    MD0100PA00X+119397Y+100447X0190Y         S0      
327GND              J1    -219        A01X+119397Y+100447X0205Y0590R090 S1      
317GND              VIA   -    MD0100PA00X+118041Y+100447X0190Y         S0      
327GND              J15   -75         A01X+118041Y+100447X0205Y0590R090 S1      
317GND              VIA   -    MD0100PA00X+116427Y+100447X0190Y         S0      
327GND              J15   -219        A01X+116427Y+100447X0205Y0590R090 S1      
317GND              VIA   -    MD0100PA00X+064735Y+100447X0190Y         S0      
327GND              J102  -219        A01X+064735Y+100447X0205Y0590R090 S1      
317GND              VIA   -    MD0100PA00X+049228Y+101547X0190Y         S0      
317GND              VIA   -    MD0100PA00X+048478Y+101547X0190Y         S0      
317GND              VIA   -    MD0100PA00X+047720Y+101547X0190Y         S0      
317GND              VIA   -    MD0100PA00X+046236Y+101350X0190Y    R270 S0      
317GND              VIA   -    MD0100PA00X+046236Y+100976X0190Y    R270 S0      
317GND              VIA   -    MD0100PA00X+045741Y+101474X0190Y    R180 S0      
317GND              VIA   -    MD0100PA00X+046236Y+100602X0190Y    R270 S0      
317GND              VIA   -    MD0100PA00X+045747Y+100940X0190Y    R180 S0      
317GND              VIA   -    MD0100PA00X+044717Y+101474X0190Y    R180 S0      
317GND              VIA   -    MD0100PA00X+044196Y+100177X0190Y    R180 S0      
317GND              VIA   -    MD0100PA00X+045373Y+100940X0190Y    R180 S0      
317GND              VIA   -    MD0100PA00X+044625Y+100940X0190Y    R180 S0      
317GND              VIA   -    MD0100PA00X+044999Y+100940X0190Y    R180 S0      
317GND              VIA   -    MD0100PA00X+044251Y+100940X0190Y    R180 S0      
317GND              VIA   -    MD0100PA00X+042847Y+101474X0190Y    R180 S0      
317GND              VIA   -    MD0100PA00X+043877Y+100940X0190Y    R180 S0      
317GND              VIA   -    MD0100PA00X+043503Y+100940X0190Y    R180 S0      
317GND              VIA   -    MD0100PA00X+042755Y+100940X0190Y    R180 S0      
317GND              VIA   -    MD0100PA00X+043832Y+101474X0190Y    R180 S0      
317GND              VIA   -    MD0100PA00X+043129Y+100940X0190Y    R180 S0      
317GND              VIA   -    MD0100PA00X+041892Y+100976X0190Y    R270 S0      
317GND              VIA   -    MD0100PA00X+042381Y+100940X0190Y    R180 S0      
317GND              VIA   -    MD0100PA00X+041892Y+101350X0190Y    R270 S0      
317GND              VIA   -    MD0100PA00X+041892Y+100602X0190Y    R270 S0      
317GND              VIA   -    MD0100PA00X+040494Y+101547X0190Y    R180 S0      
317GND              VIA   -    MD0100PA00X+039746Y+101547X0190Y    R180 S0      
317GND              VIA   -    MD0100PA00X+038998Y+101547X0190Y    R180 S0      
317GND              VIA   -    MD0100PA00X+023397Y+100447X0190Y         S0      
327GND              J24   -75         A01X+023397Y+100447X0205Y0590R090 S1      
317GND              VIA   -    MD0100PA00X+021783Y+100447X0190Y         S0      
327GND              J24   -219        A01X+021783Y+100447X0205Y0590R090 S1      
317GND              VIA   -    MD0100PA00X+020427Y+100447X0190Y         S0      
327GND              J26   -75         A01X+020427Y+100447X0205Y0590R090 S1      
317GND              VIA   -    MD0100PA00X+018813Y+100447X0190Y         S0      
327GND              J26   -219        A01X+018813Y+100447X0205Y0590R090 S1      
317GND              VIA   -    MD0100PA00X+166934Y+099778X0190Y         S0      
327GND              J69   -73         A01X+166934Y+099778X0205Y0590R090 S1      
317GND              VIA   -    MD0100PA00X+166934Y+099108X0190Y         S0      
327GND              J69   -71         A01X+166934Y+099108X0205Y0590R090 S1      
317GND              VIA   -    MD0100PA00X+165320Y+099443X0190Y         S0      
327GND              J69   -216        A01X+165320Y+099443X0205Y0590R090 S1      
317GND              VIA   -    MD0100PA00X+165320Y+098774X0190Y         S0      
327GND              J69   -214        A01X+165320Y+098774X0205Y0590R090 S1      
317GND              VIA   -    MD0100PA00X+163964Y+099778X0190Y         S0      
327GND              J16   -73         A01X+163964Y+099778X0205Y0590R090 S1      
317GND              VIA   -    MD0100PA00X+163964Y+099108X0190Y         S0      
327GND              J16   -71         A01X+163964Y+099108X0205Y0590R090 S1      
317GND              VIA   -    MD0100PA00X+162350Y+099443X0190Y         S0      
327GND              J16   -216        A01X+162350Y+099443X0205Y0590R090 S1      
317GND              VIA   -    MD0100PA00X+162350Y+098774X0190Y         S0      
327GND              J16   -214        A01X+162350Y+098774X0205Y0590R090 S1      
317GND              VIA   -    MD0100PA00X+141818Y+098976X0190Y    R180 S0      
317GND              VIA   -    MD0100PA00X+141810Y+099376X0190Y    R180 S0      
317GND              VIA   -    MD0100PA00X+141810Y+099776X0190Y    R180 S0      
317GND              VIA   -    MD0100PA00X+121011Y+099778X0190Y         S0      
327GND              J1    -73         A01X+121011Y+099778X0205Y0590R090 S1      
317GND              VIA   -    MD0100PA00X+121011Y+099108X0190Y         S0      
327GND              J1    -71         A01X+121011Y+099108X0205Y0590R090 S1      
317GND              VIA   -    MD0100PA00X+119397Y+099443X0190Y         S0      
327GND              J1    -216        A01X+119397Y+099443X0205Y0590R090 S1      
317GND              VIA   -    MD0100PA00X+119397Y+098774X0190Y         S0      
327GND              J1    -214        A01X+119397Y+098774X0205Y0590R090 S1      
317GND              VIA   -    MD0100PA00X+118041Y+099778X0190Y         S0      
327GND              J15   -73         A01X+118041Y+099778X0205Y0590R090 S1      
317GND              VIA   -    MD0100PA00X+118041Y+099108X0190Y         S0      
327GND              J15   -71         A01X+118041Y+099108X0205Y0590R090 S1      
317GND              VIA   -    MD0100PA00X+116427Y+099443X0190Y         S0      
327GND              J15   -216        A01X+116427Y+099443X0205Y0590R090 S1      
317GND              VIA   -    MD0100PA00X+116427Y+098774X0190Y         S0      
327GND              J15   -214        A01X+116427Y+098774X0205Y0590R090 S1      
317GND              VIA   -    MD0100PA00X+064735Y+099443X0190Y         S0      
327GND              J102  -216        A01X+064735Y+099443X0205Y0590R090 S1      
317GND              VIA   -    MD0100PA00X+064735Y+098774X0190Y         S0      
327GND              J102  -214        A01X+064735Y+098774X0205Y0590R090 S1      
317GND              VIA   -    MD0100PA00X+044203Y+098977X0190Y    R180 S0      
317GND              VIA   -    MD0100PA00X+044196Y+099777X0190Y    R180 S0      
317GND              VIA   -    MD0100PA00X+044196Y+099377X0190Y    R180 S0      
317GND              VIA   -    MD0100PA00X+023397Y+099778X0190Y         S0      
327GND              J24   -73         A01X+023397Y+099778X0205Y0590R090 S1      
317GND              VIA   -    MD0100PA00X+023397Y+099108X0190Y         S0      
327GND              J24   -71         A01X+023397Y+099108X0205Y0590R090 S1      
317GND              VIA   -    MD0100PA00X+021783Y+099443X0190Y         S0      
327GND              J24   -216        A01X+021783Y+099443X0205Y0590R090 S1      
317GND              VIA   -    MD0100PA00X+021783Y+098774X0190Y         S0      
327GND              J24   -214        A01X+021783Y+098774X0205Y0590R090 S1      
317GND              VIA   -    MD0100PA00X+020427Y+099778X0190Y         S0      
327GND              J26   -73         A01X+020427Y+099778X0205Y0590R090 S1      
317GND              VIA   -    MD0100PA00X+020427Y+099108X0190Y         S0      
327GND              J26   -71         A01X+020427Y+099108X0205Y0590R090 S1      
317GND              VIA   -    MD0100PA00X+018813Y+099443X0190Y         S0      
327GND              J26   -216        A01X+018813Y+099443X0205Y0590R090 S1      
317GND              VIA   -    MD0100PA00X+018813Y+098774X0190Y         S0      
327GND              J26   -214        A01X+018813Y+098774X0205Y0590R090 S1      
317GND              VIA   -    MD0100PA00X+166934Y+098439X0190Y         S0      
327GND              J69   -69         A01X+166934Y+098439X0205Y0590R090 S1      
317GND              VIA   -    MD0100PA00X+166934Y+097770X0190Y         S0      
327GND              J69   -67         A01X+166934Y+097770X0205Y0590R090 S1      
317GND              VIA   -    MD0100PA00X+165320Y+098104X0190Y         S0      
327GND              J69   -212        A01X+165320Y+098104X0205Y0590R090 S1      
317GND              VIA   -    MD0100PA00X+165320Y+097435X0190Y         S0      
327GND              J69   -210        A01X+165320Y+097435X0205Y0590R090 S1      
317GND              VIA   -    MD0100PA00X+163964Y+098439X0190Y         S0      
327GND              J16   -69         A01X+163964Y+098439X0205Y0590R090 S1      
317GND              VIA   -    MD0100PA00X+163964Y+097770X0190Y         S0      
327GND              J16   -67         A01X+163964Y+097770X0205Y0590R090 S1      
317GND              VIA   -    MD0100PA00X+162350Y+098104X0190Y         S0      
327GND              J16   -212        A01X+162350Y+098104X0205Y0590R090 S1      
317GND              VIA   -    MD0100PA00X+162350Y+097435X0190Y         S0      
327GND              J16   -210        A01X+162350Y+097435X0205Y0590R090 S1      
317GND              VIA   -    MD0100PA00X+141630Y+097424X0190Y    R090 S0      
317GND              VIA   -    MD0100PA00X+141630Y+098174X0190Y    R090 S0      
317GND              VIA   -    MD0100PA00X+121011Y+098439X0190Y         S0      
327GND              J1    -69         A01X+121011Y+098439X0205Y0590R090 S1      
317GND              VIA   -    MD0100PA00X+121011Y+097770X0190Y         S0      
327GND              J1    -67         A01X+121011Y+097770X0205Y0590R090 S1      
317GND              VIA   -    MD0100PA00X+119397Y+098104X0190Y         S0      
327GND              J1    -212        A01X+119397Y+098104X0205Y0590R090 S1      
317GND              VIA   -    MD0100PA00X+119397Y+097435X0190Y         S0      
327GND              J1    -210        A01X+119397Y+097435X0205Y0590R090 S1      
317GND              VIA   -    MD0100PA00X+118041Y+098439X0190Y         S0      
327GND              J15   -69         A01X+118041Y+098439X0205Y0590R090 S1      
317GND              VIA   -    MD0100PA00X+118041Y+097770X0190Y         S0      
327GND              J15   -67         A01X+118041Y+097770X0205Y0590R090 S1      
317GND              VIA   -    MD0100PA00X+116427Y+098104X0190Y         S0      
327GND              J15   -212        A01X+116427Y+098104X0205Y0590R090 S1      
317GND              VIA   -    MD0100PA00X+116427Y+097435X0190Y         S0      
327GND              J15   -210        A01X+116427Y+097435X0205Y0590R090 S1      
317GND              VIA   -    MD0100PA00X+064735Y+098104X0190Y         S0      
327GND              J102  -212        A01X+064735Y+098104X0205Y0590R090 S1      
317GND              VIA   -    MD0100PA00X+064735Y+097435X0190Y         S0      
327GND              J102  -210        A01X+064735Y+097435X0205Y0590R090 S1      
317GND              VIA   -    MD0100PA00X+044016Y+097424X0190Y    R090 S0      
317GND              VIA   -    MD0100PA00X+044016Y+098174X0190Y    R090 S0      
317GND              VIA   -    MD0100PA00X+023397Y+098439X0190Y         S0      
327GND              J24   -69         A01X+023397Y+098439X0205Y0590R090 S1      
317GND              VIA   -    MD0100PA00X+023397Y+097770X0190Y         S0      
327GND              J24   -67         A01X+023397Y+097770X0205Y0590R090 S1      
317GND              VIA   -    MD0100PA00X+021783Y+098104X0190Y         S0      
327GND              J24   -212        A01X+021783Y+098104X0205Y0590R090 S1      
317GND              VIA   -    MD0100PA00X+021783Y+097435X0190Y         S0      
327GND              J24   -210        A01X+021783Y+097435X0205Y0590R090 S1      
317GND              VIA   -    MD0100PA00X+020427Y+098439X0190Y         S0      
327GND              J26   -69         A01X+020427Y+098439X0205Y0590R090 S1      
317GND              VIA   -    MD0100PA00X+020427Y+097770X0190Y         S0      
327GND              J26   -67         A01X+020427Y+097770X0205Y0590R090 S1      
317GND              VIA   -    MD0100PA00X+018813Y+098104X0190Y         S0      
327GND              J26   -212        A01X+018813Y+098104X0205Y0590R090 S1      
317GND              VIA   -    MD0100PA00X+018813Y+097435X0190Y         S0      
327GND              J26   -210        A01X+018813Y+097435X0205Y0590R090 S1      
317GND              VIA   -    MD0100PA00X+166934Y+097100X0190Y         S0      
327GND              J69   -65         A01X+166934Y+097100X0205Y0590R090 S1      
317GND              VIA   -    MD0100PA00X+166934Y+096431X0190Y         S0      
327GND              J69   -63         A01X+166934Y+096431X0205Y0590R090 S1      
317GND              VIA   -    MD0100PA00X+166934Y+095762X0190Y         S0      
327GND              J69   -61         A01X+166934Y+095762X0205Y0590R090 S1      
317GND              VIA   -    MD0100PA00X+165320Y+096766X0190Y         S0      
327GND              J69   -208        A01X+165320Y+096766X0205Y0590R090 S1      
317GND              VIA   -    MD0100PA00X+165320Y+096096X0190Y         S0      
327GND              J69   -206        A01X+165320Y+096096X0205Y0590R090 S1      
317GND              VIA   -    MD0100PA00X+163964Y+097100X0190Y         S0      
327GND              J16   -65         A01X+163964Y+097100X0205Y0590R090 S1      
317GND              VIA   -    MD0100PA00X+163964Y+096431X0190Y         S0      
327GND              J16   -63         A01X+163964Y+096431X0205Y0590R090 S1      
317GND              VIA   -    MD0100PA00X+163964Y+095762X0190Y         S0      
327GND              J16   -61         A01X+163964Y+095762X0205Y0590R090 S1      
317GND              VIA   -    MD0100PA00X+162350Y+096766X0190Y         S0      
327GND              J16   -208        A01X+162350Y+096766X0205Y0590R090 S1      
317GND              VIA   -    MD0100PA00X+162350Y+096096X0190Y         S0      
327GND              J16   -206        A01X+162350Y+096096X0205Y0590R090 S1      
317GND              VIA   -    MD0100PA00X+141630Y+096674X0190Y    R090 S0      
317GND              VIA   -    MD0100PA00X+121011Y+097100X0190Y         S0      
327GND              J1    -65         A01X+121011Y+097100X0205Y0590R090 S1      
317GND              VIA   -    MD0100PA00X+121011Y+096431X0190Y         S0      
327GND              J1    -63         A01X+121011Y+096431X0205Y0590R090 S1      
317GND              VIA   -    MD0100PA00X+121011Y+095762X0190Y         S0      
327GND              J1    -61         A01X+121011Y+095762X0205Y0590R090 S1      
317GND              VIA   -    MD0100PA00X+119397Y+096766X0190Y         S0      
327GND              J1    -208        A01X+119397Y+096766X0205Y0590R090 S1      
317GND              VIA   -    MD0100PA00X+119397Y+096096X0190Y         S0      
327GND              J1    -206        A01X+119397Y+096096X0205Y0590R090 S1      
317GND              VIA   -    MD0100PA00X+118041Y+097100X0190Y         S0      
327GND              J15   -65         A01X+118041Y+097100X0205Y0590R090 S1      
317GND              VIA   -    MD0100PA00X+118041Y+096431X0190Y         S0      
327GND              J15   -63         A01X+118041Y+096431X0205Y0590R090 S1      
317GND              VIA   -    MD0100PA00X+118041Y+095762X0190Y         S0      
327GND              J15   -61         A01X+118041Y+095762X0205Y0590R090 S1      
317GND              VIA   -    MD0100PA00X+116427Y+096766X0190Y         S0      
327GND              J15   -208        A01X+116427Y+096766X0205Y0590R090 S1      
317GND              VIA   -    MD0100PA00X+116427Y+096096X0190Y         S0      
327GND              J15   -206        A01X+116427Y+096096X0205Y0590R090 S1      
317GND              VIA   -    MD0100PA00X+064735Y+096766X0190Y         S0      
327GND              J102  -208        A01X+064735Y+096766X0205Y0590R090 S1      
317GND              VIA   -    MD0100PA00X+064735Y+096097X0190Y         S0      
327GND              J102  -206        A01X+064735Y+096097X0205Y0590R090 S1      
317GND              VIA   -    MD0100PA00X+044016Y+096674X0190Y    R090 S0      
317GND              VIA   -    MD0100PA00X+023397Y+097100X0190Y         S0      
327GND              J24   -65         A01X+023397Y+097100X0205Y0590R090 S1      
317GND              VIA   -    MD0100PA00X+023397Y+096431X0190Y         S0      
327GND              J24   -63         A01X+023397Y+096431X0205Y0590R090 S1      
317GND              VIA   -    MD0100PA00X+023397Y+095762X0190Y         S0      
327GND              J24   -61         A01X+023397Y+095762X0205Y0590R090 S1      
317GND              VIA   -    MD0100PA00X+021783Y+096766X0190Y         S0      
327GND              J24   -208        A01X+021783Y+096766X0205Y0590R090 S1      
317GND              VIA   -    MD0100PA00X+021783Y+096097X0190Y         S0      
327GND              J24   -206        A01X+021783Y+096097X0205Y0590R090 S1      
317GND              VIA   -    MD0100PA00X+020427Y+097100X0190Y         S0      
327GND              J26   -65         A01X+020427Y+097100X0205Y0590R090 S1      
317GND              VIA   -    MD0100PA00X+020427Y+096431X0190Y         S0      
327GND              J26   -63         A01X+020427Y+096431X0205Y0590R090 S1      
317GND              VIA   -    MD0100PA00X+020427Y+095762X0190Y         S0      
327GND              J26   -61         A01X+020427Y+095762X0205Y0590R090 S1      
317GND              VIA   -    MD0100PA00X+018813Y+096766X0190Y         S0      
327GND              J26   -208        A01X+018813Y+096766X0205Y0590R090 S1      
317GND              VIA   -    MD0100PA00X+018813Y+096097X0190Y         S0      
327GND              J26   -206        A01X+018813Y+096097X0205Y0590R090 S1      
317GND              VIA   -    MD0100PA00X+166934Y+095092X0190Y         S0      
327GND              J69   -59         A01X+166934Y+095092X0205Y0590R090 S1      
317GND              VIA   -    MD0100PA00X+166389Y+094423X0190Y         S0      
327GND              J69   -57         A01X+166934Y+094423X0205Y0590R090 S1      
317GND              VIA   -    MD0100PA00X+165320Y+095427X0190Y         S0      
327GND              J69   -204        A01X+165320Y+095427X0205Y0590R090 S1      
317GND              VIA   -    MD0100PA00X+165865Y+094758X0190Y    R180 S0      
327GND              J69   -202        A01X+165320Y+094758X0205Y0590R090 S1      
317GND              VIA   -    MD0100PA00X+165760Y+094256X0190Y         S0      
317GND              VIA   -    MD0100PA00X+163964Y+095092X0190Y         S0      
327GND              J16   -59         A01X+163964Y+095092X0205Y0590R090 S1      
317GND              VIA   -    MD0100PA00X+163419Y+094423X0190Y         S0      
327GND              J16   -57         A01X+163964Y+094423X0205Y0590R090 S1      
317GND              VIA   -    MD0100PA00X+162350Y+095427X0190Y         S0      
327GND              J16   -204        A01X+162350Y+095427X0205Y0590R090 S1      
317GND              VIA   -    MD0100PA00X+162895Y+094758X0190Y    R180 S0      
327GND              J16   -202        A01X+162350Y+094758X0205Y0590R090 S1      
317GND              VIA   -    MD0100PA00X+162790Y+094256X0190Y         S0      
317GND              VIA   -    MD0100PA00X+121011Y+095092X0190Y         S0      
327GND              J1    -59         A01X+121011Y+095092X0205Y0590R090 S1      
317GND              VIA   -    MD0100PA00X+120466Y+094423X0190Y         S0      
327GND              J1    -57         A01X+121011Y+094423X0205Y0590R090 S1      
317GND              VIA   -    MD0100PA00X+119942Y+094758X0190Y    R180 S0      
327GND              J1    -202        A01X+119397Y+094758X0205Y0590R090 S1      
317GND              VIA   -    MD0100PA00X+118957Y+094256X0190Y         S0      
317GND              VIA   -    MD0100PA00X+119397Y+095427X0190Y         S0      
327GND              J1    -204        A01X+119397Y+095427X0205Y0590R090 S1      
317GND              VIA   -    MD0100PA00X+118041Y+095092X0190Y         S0      
327GND              J15   -59         A01X+118041Y+095092X0205Y0590R090 S1      
317GND              VIA   -    MD0100PA00X+117496Y+094423X0190Y         S0      
327GND              J15   -57         A01X+118041Y+094423X0205Y0590R090 S1      
317GND              VIA   -    MD0100PA00X+116427Y+095427X0190Y         S0      
327GND              J15   -204        A01X+116427Y+095427X0205Y0590R090 S1      
317GND              VIA   -    MD0100PA00X+116972Y+094758X0190Y    R180 S0      
327GND              J15   -202        A01X+116427Y+094758X0205Y0590R090 S1      
317GND              VIA   -    MD0100PA00X+115987Y+094256X0190Y         S0      
317GND              VIA   -    MD0100PA00X+064735Y+095427X0190Y         S0      
327GND              J102  -204        A01X+064735Y+095427X0205Y0590R090 S1      
317GND              VIA   -    MD0100PA00X+023397Y+095093X0190Y         S0      
327GND              J24   -59         A01X+023397Y+095093X0205Y0590R090 S1      
317GND              VIA   -    MD0100PA00X+021783Y+095427X0190Y         S0      
327GND              J24   -204        A01X+021783Y+095427X0205Y0590R090 S1      
317GND              VIA   -    MD0100PA00X+022328Y+094758X0190Y    R180 S0      
327GND              J24   -202        A01X+021783Y+094758X0205Y0590R090 S1      
317GND              VIA   -    MD0100PA00X+022852Y+094423X0190Y         S0      
327GND              J24   -57         A01X+023397Y+094423X0205Y0590R090 S1      
317GND              VIA   -    MD0100PA00X+020427Y+095093X0190Y         S0      
327GND              J26   -59         A01X+020427Y+095093X0205Y0590R090 S1      
317GND              VIA   -    MD0100PA00X+021343Y+094256X0190Y         S0      
317GND              VIA   -    MD0100PA00X+018813Y+095427X0190Y         S0      
327GND              J26   -204        A01X+018813Y+095427X0205Y0590R090 S1      
317GND              VIA   -    MD0100PA00X+019358Y+094758X0190Y    R180 S0      
327GND              J26   -202        A01X+018813Y+094758X0205Y0590R090 S1      
317GND              VIA   -    MD0100PA00X+019882Y+094423X0190Y         S0      
327GND              J26   -57         A01X+020427Y+094423X0205Y0590R090 S1      
317GND              VIA   -    MD0100PA00X+018373Y+094256X0190Y         S0      
317GND              VIA   -    MD0100PA00X+166934Y+092750X0190Y         S0      
327GND              J69   -52         A01X+166934Y+092750X0205Y0590R090 S1      
317GND              VIA   -    MD0100PA00X+166389Y+093419X0190Y         S0      
327GND              J69   -54         A01X+166934Y+093419X0205Y0590R090 S1      
317GND              VIA   -    MD0100PA00X+167374Y+093921X0190Y         S0      
317GND              VIA   -    MD0100PA00X+165320Y+093085X0190Y         S0      
327GND              J69   -197        A01X+165320Y+093085X0205Y0590R090 S1      
317GND              VIA   -    MD0100PA00X+165865Y+093754X0190Y    R180 S0      
327GND              J69   -199        A01X+165320Y+093754X0205Y0590R090 S1      
317GND              VIA   -    MD0100PA00X+163964Y+092750X0190Y         S0      
327GND              J16   -52         A01X+163964Y+092750X0205Y0590R090 S1      
317GND              VIA   -    MD0100PA00X+163419Y+093419X0190Y         S0      
327GND              J16   -54         A01X+163964Y+093419X0205Y0590R090 S1      
317GND              VIA   -    MD0100PA00X+164404Y+093921X0190Y         S0      
317GND              VIA   -    MD0100PA00X+162350Y+093085X0190Y         S0      
327GND              J16   -197        A01X+162350Y+093085X0205Y0590R090 S1      
317GND              VIA   -    MD0100PA00X+162895Y+093754X0190Y    R180 S0      
327GND              J16   -199        A01X+162350Y+093754X0205Y0590R090 S1      
317GND              VIA   -    MD0100PA00X+121011Y+092750X0190Y         S0      
327GND              J1    -52         A01X+121011Y+092750X0205Y0590R090 S1      
317GND              VIA   -    MD0100PA00X+120466Y+093419X0190Y         S0      
327GND              J1    -54         A01X+121011Y+093419X0205Y0590R090 S1      
317GND              VIA   -    MD0100PA00X+120571Y+093921X0190Y         S0      
317GND              VIA   -    MD0100PA00X+119397Y+093085X0190Y         S0      
327GND              J1    -197        A01X+119397Y+093085X0205Y0590R090 S1      
317GND              VIA   -    MD0100PA00X+119942Y+093754X0190Y    R180 S0      
327GND              J1    -199        A01X+119397Y+093754X0205Y0590R090 S1      
317GND              VIA   -    MD0100PA00X+118041Y+092750X0190Y         S0      
327GND              J15   -52         A01X+118041Y+092750X0205Y0590R090 S1      
317GND              VIA   -    MD0100PA00X+117496Y+093419X0190Y         S0      
327GND              J15   -54         A01X+118041Y+093419X0205Y0590R090 S1      
317GND              VIA   -    MD0100PA00X+117601Y+093921X0190Y         S0      
317GND              VIA   -    MD0100PA00X+116427Y+093085X0190Y         S0      
327GND              J15   -197        A01X+116427Y+093085X0205Y0590R090 S1      
317GND              VIA   -    MD0100PA00X+116972Y+093754X0190Y    R180 S0      
327GND              J15   -199        A01X+116427Y+093754X0205Y0590R090 S1      
317GND              VIA   -    MD0100PA00X+064735Y+093085X0190Y         S0      
327GND              J102  -197        A01X+064735Y+093085X0205Y0590R090 S1      
317GND              VIA   -    MD0100PA00X+023397Y+092750X0190Y         S0      
327GND              J24   -52         A01X+023397Y+092750X0205Y0590R090 S1      
317GND              VIA   -    MD0100PA00X+021783Y+093085X0190Y         S0      
327GND              J24   -197        A01X+021783Y+093085X0205Y0590R090 S1      
317GND              VIA   -    MD0100PA00X+022328Y+093754X0190Y    R180 S0      
327GND              J24   -199        A01X+021783Y+093754X0205Y0590R090 S1      
317GND              VIA   -    MD0100PA00X+022852Y+093419X0190Y         S0      
327GND              J24   -54         A01X+023397Y+093419X0205Y0590R090 S1      
317GND              VIA   -    MD0100PA00X+022957Y+093921X0190Y         S0      
317GND              VIA   -    MD0100PA00X+020427Y+092750X0190Y         S0      
327GND              J26   -52         A01X+020427Y+092750X0205Y0590R090 S1      
317GND              VIA   -    MD0100PA00X+018813Y+093085X0190Y         S0      
327GND              J26   -197        A01X+018813Y+093085X0205Y0590R090 S1      
317GND              VIA   -    MD0100PA00X+019358Y+093754X0190Y    R180 S0      
327GND              J26   -199        A01X+018813Y+093754X0205Y0590R090 S1      
317GND              VIA   -    MD0100PA00X+019882Y+093419X0190Y         S0      
327GND              J26   -54         A01X+020427Y+093419X0205Y0590R090 S1      
317GND              VIA   -    MD0100PA00X+019987Y+093921X0190Y         S0      
317GND              VIA   -    MD0100PA00X+166934Y+092081X0190Y         S0      
327GND              J69   -50         A01X+166934Y+092081X0205Y0590R090 S1      
317GND              VIA   -    MD0100PA00X+166934Y+091411X0190Y         S0      
327GND              J69   -48         A01X+166934Y+091411X0205Y0590R090 S1      
317GND              VIA   -    MD0100PA00X+165320Y+092415X0190Y         S0      
327GND              J69   -195        A01X+165320Y+092415X0205Y0590R090 S1      
317GND              VIA   -    MD0100PA00X+165320Y+091746X0190Y         S0      
327GND              J69   -193        A01X+165320Y+091746X0205Y0590R090 S1      
317GND              VIA   -    MD0100PA00X+163964Y+092081X0190Y         S0      
327GND              J16   -50         A01X+163964Y+092081X0205Y0590R090 S1      
317GND              VIA   -    MD0100PA00X+163964Y+091411X0190Y         S0      
327GND              J16   -48         A01X+163964Y+091411X0205Y0590R090 S1      
317GND              VIA   -    MD0100PA00X+162350Y+092415X0190Y         S0      
327GND              J16   -195        A01X+162350Y+092415X0205Y0590R090 S1      
317GND              VIA   -    MD0100PA00X+162350Y+091746X0190Y         S0      
327GND              J16   -193        A01X+162350Y+091746X0205Y0590R090 S1      
317GND              VIA   -    MD0100PA00X+121011Y+092081X0190Y         S0      
327GND              J1    -50         A01X+121011Y+092081X0205Y0590R090 S1      
317GND              VIA   -    MD0100PA00X+121011Y+091411X0190Y         S0      
327GND              J1    -48         A01X+121011Y+091411X0205Y0590R090 S1      
317GND              VIA   -    MD0100PA00X+119397Y+092415X0190Y         S0      
327GND              J1    -195        A01X+119397Y+092415X0205Y0590R090 S1      
317GND              VIA   -    MD0100PA00X+119397Y+091746X0190Y         S0      
327GND              J1    -193        A01X+119397Y+091746X0205Y0590R090 S1      
317GND              VIA   -    MD0100PA00X+118041Y+092081X0190Y         S0      
327GND              J15   -50         A01X+118041Y+092081X0205Y0590R090 S1      
317GND              VIA   -    MD0100PA00X+118041Y+091411X0190Y         S0      
327GND              J15   -48         A01X+118041Y+091411X0205Y0590R090 S1      
317GND              VIA   -    MD0100PA00X+116427Y+092415X0190Y         S0      
327GND              J15   -195        A01X+116427Y+092415X0205Y0590R090 S1      
317GND              VIA   -    MD0100PA00X+116427Y+091746X0190Y         S0      
327GND              J15   -193        A01X+116427Y+091746X0205Y0590R090 S1      
317GND              VIA   -    MD0100PA00X+064735Y+092416X0190Y         S0      
327GND              J102  -195        A01X+064735Y+092416X0205Y0590R090 S1      
317GND              VIA   -    MD0100PA00X+064735Y+091746X0190Y         S0      
327GND              J102  -193        A01X+064735Y+091746X0205Y0590R090 S1      
317GND              VIA   -    MD0100PA00X+023397Y+092081X0190Y         S0      
327GND              J24   -50         A01X+023397Y+092081X0205Y0590R090 S1      
317GND              VIA   -    MD0100PA00X+023397Y+091412X0190Y         S0      
327GND              J24   -48         A01X+023397Y+091412X0205Y0590R090 S1      
317GND              VIA   -    MD0100PA00X+021783Y+092416X0190Y         S0      
327GND              J24   -195        A01X+021783Y+092416X0205Y0590R090 S1      
317GND              VIA   -    MD0100PA00X+021783Y+091746X0190Y         S0      
327GND              J24   -193        A01X+021783Y+091746X0205Y0590R090 S1      
317GND              VIA   -    MD0100PA00X+020427Y+092081X0190Y         S0      
327GND              J26   -50         A01X+020427Y+092081X0205Y0590R090 S1      
317GND              VIA   -    MD0100PA00X+020427Y+091412X0190Y         S0      
327GND              J26   -48         A01X+020427Y+091412X0205Y0590R090 S1      
317GND              VIA   -    MD0100PA00X+018813Y+092416X0190Y         S0      
327GND              J26   -195        A01X+018813Y+092416X0205Y0590R090 S1      
317GND              VIA   -    MD0100PA00X+018813Y+091746X0190Y         S0      
327GND              J26   -193        A01X+018813Y+091746X0205Y0590R090 S1      
317GND              VIA   -    MD0100PA00X+166389Y+090742X0190Y         S0      
327GND              J69   -46         A01X+166934Y+090742X0205Y0590R090 S1      
317GND              VIA   -    MD0100PA00X+166389Y+089738X0190Y         S0      
327GND              J69   -43         A01X+166934Y+089738X0205Y0590R090 S1      
317GND              VIA   -    MD0100PA00X+167374Y+090240X0190Y         S0      
317GND              VIA   -    MD0100PA00X+165865Y+091077X0190Y    R180 S0      
327GND              J69   -191        A01X+165320Y+091077X0205Y0590R090 S1      
317GND              VIA   -    MD0100PA00X+165865Y+090073X0190Y    R180 S0      
327GND              J69   -188        A01X+165320Y+090073X0205Y0590R090 S1      
317GND              VIA   -    MD0100PA00X+165760Y+090575X0190Y         S0      
317GND              VIA   -    MD0100PA00X+163419Y+090742X0190Y         S0      
327GND              J16   -46         A01X+163964Y+090742X0205Y0590R090 S1      
317GND              VIA   -    MD0100PA00X+163419Y+089738X0190Y         S0      
327GND              J16   -43         A01X+163964Y+089738X0205Y0590R090 S1      
317GND              VIA   -    MD0100PA00X+164404Y+090240X0190Y         S0      
317GND              VIA   -    MD0100PA00X+162895Y+091077X0190Y    R180 S0      
327GND              J16   -191        A01X+162350Y+091077X0205Y0590R090 S1      
317GND              VIA   -    MD0100PA00X+162895Y+090073X0190Y    R180 S0      
327GND              J16   -188        A01X+162350Y+090073X0205Y0590R090 S1      
317GND              VIA   -    MD0100PA00X+162790Y+090575X0190Y         S0      
317GND              VIA   -    MD0100PA00X+120466Y+090742X0190Y         S0      
327GND              J1    -46         A01X+121011Y+090742X0205Y0590R090 S1      
317GND              VIA   -    MD0100PA00X+120466Y+089738X0190Y         S0      
327GND              J1    -43         A01X+121011Y+089738X0205Y0590R090 S1      
317GND              VIA   -    MD0100PA00X+120571Y+090240X0190Y         S0      
317GND              VIA   -    MD0100PA00X+119942Y+091077X0190Y    R180 S0      
327GND              J1    -191        A01X+119397Y+091077X0205Y0590R090 S1      
317GND              VIA   -    MD0100PA00X+119942Y+090073X0190Y    R180 S0      
327GND              J1    -188        A01X+119397Y+090073X0205Y0590R090 S1      
317GND              VIA   -    MD0100PA00X+118957Y+090575X0190Y         S0      
317GND              VIA   -    MD0100PA00X+117496Y+090742X0190Y         S0      
327GND              J15   -46         A01X+118041Y+090742X0205Y0590R090 S1      
317GND              VIA   -    MD0100PA00X+117496Y+089738X0190Y         S0      
327GND              J15   -43         A01X+118041Y+089738X0205Y0590R090 S1      
317GND              VIA   -    MD0100PA00X+117601Y+090240X0190Y         S0      
317GND              VIA   -    MD0100PA00X+116972Y+091077X0190Y    R180 S0      
327GND              J15   -191        A01X+116427Y+091077X0205Y0590R090 S1      
317GND              VIA   -    MD0100PA00X+116972Y+090073X0190Y    R180 S0      
327GND              J15   -188        A01X+116427Y+090073X0205Y0590R090 S1      
317GND              VIA   -    MD0100PA00X+115987Y+090575X0190Y         S0      
317GND              VIA   -    MD0100PA00X+022328Y+091077X0190Y    R180 S0      
327GND              J24   -191        A01X+021783Y+091077X0205Y0590R090 S1      
317GND              VIA   -    MD0100PA00X+022852Y+090742X0190Y         S0      
327GND              J24   -46         A01X+023397Y+090742X0205Y0590R090 S1      
317GND              VIA   -    MD0100PA00X+022328Y+090073X0190Y    R180 S0      
327GND              J24   -188        A01X+021783Y+090073X0205Y0590R090 S1      
317GND              VIA   -    MD0100PA00X+022852Y+089738X0190Y         S0      
327GND              J24   -43         A01X+023397Y+089738X0205Y0590R090 S1      
317GND              VIA   -    MD0100PA00X+022957Y+090240X0190Y         S0      
317GND              VIA   -    MD0100PA00X+021343Y+090575X0190Y         S0      
317GND              VIA   -    MD0100PA00X+019358Y+091077X0190Y    R180 S0      
327GND              J26   -191        A01X+018813Y+091077X0205Y0590R090 S1      
317GND              VIA   -    MD0100PA00X+019882Y+090742X0190Y         S0      
327GND              J26   -46         A01X+020427Y+090742X0205Y0590R090 S1      
317GND              VIA   -    MD0100PA00X+019358Y+090073X0190Y    R180 S0      
327GND              J26   -188        A01X+018813Y+090073X0205Y0590R090 S1      
317GND              VIA   -    MD0100PA00X+019882Y+089738X0190Y         S0      
327GND              J26   -43         A01X+020427Y+089738X0205Y0590R090 S1      
317GND              VIA   -    MD0100PA00X+019987Y+090240X0190Y         S0      
317GND              VIA   -    MD0100PA00X+018373Y+090575X0190Y         S0      
317GND              VIA   -    MD0100PA00X+166934Y+089069X0190Y         S0      
327GND              J69   -41         A01X+166934Y+089069X0205Y0590R090 S1      
317GND              VIA   -    MD0100PA00X+166934Y+088400X0190Y         S0      
327GND              J69   -39         A01X+166934Y+088400X0205Y0590R090 S1      
317GND              VIA   -    MD0100PA00X+165320Y+089404X0190Y         S0      
327GND              J69   -186        A01X+165320Y+089404X0205Y0590R090 S1      
317GND              VIA   -    MD0100PA00X+165320Y+088734X0190Y         S0      
327GND              J69   -184        A01X+165320Y+088734X0205Y0590R090 S1      
317GND              VIA   -    MD0100PA00X+163964Y+089069X0190Y         S0      
327GND              J16   -41         A01X+163964Y+089069X0205Y0590R090 S1      
317GND              VIA   -    MD0100PA00X+163964Y+088400X0190Y         S0      
327GND              J16   -39         A01X+163964Y+088400X0205Y0590R090 S1      
317GND              VIA   -    MD0100PA00X+162350Y+089404X0190Y         S0      
327GND              J16   -186        A01X+162350Y+089404X0205Y0590R090 S1      
317GND              VIA   -    MD0100PA00X+162350Y+088734X0190Y         S0      
327GND              J16   -184        A01X+162350Y+088734X0205Y0590R090 S1      
317GND              VIA   -    MD0100PA00X+119397Y+089404X0190Y         S0      
327GND              J1    -186        A01X+119397Y+089404X0205Y0590R090 S1      
317GND              VIA   -    MD0100PA00X+116427Y+089404X0190Y         S0      
327GND              J15   -186        A01X+116427Y+089404X0205Y0590R090 S1      
317GND              VIA   -    MD0100PA00X+064735Y+089404X0190Y         S0      
327GND              J102  -186        A01X+064735Y+089404X0205Y0590R090 S1      
317GND              VIA   -    MD0100PA00X+064735Y+088734X0190Y         S0      
327GND              J102  -184        A01X+064735Y+088734X0205Y0590R090 S1      
317GND              VIA   -    MD0100PA00X+023397Y+089069X0190Y         S0      
327GND              J24   -41         A01X+023397Y+089069X0205Y0590R090 S1      
317GND              VIA   -    MD0100PA00X+023397Y+088400X0190Y         S0      
327GND              J24   -39         A01X+023397Y+088400X0205Y0590R090 S1      
317GND              VIA   -    MD0100PA00X+021783Y+089404X0190Y         S0      
327GND              J24   -186        A01X+021783Y+089404X0205Y0590R090 S1      
317GND              VIA   -    MD0100PA00X+021783Y+088734X0190Y         S0      
327GND              J24   -184        A01X+021783Y+088734X0205Y0590R090 S1      
317GND              VIA   -    MD0100PA00X+020427Y+089069X0190Y         S0      
327GND              J26   -41         A01X+020427Y+089069X0205Y0590R090 S1      
317GND              VIA   -    MD0100PA00X+020427Y+088400X0190Y         S0      
327GND              J26   -39         A01X+020427Y+088400X0205Y0590R090 S1      
317GND              VIA   -    MD0100PA00X+018813Y+089404X0190Y         S0      
327GND              J26   -186        A01X+018813Y+089404X0205Y0590R090 S1      
317GND              VIA   -    MD0100PA00X+018813Y+088734X0190Y         S0      
327GND              J26   -184        A01X+018813Y+088734X0205Y0590R090 S1      
317GND              VIA   -    MD0100PA00X+166934Y+087730X0190Y         S0      
327GND              J69   -37         A01X+166934Y+087730X0205Y0590R090 S1      
317GND              VIA   -    MD0100PA00X+166389Y+087061X0190Y         S0      
327GND              J69   -35         A01X+166934Y+087061X0205Y0590R090 S1      
317GND              VIA   -    MD0100PA00X+165320Y+088065X0190Y         S0      
327GND              J69   -182        A01X+165320Y+088065X0205Y0590R090 S1      
317GND              VIA   -    MD0100PA00X+165865Y+087396X0190Y    R180 S0      
327GND              J69   -180        A01X+165320Y+087396X0205Y0590R090 S1      
317GND              VIA   -    MD0100PA00X+165760Y+086894X0190Y         S0      
317GND              VIA   -    MD0100PA00X+163964Y+087730X0190Y         S0      
327GND              J16   -37         A01X+163964Y+087730X0205Y0590R090 S1      
317GND              VIA   -    MD0100PA00X+163419Y+087061X0190Y         S0      
327GND              J16   -35         A01X+163964Y+087061X0205Y0590R090 S1      
317GND              VIA   -    MD0100PA00X+162350Y+088065X0190Y         S0      
327GND              J16   -182        A01X+162350Y+088065X0205Y0590R090 S1      
317GND              VIA   -    MD0100PA00X+162895Y+087396X0190Y    R180 S0      
327GND              J16   -180        A01X+162350Y+087396X0205Y0590R090 S1      
317GND              VIA   -    MD0100PA00X+162790Y+086894X0190Y         S0      
317GND              VIA   -    MD0100PA00X+064735Y+088065X0190Y         S0      
327GND              J102  -182        A01X+064735Y+088065X0205Y0590R090 S1      
317GND              VIA   -    MD0100PA00X+023397Y+087730X0190Y         S0      
327GND              J24   -37         A01X+023397Y+087730X0205Y0590R090 S1      
317GND              VIA   -    MD0100PA00X+021783Y+088065X0190Y         S0      
327GND              J24   -182        A01X+021783Y+088065X0205Y0590R090 S1      
317GND              VIA   -    MD0100PA00X+022328Y+087396X0190Y    R180 S0      
327GND              J24   -180        A01X+021783Y+087396X0205Y0590R090 S1      
317GND              VIA   -    MD0100PA00X+022852Y+087061X0190Y         S0      
327GND              J24   -35         A01X+023397Y+087061X0205Y0590R090 S1      
317GND              VIA   -    MD0100PA00X+020427Y+087730X0190Y         S0      
327GND              J26   -37         A01X+020427Y+087730X0205Y0590R090 S1      
317GND              VIA   -    MD0100PA00X+021343Y+086894X0190Y         S0      
317GND              VIA   -    MD0100PA00X+018813Y+088065X0190Y         S0      
327GND              J26   -182        A01X+018813Y+088065X0205Y0590R090 S1      
317GND              VIA   -    MD0100PA00X+019358Y+087396X0190Y    R180 S0      
327GND              J26   -180        A01X+018813Y+087396X0205Y0590R090 S1      
317GND              VIA   -    MD0100PA00X+019882Y+087061X0190Y         S0      
327GND              J26   -35         A01X+020427Y+087061X0205Y0590R090 S1      
317GND              VIA   -    MD0100PA00X+018373Y+086894X0190Y         S0      
317GND              VIA   -    MD0100PA00X+166934Y+085388X0190Y         S0      
327GND              J69   -30         A01X+166934Y+085388X0205Y0590R090 S1      
317GND              VIA   -    MD0100PA00X+166389Y+086057X0190Y         S0      
327GND              J69   -32         A01X+166934Y+086057X0205Y0590R090 S1      
317GND              VIA   -    MD0100PA00X+167374Y+086559X0190Y         S0      
317GND              VIA   -    MD0100PA00X+165320Y+085722X0190Y         S0      
327GND              J69   -175        A01X+165320Y+085722X0205Y0590R090 S1      
317GND              VIA   -    MD0100PA00X+165865Y+086392X0190Y    R180 S0      
327GND              J69   -177        A01X+165320Y+086392X0205Y0590R090 S1      
317GND              VIA   -    MD0100PA00X+163964Y+085388X0190Y         S0      
327GND              J16   -30         A01X+163964Y+085388X0205Y0590R090 S1      
317GND              VIA   -    MD0100PA00X+163419Y+086057X0190Y         S0      
327GND              J16   -32         A01X+163964Y+086057X0205Y0590R090 S1      
317GND              VIA   -    MD0100PA00X+164404Y+086559X0190Y         S0      
317GND              VIA   -    MD0100PA00X+162350Y+085722X0190Y         S0      
327GND              J16   -175        A01X+162350Y+085722X0205Y0590R090 S1      
317GND              VIA   -    MD0100PA00X+162895Y+086392X0190Y    R180 S0      
327GND              J16   -177        A01X+162350Y+086392X0205Y0590R090 S1      
317GND              VIA   -    MD0100PA00X+133935Y+085739X0200Y         S0      
317GND              VIA   -    MD0100PA00X+133028Y+085739X0200Y         S0      
317GND              VIA   -    MD0100PA00X+064735Y+085723X0190Y         S0      
327GND              J102  -175        A01X+064735Y+085723X0205Y0590R090 S1      
317GND              VIA   -    MD0100PA00X+051657Y+086533X0200Y    R090 S0      
317GND              VIA   -    MD0100PA00X+050626Y+086534X0200Y    R090 S0      
317GND              VIA   -    MD0100PA00X+023397Y+085388X0190Y         S0      
327GND              J24   -30         A01X+023397Y+085388X0205Y0590R090 S1      
317GND              VIA   -    MD0100PA00X+021783Y+085723X0190Y         S0      
327GND              J24   -175        A01X+021783Y+085723X0205Y0590R090 S1      
317GND              VIA   -    MD0100PA00X+022328Y+086392X0190Y    R180 S0      
327GND              J24   -177        A01X+021783Y+086392X0205Y0590R090 S1      
317GND              VIA   -    MD0100PA00X+022852Y+086057X0190Y         S0      
327GND              J24   -32         A01X+023397Y+086057X0205Y0590R090 S1      
317GND              VIA   -    MD0100PA00X+022957Y+086559X0190Y         S0      
317GND              VIA   -    MD0100PA00X+020427Y+085388X0190Y         S0      
327GND              J26   -30         A01X+020427Y+085388X0205Y0590R090 S1      
317GND              VIA   -    MD0100PA00X+018813Y+085723X0190Y         S0      
327GND              J26   -175        A01X+018813Y+085723X0205Y0590R090 S1      
317GND              VIA   -    MD0100PA00X+019358Y+086392X0190Y    R180 S0      
327GND              J26   -177        A01X+018813Y+086392X0205Y0590R090 S1      
317GND              VIA   -    MD0100PA00X+019882Y+086057X0190Y         S0      
327GND              J26   -32         A01X+020427Y+086057X0205Y0590R090 S1      
317GND              VIA   -    MD0100PA00X+019987Y+086559X0190Y         S0      
317GND              VIA   -    MD0100PA00X+166934Y+084718X0190Y         S0      
327GND              J69   -28         A01X+166934Y+084718X0205Y0590R090 S1      
317GND              VIA   -    MD0100PA00X+166934Y+084049X0190Y         S0      
327GND              J69   -26         A01X+166934Y+084049X0205Y0590R090 S1      
317GND              VIA   -    MD0100PA00X+165320Y+085053X0190Y         S0      
327GND              J69   -173        A01X+165320Y+085053X0205Y0590R090 S1      
317GND              VIA   -    MD0100PA00X+165320Y+084384X0190Y         S0      
327GND              J69   -171        A01X+165320Y+084384X0205Y0590R090 S1      
317GND              VIA   -    MD0100PA00X+163964Y+084718X0190Y         S0      
327GND              J16   -28         A01X+163964Y+084718X0205Y0590R090 S1      
317GND              VIA   -    MD0100PA00X+163964Y+084049X0190Y         S0      
327GND              J16   -26         A01X+163964Y+084049X0205Y0590R090 S1      
317GND              VIA   -    MD0100PA00X+162350Y+085053X0190Y         S0      
327GND              J16   -173        A01X+162350Y+085053X0205Y0590R090 S1      
317GND              VIA   -    MD0100PA00X+162350Y+084384X0190Y         S0      
327GND              J16   -171        A01X+162350Y+084384X0205Y0590R090 S1      
317GND              VIA   -    MD0100PA00X+100759Y+084426X0200Y         S0      
317GND              VIA   -    MD0100PA00X+064735Y+085053X0190Y         S0      
327GND              J102  -173        A01X+064735Y+085053X0205Y0590R090 S1      
317GND              VIA   -    MD0100PA00X+064735Y+084384X0190Y         S0      
327GND              J102  -171        A01X+064735Y+084384X0205Y0590R090 S1      
317GND              VIA   -    MD0100PA00X+037200Y+084936X0200Y         S0      
317GND              VIA   -    MD0100PA00X+037200Y+084036X0200Y         S0      
317GND              VIA   -    MD0100PA00X+037200Y+083786X0200Y         S0      
317GND              VIA   -    MD0100PA00X+023397Y+084719X0190Y         S0      
327GND              J24   -28         A01X+023397Y+084719X0205Y0590R090 S1      
317GND              VIA   -    MD0100PA00X+023397Y+084049X0190Y         S0      
327GND              J24   -26         A01X+023397Y+084049X0205Y0590R090 S1      
317GND              VIA   -    MD0100PA00X+021783Y+085053X0190Y         S0      
327GND              J24   -173        A01X+021783Y+085053X0205Y0590R090 S1      
317GND              VIA   -    MD0100PA00X+021783Y+084384X0190Y         S0      
327GND              J24   -171        A01X+021783Y+084384X0205Y0590R090 S1      
317GND              VIA   -    MD0100PA00X+020427Y+084719X0190Y         S0      
327GND              J26   -28         A01X+020427Y+084719X0205Y0590R090 S1      
317GND              VIA   -    MD0100PA00X+020427Y+084049X0190Y         S0      
327GND              J26   -26         A01X+020427Y+084049X0205Y0590R090 S1      
317GND              VIA   -    MD0100PA00X+018813Y+085053X0190Y         S0      
327GND              J26   -173        A01X+018813Y+085053X0205Y0590R090 S1      
317GND              VIA   -    MD0100PA00X+018813Y+084384X0190Y         S0      
327GND              J26   -171        A01X+018813Y+084384X0205Y0590R090 S1      
317GND              VIA   -    MD0100PA00X+166389Y+083380X0190Y         S0      
327GND              J69   -24         A01X+166934Y+083380X0205Y0590R090 S1      
317GND              VIA   -    MD0100PA00X+166389Y+082376X0190Y         S0      
327GND              J69   -21         A01X+166934Y+082376X0205Y0590R090 S1      
317GND              VIA   -    MD0100PA00X+167374Y+082878X0190Y         S0      
317GND              VIA   -    MD0100PA00X+165865Y+083715X0190Y    R180 S0      
327GND              J69   -169        A01X+165320Y+083715X0205Y0590R090 S1      
317GND              VIA   -    MD0100PA00X+165865Y+082711X0190Y    R180 S0      
327GND              J69   -166        A01X+165320Y+082711X0205Y0590R090 S1      
317GND              VIA   -    MD0100PA00X+165760Y+083213X0190Y         S0      
317GND              VIA   -    MD0100PA00X+163419Y+083380X0190Y         S0      
327GND              J16   -24         A01X+163964Y+083380X0205Y0590R090 S1      
317GND              VIA   -    MD0100PA00X+163419Y+082376X0190Y         S0      
327GND              J16   -21         A01X+163964Y+082376X0205Y0590R090 S1      
317GND              VIA   -    MD0100PA00X+164404Y+082878X0190Y         S0      
317GND              VIA   -    MD0100PA00X+162895Y+083715X0190Y    R180 S0      
327GND              J16   -169        A01X+162350Y+083715X0205Y0590R090 S1      
317GND              VIA   -    MD0100PA00X+162895Y+082711X0190Y    R180 S0      
327GND              J16   -166        A01X+162350Y+082711X0205Y0590R090 S1      
317GND              VIA   -    MD0100PA00X+162790Y+083213X0190Y         S0      
317GND              VIA   -    MD0100PA00X+150134Y+082515X0200Y         S0      
317GND              VIA   -    MD0100PA00X+149267Y+082851X0200Y         S0      
317GND              VIA   -    MD0100PA00X+100759Y+083586X0200Y         S0      
317GND              VIA   -    MD0100PA00X+100759Y+083336X0200Y         S0      
317GND              VIA   -    MD0100PA00X+100759Y+082475X0200Y         S0      
317GND              VIA   -    MD0100PA00X+037200Y+082886X0200Y         S0      
317GND              VIA   -    MD0100PA00X+037200Y+082636X0200Y         S0      
317GND              VIA   -    MD0100PA00X+022328Y+082711X0190Y    R180 S0      
327GND              J24   -166        A01X+021783Y+082711X0205Y0590R090 S1      
317GND              VIA   -    MD0100PA00X+022852Y+083380X0190Y         S0      
327GND              J24   -24         A01X+023397Y+083380X0205Y0590R090 S1      
317GND              VIA   -    MD0100PA00X+022852Y+082376X0190Y         S0      
327GND              J24   -21         A01X+023397Y+082376X0205Y0590R090 S1      
317GND              VIA   -    MD0100PA00X+022328Y+083715X0190Y    R180 S0      
327GND              J24   -169        A01X+021783Y+083715X0205Y0590R090 S1      
317GND              VIA   -    MD0100PA00X+022957Y+082878X0190Y         S0      
317GND              VIA   -    MD0100PA00X+021343Y+083213X0190Y         S0      
317GND              VIA   -    MD0100PA00X+019358Y+083715X0190Y    R180 S0      
327GND              J26   -169        A01X+018813Y+083715X0205Y0590R090 S1      
317GND              VIA   -    MD0100PA00X+019358Y+082711X0190Y    R180 S0      
327GND              J26   -166        A01X+018813Y+082711X0205Y0590R090 S1      
317GND              VIA   -    MD0100PA00X+019882Y+083380X0190Y         S0      
327GND              J26   -24         A01X+020427Y+083380X0205Y0590R090 S1      
317GND              VIA   -    MD0100PA00X+019882Y+082376X0190Y         S0      
327GND              J26   -21         A01X+020427Y+082376X0205Y0590R090 S1      
317GND              VIA   -    MD0100PA00X+019987Y+082878X0190Y         S0      
317GND              VIA   -    MD0100PA00X+018373Y+083213X0190Y         S0      
317GND              VIA   -    MD0100PA00X+166934Y+081707X0190Y         S0      
327GND              J69   -19         A01X+166934Y+081707X0205Y0590R090 S1      
317GND              VIA   -    MD0100PA00X+166934Y+081037X0190Y         S0      
327GND              J69   -17         A01X+166934Y+081037X0205Y0590R090 S1      
317GND              VIA   -    MD0100PA00X+165320Y+082041X0190Y         S0      
327GND              J69   -164        A01X+165320Y+082041X0205Y0590R090 S1      
317GND              VIA   -    MD0100PA00X+165320Y+081372X0190Y         S0      
327GND              J69   -162        A01X+165320Y+081372X0205Y0590R090 S1      
317GND              VIA   -    MD0100PA00X+163964Y+081707X0190Y         S0      
327GND              J16   -19         A01X+163964Y+081707X0205Y0590R090 S1      
317GND              VIA   -    MD0100PA00X+163964Y+081037X0190Y         S0      
327GND              J16   -17         A01X+163964Y+081037X0205Y0590R090 S1      
317GND              VIA   -    MD0100PA00X+162350Y+082041X0190Y         S0      
327GND              J16   -164        A01X+162350Y+082041X0205Y0590R090 S1      
317GND              VIA   -    MD0100PA00X+162350Y+081372X0190Y         S0      
327GND              J16   -162        A01X+162350Y+081372X0205Y0590R090 S1      
317GND              VIA   -    MD0100PA00X+150173Y+081187X0200Y         S0      
317GND              VIA   -    MD0100PA00X+149818Y+081701X0200Y    R180 S0      
327GND              C211  -2          A18X+149418Y+081941X0198Y0197R090 S2      
327GND              C208  -2   M      A18X+149818Y+081941X0198Y0197R090 S2      
317GND              VIA   -    MD0100PA00X+147818Y+081701X0200Y    R180 S0      
327GND              C210  -2          A18X+148218Y+081941X0198Y0197R090 S2      
327GND              C209  -2   M      A18X+147818Y+081941X0198Y0197R090 S2      
317GND              VIA   -    MD0100PA00X+127868Y+080899X0200Y    R180 S0      
317GND              VIA   -    MD0100PA00X+100759Y+082225X0200Y         S0      
317GND              VIA   -    MD0100PA00X+100759Y+081385X0200Y         S0      
317GND              VIA   -    MD0100PA00X+100759Y+081135X0200Y         S0      
317GND              VIA   -    MD0100PA00X+095184Y+081273X0200Y         S0      
317GND              VIA   -    MD0100PA00X+090639Y+081847X0200Y         S0      
317GND              VIA   -    MD0100PA00X+064735Y+082042X0190Y         S0      
327GND              J102  -164        A01X+064735Y+082042X0205Y0590R090 S1      
317GND              VIA   -    MD0100PA00X+064735Y+081372X0190Y         S0      
327GND              J102  -162        A01X+064735Y+081372X0205Y0590R090 S1      
317GND              VIA   -    MD0100PA00X+058600Y+080886X0200Y    R180 S0      
327GND              C234  -2          A18X+057977Y+080346X0198Y0197R270 S2      
327GND              C235  -2   M      A18X+058367Y+080356X0198Y0197R270 S2      
317GND              VIA   -    MD0100PA00X+038450Y+081986X0200Y         S0      
317GND              VIA   -    MD0100PA00X+038450Y+081086X0200Y         S0      
317GND              VIA   -    MD0100PA00X+037200Y+081686X0200Y         S0      
317GND              VIA   -    MD0100PA00X+023397Y+081707X0190Y         S0      
327GND              J24   -19         A01X+023397Y+081707X0205Y0590R090 S1      
317GND              VIA   -    MD0100PA00X+023397Y+081038X0190Y         S0      
327GND              J24   -17         A01X+023397Y+081038X0205Y0590R090 S1      
317GND              VIA   -    MD0100PA00X+021783Y+082042X0190Y         S0      
327GND              J24   -164        A01X+021783Y+082042X0205Y0590R090 S1      
317GND              VIA   -    MD0100PA00X+021783Y+081372X0190Y         S0      
327GND              J24   -162        A01X+021783Y+081372X0205Y0590R090 S1      
317GND              VIA   -    MD0100PA00X+020427Y+081707X0190Y         S0      
327GND              J26   -19         A01X+020427Y+081707X0205Y0590R090 S1      
317GND              VIA   -    MD0100PA00X+020427Y+081038X0190Y         S0      
327GND              J26   -17         A01X+020427Y+081038X0205Y0590R090 S1      
317GND              VIA   -    MD0100PA00X+018813Y+082042X0190Y         S0      
327GND              J26   -164        A01X+018813Y+082042X0205Y0590R090 S1      
317GND              VIA   -    MD0100PA00X+018813Y+081372X0190Y         S0      
327GND              J26   -162        A01X+018813Y+081372X0205Y0590R090 S1      
317GND              VIA   -    MD0100PA00X+166934Y+080368X0190Y         S0      
327GND              J69   -15         A01X+166934Y+080368X0205Y0590R090 S1      
317GND              VIA   -    MD0100PA00X+166389Y+079699X0190Y         S0      
327GND              J69   -13         A01X+166934Y+079699X0205Y0590R090 S1      
317GND              VIA   -    MD0100PA00X+165320Y+080703X0190Y         S0      
327GND              J69   -160        A01X+165320Y+080703X0205Y0590R090 S1      
317GND              VIA   -    MD0100PA00X+165865Y+080034X0190Y    R180 S0      
327GND              J69   -158        A01X+165320Y+080034X0205Y0590R090 S1      
317GND              VIA   -    MD0100PA00X+165760Y+079532X0190Y         S0      
317GND              VIA   -    MD0100PA00X+163964Y+080368X0190Y         S0      
327GND              J16   -15         A01X+163964Y+080368X0205Y0590R090 S1      
317GND              VIA   -    MD0100PA00X+163419Y+079699X0190Y         S0      
327GND              J16   -13         A01X+163964Y+079699X0205Y0590R090 S1      
317GND              VIA   -    MD0100PA00X+162350Y+080703X0190Y         S0      
327GND              J16   -160        A01X+162350Y+080703X0205Y0590R090 S1      
317GND              VIA   -    MD0100PA00X+162895Y+080034X0190Y    R180 S0      
327GND              J16   -158        A01X+162350Y+080034X0205Y0590R090 S1      
317GND              VIA   -    MD0100PA00X+162790Y+079532X0190Y         S0      
317GND              VIA   -    MD0100PA00X+158485Y+079351X0200Y    R180 S0      
327GND              U3    -3          A18X+158918Y+079351X0220Y0530R090 S2      
317GND              VIA   -    MD0100PA00X+156952Y+080668X0200Y         S0      
327GND              C30   -2          A18X+156952Y+080406X0198Y0197     S2      
317GND              VIA   -    MD0100PA00X+149924Y+080351X0200Y         S0      
317GND              VIA   -    MD0100PA00X+148918Y+080349X0200Y    R180 S0      
327GND              C212  -2          A18X+148918Y+080591X0198Y0197R090 S2      
317GND              VIA   -    MD0100PA00X+147718Y+080349X0200Y    R180 S0      
327GND              C207  -2          A18X+147718Y+080591X0198Y0197R090 S2      
317GND              VIA   -    MD0100PA00X+100759Y+080288X0200Y         S0      
317GND              VIA   -    MD0100PA00X+100759Y+080038X0200Y         S0      
317GND              VIA   -    MD0100PA00X+064735Y+080703X0190Y         S0      
327GND              J102  -160        A01X+064735Y+080703X0205Y0590R090 S1      
317GND              VIA   -    MD0100PA00X+060656Y+079612X0200Y         S0      
317GND              VIA   -    MD0100PA00X+059261Y+080599X0200Y         S0      
317GND              VIA   -    MD0100PA00X+059707Y+079927X0200Y    R180 S0      
327GND              C232  -2   M      A18X+059557Y+079676X0198Y0197R270 S2      
327GND              C233  -2          A18X+059947Y+079676X0198Y0197R270 S2      
317GND              VIA   -    MD0100PA00X+023397Y+080368X0190Y         S0      
327GND              J24   -15         A01X+023397Y+080368X0205Y0590R090 S1      
317GND              VIA   -    MD0100PA00X+021783Y+080703X0190Y         S0      
327GND              J24   -160        A01X+021783Y+080703X0205Y0590R090 S1      
317GND              VIA   -    MD0100PA00X+022328Y+080034X0190Y    R180 S0      
327GND              J24   -158        A01X+021783Y+080034X0205Y0590R090 S1      
317GND              VIA   -    MD0100PA00X+022852Y+079699X0190Y         S0      
327GND              J24   -13         A01X+023397Y+079699X0205Y0590R090 S1      
317GND              VIA   -    MD0100PA00X+020427Y+080368X0190Y         S0      
327GND              J26   -15         A01X+020427Y+080368X0205Y0590R090 S1      
317GND              VIA   -    MD0100PA00X+021343Y+079532X0190Y         S0      
317GND              VIA   -    MD0100PA00X+018813Y+080703X0190Y         S0      
327GND              J26   -160        A01X+018813Y+080703X0205Y0590R090 S1      
317GND              VIA   -    MD0100PA00X+019358Y+080034X0190Y    R180 S0      
327GND              J26   -158        A01X+018813Y+080034X0205Y0590R090 S1      
317GND              VIA   -    MD0100PA00X+019882Y+079699X0190Y         S0      
327GND              J26   -13         A01X+020427Y+079699X0205Y0590R090 S1      
317GND              VIA   -    MD0100PA00X+018373Y+079532X0190Y         S0      
317GND              VIA   -    MD0100PA00X+166934Y+078026X0190Y         S0      
327GND              J69   -8          A01X+166934Y+078026X0205Y0590R090 S1      
317GND              VIA   -    MD0100PA00X+166389Y+078695X0190Y         S0      
327GND              J69   -10         A01X+166934Y+078695X0205Y0590R090 S1      
317GND              VIA   -    MD0100PA00X+167374Y+079197X0190Y         S0      
317GND              VIA   -    MD0100PA00X+165320Y+078360X0190Y         S0      
327GND              J69   -153        A01X+165320Y+078360X0205Y0590R090 S1      
317GND              VIA   -    MD0100PA00X+165865Y+079030X0190Y    R180 S0      
327GND              J69   -155        A01X+165320Y+079030X0205Y0590R090 S1      
317GND              VIA   -    MD0100PA00X+163964Y+078026X0190Y         S0      
327GND              J16   -8          A01X+163964Y+078026X0205Y0590R090 S1      
317GND              VIA   -    MD0100PA00X+163419Y+078695X0190Y         S0      
327GND              J16   -10         A01X+163964Y+078695X0205Y0590R090 S1      
317GND              VIA   -    MD0100PA00X+164404Y+079197X0190Y         S0      
317GND              VIA   -    MD0100PA00X+162350Y+078360X0190Y         S0      
327GND              J16   -153        A01X+162350Y+078360X0205Y0590R090 S1      
317GND              VIA   -    MD0100PA00X+162895Y+079030X0190Y    R180 S0      
327GND              J16   -155        A01X+162350Y+079030X0205Y0590R090 S1      
317GND              VIA   -    MD0100PA00X+124675Y+078575X0200Y    R180 S0      
317GND              VIA   -    MD0100PA00X+100759Y+079198X0200Y    R180 S0      
317GND              VIA   -    MD0100PA00X+100759Y+078948X0200Y    R180 S0      
317GND              VIA   -    MD0100PA00X+100759Y+077838X0200Y    R180 S0      
317GND              VIA   -    MD0100PA00X+100759Y+078088X0200Y    R180 S0      
317GND              VIA   -    MD0100PA00X+064735Y+078360X0190Y         S0      
327GND              J102  -153        A01X+064735Y+078360X0205Y0590R090 S1      
317GND              VIA   -    MD0100PA00X+061617Y+078036X0200Y         S0      
317GND              VIA   -    MD0100PA00X+061376Y+079042X0200Y    R180 S0      
327GND              C231  -2   M      A18X+061167Y+078596X0198Y0197R270 S2      
327GND              C230  -2          A18X+060767Y+078596X0198Y0197R270 S2      
317GND              VIA   -    MD0100PA00X+023397Y+078026X0190Y         S0      
327GND              J24   -8          A01X+023397Y+078026X0205Y0590R090 S1      
317GND              VIA   -    MD0100PA00X+021783Y+078360X0190Y         S0      
327GND              J24   -153        A01X+021783Y+078360X0205Y0590R090 S1      
317GND              VIA   -    MD0100PA00X+022328Y+079030X0190Y    R180 S0      
327GND              J24   -155        A01X+021783Y+079030X0205Y0590R090 S1      
317GND              VIA   -    MD0100PA00X+022852Y+078695X0190Y         S0      
327GND              J24   -10         A01X+023397Y+078695X0205Y0590R090 S1      
317GND              VIA   -    MD0100PA00X+022957Y+079197X0190Y         S0      
317GND              VIA   -    MD0100PA00X+020427Y+078026X0190Y         S0      
327GND              J26   -8          A01X+020427Y+078026X0205Y0590R090 S1      
317GND              VIA   -    MD0100PA00X+018813Y+078360X0190Y         S0      
327GND              J26   -153        A01X+018813Y+078360X0205Y0590R090 S1      
317GND              VIA   -    MD0100PA00X+019358Y+079030X0190Y    R180 S0      
327GND              J26   -155        A01X+018813Y+079030X0205Y0590R090 S1      
317GND              VIA   -    MD0100PA00X+019882Y+078695X0190Y         S0      
327GND              J26   -10         A01X+020427Y+078695X0205Y0590R090 S1      
317GND              VIA   -    MD0100PA00X+019987Y+079197X0190Y         S0      
317GND              VIA   -    MD0100PA00X+178814Y+077356X0190Y         S0      
327GND              J67   -6          A01X+178814Y+077356X0205Y0590R090 S1      
317GND              VIA   -    MD0100PA00X+178359Y+076376X0190Y    R180 S0      
327GND              C112  -2          A18X+178359Y+076376X0198Y0197     S2      
317GND              VIA   -    MD0100PA00X+177655Y+076726X0190Y         S0      
327GND              R769  -2          A18X+177655Y+076726X0198Y0197R180 S2      
317GND              VIA   -    MD0100PA00X+175844Y+077356X0190Y         S0      
327GND              J20   -6          A01X+175844Y+077356X0205Y0590R090 S1      
317GND              VIA   -    MD0100PA00X+175389Y+076376X0190Y         S0      
327GND              C132  -2          A18X+175389Y+076376X0198Y0197     S2      
317GND              VIA   -    MD0100PA00X+174685Y+076726X0190Y         S0      
327GND              R768  -2          A18X+174685Y+076726X0198Y0197R180 S2      
317GND              VIA   -    MD0100PA00X+172874Y+077356X0190Y         S0      
327GND              J68   -6          A01X+172874Y+077356X0205Y0590R090 S1      
317GND              VIA   -    MD0100PA00X+172419Y+076376X0190Y         S0      
327GND              C128  -2          A18X+172419Y+076376X0198Y0197     S2      
317GND              VIA   -    MD0100PA00X+171715Y+076726X0190Y         S0      
327GND              R767  -2          A18X+171715Y+076726X0198Y0197R180 S2      
317GND              VIA   -    MD0100PA00X+169904Y+077356X0190Y         S0      
327GND              J18   -6          A01X+169904Y+077356X0205Y0590R090 S1      
317GND              VIA   -    MD0100PA00X+169449Y+076376X0190Y         S0      
327GND              C124  -2          A18X+169449Y+076376X0198Y0197     S2      
317GND              VIA   -    MD0100PA00X+168745Y+076726X0190Y         S0      
327GND              R766  -2          A18X+168745Y+076726X0198Y0197R180 S2      
317GND              VIA   -    MD0100PA00X+168835Y+079030X0190Y    R180 S0      
317GND              VIA   -    MD0100PA00X+168290Y+078360X0190Y         S0      
317GND              VIA   -    MD0100PA00X+168290Y+077691X0190Y         S0      
317GND              VIA   -    MD0100PA00X+168290Y+081372X0190Y         S0      
317GND              VIA   -    MD0100PA00X+168290Y+082041X0190Y         S0      
317GND              VIA   -    MD0100PA00X+168290Y+080703X0190Y         S0      
317GND              VIA   -    MD0100PA00X+168835Y+080034X0190Y    R180 S0      
317GND              VIA   -    MD0100PA00X+168730Y+079532X0190Y         S0      
317GND              VIA   -    MD0100PA00X+168290Y+084384X0190Y         S0      
317GND              VIA   -    MD0100PA00X+168290Y+085053X0190Y         S0      
317GND              VIA   -    MD0100PA00X+168835Y+083715X0190Y    R180 S0      
317GND              VIA   -    MD0100PA00X+168730Y+083213X0190Y         S0      
317GND              VIA   -    MD0100PA00X+168835Y+082711X0190Y    R180 S0      
317GND              VIA   -    MD0100PA00X+168290Y+085722X0190Y         S0      
317GND              VIA   -    MD0100PA00X+168835Y+086392X0190Y    R180 S0      
317GND              VIA   -    MD0100PA00X+168290Y+088734X0190Y         S0      
317GND              VIA   -    MD0100PA00X+168290Y+089404X0190Y         S0      
317GND              VIA   -    MD0100PA00X+168290Y+088065X0190Y         S0      
317GND              VIA   -    MD0100PA00X+168835Y+087396X0190Y    R180 S0      
317GND              VIA   -    MD0100PA00X+168730Y+086894X0190Y         S0      
317GND              VIA   -    MD0100PA00X+168290Y+092415X0190Y         S0      
317GND              VIA   -    MD0100PA00X+168290Y+091746X0190Y         S0      
317GND              VIA   -    MD0100PA00X+168835Y+090073X0190Y    R180 S0      
317GND              VIA   -    MD0100PA00X+168835Y+091077X0190Y    R180 S0      
317GND              VIA   -    MD0100PA00X+168730Y+090575X0190Y         S0      
317GND              VIA   -    MD0100PA00X+168290Y+095427X0190Y         S0      
317GND              VIA   -    MD0100PA00X+168835Y+094758X0190Y    R180 S0      
317GND              VIA   -    MD0100PA00X+168730Y+094256X0190Y         S0      
317GND              VIA   -    MD0100PA00X+168835Y+093754X0190Y    R180 S0      
317GND              VIA   -    MD0100PA00X+168290Y+093085X0190Y         S0      
317GND              VIA   -    MD0100PA00X+168290Y+097435X0190Y         S0      
317GND              VIA   -    MD0100PA00X+168290Y+098104X0190Y         S0      
317GND              VIA   -    MD0100PA00X+168290Y+096096X0190Y         S0      
317GND              VIA   -    MD0100PA00X+168290Y+096766X0190Y         S0      
317GND              VIA   -    MD0100PA00X+168290Y+100447X0190Y         S0      
317GND              VIA   -    MD0100PA00X+168290Y+098774X0190Y         S0      
317GND              VIA   -    MD0100PA00X+168290Y+099443X0190Y         S0      
317GND              VIA   -    MD0100PA00X+168290Y+107140X0190Y         S0      
317GND              VIA   -    MD0100PA00X+168290Y+106136X0190Y         S0      
317GND              VIA   -    MD0100PA00X+168290Y+104797X0190Y         S0      
317GND              VIA   -    MD0100PA00X+168290Y+105467X0190Y         S0      
317GND              VIA   -    MD0100PA00X+168290Y+103459X0190Y         S0      
317GND              VIA   -    MD0100PA00X+168290Y+104128X0190Y         S0      
317GND              VIA   -    MD0100PA00X+168290Y+111490X0190Y         S0      
317GND              VIA   -    MD0100PA00X+168290Y+110821X0190Y         S0      
317GND              VIA   -    MD0100PA00X+168290Y+110152X0190Y         S0      
317GND              VIA   -    MD0100PA00X+168835Y+109482X0190Y    R180 S0      
317GND              VIA   -    MD0100PA00X+168835Y+108478X0190Y    R180 S0      
317GND              VIA   -    MD0100PA00X+168730Y+108980X0190Y         S0      
317GND              VIA   -    MD0100PA00X+168290Y+107809X0190Y         S0      
317GND              VIA   -    MD0100PA00X+168730Y+116343X0190Y         S0      
317GND              VIA   -    MD0100PA00X+168290Y+115171X0190Y         S0      
317GND              VIA   -    MD0100PA00X+168835Y+115841X0190Y    R180 S0      
317GND              VIA   -    MD0100PA00X+168290Y+114502X0190Y         S0      
317GND              VIA   -    MD0100PA00X+168290Y+113833X0190Y         S0      
317GND              VIA   -    MD0100PA00X+168730Y+112662X0190Y         S0      
317GND              VIA   -    MD0100PA00X+168835Y+112160X0190Y    R180 S0      
317GND              VIA   -    MD0100PA00X+168835Y+113163X0190Y    R180 S0      
317GND              VIA   -    MD0100PA00X+168835Y+119522X0190Y    R180 S0      
317GND              VIA   -    MD0100PA00X+168730Y+120024X0190Y         S0      
317GND              VIA   -    MD0100PA00X+168835Y+120526X0190Y    R180 S0      
317GND              VIA   -    MD0100PA00X+168290Y+118183X0190Y         S0      
317GND              VIA   -    MD0100PA00X+168290Y+118852X0190Y         S0      
317GND              VIA   -    MD0100PA00X+168290Y+117514X0190Y         S0      
317GND              VIA   -    MD0100PA00X+168835Y+116844X0190Y    R180 S0      
317GND              VIA   -    MD0100PA00X+168290Y+125545X0190Y         S0      
317GND              VIA   -    MD0100PA00X+168835Y+124207X0190Y    R180 S0      
317GND              VIA   -    MD0100PA00X+168290Y+124876X0190Y         S0      
317GND              VIA   -    MD0100PA00X+168835Y+123203X0190Y    R180 S0      
317GND              VIA   -    MD0100PA00X+168730Y+123705X0190Y         S0      
317GND              VIA   -    MD0100PA00X+168290Y+122534X0190Y         S0      
317GND              VIA   -    MD0100PA00X+168290Y+121864X0190Y         S0      
317GND              VIA   -    MD0100PA00X+168290Y+121195X0190Y         S0      
317GND              VIA   -    MD0100PA00X+169359Y+078695X0190Y         S0      
317GND              VIA   -    MD0100PA00X+169904Y+078026X0190Y         S0      
317GND              VIA   -    MD0100PA00X+170344Y+079197X0190Y         S0      
317GND              VIA   -    MD0100PA00X+169904Y+081037X0190Y         S0      
317GND              VIA   -    MD0100PA00X+169904Y+081707X0190Y         S0      
317GND              VIA   -    MD0100PA00X+169359Y+079699X0190Y         S0      
317GND              VIA   -    MD0100PA00X+169904Y+080368X0190Y         S0      
317GND              VIA   -    MD0100PA00X+169904Y+084049X0190Y         S0      
317GND              VIA   -    MD0100PA00X+169904Y+084718X0190Y         S0      
317GND              VIA   -    MD0100PA00X+169359Y+083380X0190Y         S0      
317GND              VIA   -    MD0100PA00X+170344Y+082878X0190Y         S0      
317GND              VIA   -    MD0100PA00X+169359Y+082376X0190Y         S0      
317GND              VIA   -    MD0100PA00X+170344Y+086559X0190Y         S0      
317GND              VIA   -    MD0100PA00X+169359Y+086057X0190Y         S0      
317GND              VIA   -    MD0100PA00X+169904Y+085388X0190Y         S0      
317GND              VIA   -    MD0100PA00X+169359Y+089738X0190Y         S0      
317GND              VIA   -    MD0100PA00X+170344Y+090240X0190Y         S0      
317GND              VIA   -    MD0100PA00X+169359Y+090742X0190Y         S0      
317GND              VIA   -    MD0100PA00X+169904Y+089069X0190Y         S0      
317GND              VIA   -    MD0100PA00X+169904Y+088400X0190Y         S0      
317GND              VIA   -    MD0100PA00X+169904Y+087730X0190Y         S0      
317GND              VIA   -    MD0100PA00X+169359Y+087061X0190Y         S0      
317GND              VIA   -    MD0100PA00X+169904Y+092081X0190Y         S0      
317GND              VIA   -    MD0100PA00X+169904Y+091411X0190Y         S0      
317GND              VIA   -    MD0100PA00X+169904Y+095762X0190Y         S0      
317GND              VIA   -    MD0100PA00X+169904Y+097100X0190Y         S0      
317GND              VIA   -    MD0100PA00X+169904Y+096431X0190Y         S0      
317GND              VIA   -    MD0100PA00X+169904Y+095092X0190Y         S0      
317GND              VIA   -    MD0100PA00X+169359Y+094423X0190Y         S0      
317GND              VIA   -    MD0100PA00X+170344Y+093921X0190Y         S0      
317GND              VIA   -    MD0100PA00X+169904Y+092750X0190Y         S0      
317GND              VIA   -    MD0100PA00X+169359Y+093419X0190Y         S0      
317GND              VIA   -    MD0100PA00X+169904Y+099108X0190Y         S0      
317GND              VIA   -    MD0100PA00X+169904Y+099778X0190Y         S0      
317GND              VIA   -    MD0100PA00X+169904Y+098439X0190Y         S0      
317GND              VIA   -    MD0100PA00X+169904Y+097770X0190Y         S0      
317GND              VIA   -    MD0100PA00X+169904Y+103124X0190Y         S0      
317GND              VIA   -    MD0100PA00X+169904Y+103793X0190Y         S0      
317GND              VIA   -    MD0100PA00X+169904Y+104463X0190Y         S0      
317GND              VIA   -    MD0100PA00X+169904Y+100447X0190Y         S0      
317GND              VIA   -    MD0100PA00X+169359Y+108144X0190Y         S0      
317GND              VIA   -    MD0100PA00X+170344Y+108646X0190Y         S0      
317GND              VIA   -    MD0100PA00X+169904Y+106805X0190Y         S0      
317GND              VIA   -    MD0100PA00X+169904Y+107474X0190Y         S0      
317GND              VIA   -    MD0100PA00X+169904Y+105132X0190Y         S0      
317GND              VIA   -    MD0100PA00X+169904Y+105801X0190Y         S0      
317GND              VIA   -    MD0100PA00X+169359Y+112829X0190Y         S0      
317GND              VIA   -    MD0100PA00X+170344Y+112327X0190Y         S0      
317GND              VIA   -    MD0100PA00X+169904Y+113498X0190Y         S0      
317GND              VIA   -    MD0100PA00X+169359Y+111825X0190Y         S0      
317GND              VIA   -    MD0100PA00X+169904Y+111156X0190Y         S0      
317GND              VIA   -    MD0100PA00X+169904Y+109817X0190Y         S0      
317GND              VIA   -    MD0100PA00X+169904Y+110486X0190Y         S0      
317GND              VIA   -    MD0100PA00X+169359Y+109148X0190Y         S0      
317GND              VIA   -    MD0100PA00X+169904Y+117848X0190Y         S0      
317GND              VIA   -    MD0100PA00X+169904Y+117179X0190Y         S0      
317GND              VIA   -    MD0100PA00X+170344Y+116008X0190Y         S0      
317GND              VIA   -    MD0100PA00X+169359Y+116510X0190Y         S0      
317GND              VIA   -    MD0100PA00X+169359Y+115506X0190Y         S0      
317GND              VIA   -    MD0100PA00X+169904Y+114837X0190Y         S0      
317GND              VIA   -    MD0100PA00X+169904Y+114167X0190Y         S0      
317GND              VIA   -    MD0100PA00X+169904Y+121530X0190Y         S0      
317GND              VIA   -    MD0100PA00X+169904Y+122199X0190Y         S0      
317GND              VIA   -    MD0100PA00X+169904Y+120860X0190Y         S0      
317GND              VIA   -    MD0100PA00X+170344Y+119689X0190Y         S0      
317GND              VIA   -    MD0100PA00X+169359Y+120191X0190Y         S0      
317GND              VIA   -    MD0100PA00X+169904Y+118518X0190Y         S0      
317GND              VIA   -    MD0100PA00X+169359Y+119187X0190Y         S0      
317GND              VIA   -    MD0100PA00X+169904Y+125211X0190Y         S0      
317GND              VIA   -    MD0100PA00X+169904Y+124541X0190Y         S0      
317GND              VIA   -    MD0100PA00X+170344Y+123370X0190Y         S0      
317GND              VIA   -    MD0100PA00X+169359Y+123872X0190Y         S0      
317GND              VIA   -    MD0100PA00X+169359Y+122868X0190Y         S0      
317GND              VIA   -    MD0100PA00X+171260Y+077691X0190Y         S0      
317GND              VIA   -    MD0100PA00X+171805Y+080034X0190Y    R180 S0      
317GND              VIA   -    MD0100PA00X+171700Y+079532X0190Y         S0      
317GND              VIA   -    MD0100PA00X+171260Y+078360X0190Y         S0      
317GND              VIA   -    MD0100PA00X+171805Y+079030X0190Y    R180 S0      
317GND              VIA   -    MD0100PA00X+171260Y+081372X0190Y         S0      
317GND              VIA   -    MD0100PA00X+171260Y+082041X0190Y         S0      
317GND              VIA   -    MD0100PA00X+171260Y+080703X0190Y         S0      
317GND              VIA   -    MD0100PA00X+171260Y+084384X0190Y         S0      
317GND              VIA   -    MD0100PA00X+171260Y+085053X0190Y         S0      
317GND              VIA   -    MD0100PA00X+171805Y+083715X0190Y    R180 S0      
317GND              VIA   -    MD0100PA00X+171700Y+083213X0190Y         S0      
317GND              VIA   -    MD0100PA00X+171805Y+082711X0190Y    R180 S0      
317GND              VIA   -    MD0100PA00X+171805Y+087396X0190Y    R180 S0      
317GND              VIA   -    MD0100PA00X+171260Y+088065X0190Y         S0      
317GND              VIA   -    MD0100PA00X+171700Y+086894X0190Y         S0      
317GND              VIA   -    MD0100PA00X+171260Y+085722X0190Y         S0      
317GND              VIA   -    MD0100PA00X+171805Y+086392X0190Y    R180 S0      
317GND              VIA   -    MD0100PA00X+171805Y+090073X0190Y    R180 S0      
317GND              VIA   -    MD0100PA00X+171805Y+091077X0190Y    R180 S0      
317GND              VIA   -    MD0100PA00X+171700Y+090575X0190Y         S0      
317GND              VIA   -    MD0100PA00X+171260Y+088734X0190Y         S0      
317GND              VIA   -    MD0100PA00X+171260Y+089404X0190Y         S0      
317GND              VIA   -    MD0100PA00X+171805Y+093754X0190Y    R180 S0      
317GND              VIA   -    MD0100PA00X+171260Y+093085X0190Y         S0      
317GND              VIA   -    MD0100PA00X+171260Y+092415X0190Y         S0      
317GND              VIA   -    MD0100PA00X+171260Y+091746X0190Y         S0      
317GND              VIA   -    MD0100PA00X+171260Y+096096X0190Y         S0      
317GND              VIA   -    MD0100PA00X+171260Y+096766X0190Y         S0      
317GND              VIA   -    MD0100PA00X+171260Y+095427X0190Y         S0      
317GND              VIA   -    MD0100PA00X+171805Y+094758X0190Y    R180 S0      
317GND              VIA   -    MD0100PA00X+171700Y+094256X0190Y         S0      
317GND              VIA   -    MD0100PA00X+171260Y+098774X0190Y         S0      
317GND              VIA   -    MD0100PA00X+171260Y+099443X0190Y         S0      
317GND              VIA   -    MD0100PA00X+171260Y+097435X0190Y         S0      
317GND              VIA   -    MD0100PA00X+171260Y+098104X0190Y         S0      
317GND              VIA   -    MD0100PA00X+171260Y+104797X0190Y         S0      
317GND              VIA   -    MD0100PA00X+171260Y+105467X0190Y         S0      
317GND              VIA   -    MD0100PA00X+171260Y+103459X0190Y         S0      
317GND              VIA   -    MD0100PA00X+171260Y+104128X0190Y         S0      
317GND              VIA   -    MD0100PA00X+171260Y+100447X0190Y         S0      
317GND              VIA   -    MD0100PA00X+171260Y+110152X0190Y         S0      
317GND              VIA   -    MD0100PA00X+171805Y+109482X0190Y    R180 S0      
317GND              VIA   -    MD0100PA00X+171805Y+108478X0190Y    R180 S0      
317GND              VIA   -    MD0100PA00X+171700Y+108980X0190Y         S0      
317GND              VIA   -    MD0100PA00X+171260Y+107809X0190Y         S0      
317GND              VIA   -    MD0100PA00X+171260Y+107140X0190Y         S0      
317GND              VIA   -    MD0100PA00X+171260Y+106136X0190Y         S0      
317GND              VIA   -    MD0100PA00X+171260Y+114502X0190Y         S0      
317GND              VIA   -    MD0100PA00X+171260Y+113833X0190Y         S0      
317GND              VIA   -    MD0100PA00X+171700Y+112662X0190Y         S0      
317GND              VIA   -    MD0100PA00X+171805Y+112160X0190Y    R180 S0      
317GND              VIA   -    MD0100PA00X+171805Y+113163X0190Y    R180 S0      
317GND              VIA   -    MD0100PA00X+171260Y+111490X0190Y         S0      
317GND              VIA   -    MD0100PA00X+171260Y+110821X0190Y         S0      
317GND              VIA   -    MD0100PA00X+171700Y+120024X0190Y         S0      
317GND              VIA   -    MD0100PA00X+171805Y+120526X0190Y    R180 S0      
317GND              VIA   -    MD0100PA00X+171260Y+118183X0190Y         S0      
317GND              VIA   -    MD0100PA00X+171260Y+118852X0190Y         S0      
317GND              VIA   -    MD0100PA00X+171260Y+117514X0190Y         S0      
317GND              VIA   -    MD0100PA00X+171805Y+116844X0190Y    R180 S0      
317GND              VIA   -    MD0100PA00X+171700Y+116343X0190Y         S0      
317GND              VIA   -    MD0100PA00X+171260Y+115171X0190Y         S0      
317GND              VIA   -    MD0100PA00X+171805Y+115841X0190Y    R180 S0      
317GND              VIA   -    MD0100PA00X+171260Y+125545X0190Y         S0      
317GND              VIA   -    MD0100PA00X+171805Y+124207X0190Y    R180 S0      
317GND              VIA   -    MD0100PA00X+171260Y+124876X0190Y         S0      
317GND              VIA   -    MD0100PA00X+171805Y+123203X0190Y    R180 S0      
317GND              VIA   -    MD0100PA00X+171700Y+123705X0190Y         S0      
317GND              VIA   -    MD0100PA00X+171260Y+122534X0190Y         S0      
317GND              VIA   -    MD0100PA00X+171260Y+121195X0190Y         S0      
317GND              VIA   -    MD0100PA00X+171260Y+121864X0190Y         S0      
317GND              VIA   -    MD0100PA00X+171805Y+119522X0190Y    R180 S0      
317GND              VIA   -    MD0100PA00X+172329Y+079699X0190Y         S0      
317GND              VIA   -    MD0100PA00X+172874Y+080368X0190Y         S0      
317GND              VIA   -    MD0100PA00X+172874Y+078026X0190Y         S0      
317GND              VIA   -    MD0100PA00X+172329Y+078695X0190Y         S0      
317GND              VIA   -    MD0100PA00X+173314Y+079197X0190Y         S0      
317GND              VIA   -    MD0100PA00X+172329Y+083380X0190Y         S0      
317GND              VIA   -    MD0100PA00X+172329Y+082376X0190Y         S0      
317GND              VIA   -    MD0100PA00X+173314Y+082878X0190Y         S0      
317GND              VIA   -    MD0100PA00X+172874Y+081037X0190Y         S0      
317GND              VIA   -    MD0100PA00X+172874Y+081707X0190Y         S0      
317GND              VIA   -    MD0100PA00X+172329Y+086057X0190Y         S0      
317GND              VIA   -    MD0100PA00X+173314Y+086559X0190Y         S0      
317GND              VIA   -    MD0100PA00X+172874Y+085388X0190Y         S0      
317GND              VIA   -    MD0100PA00X+172874Y+084049X0190Y         S0      
317GND              VIA   -    MD0100PA00X+172874Y+084718X0190Y         S0      
317GND              VIA   -    MD0100PA00X+172329Y+089738X0190Y         S0      
317GND              VIA   -    MD0100PA00X+173314Y+090240X0190Y         S0      
317GND              VIA   -    MD0100PA00X+172329Y+090742X0190Y         S0      
317GND              VIA   -    MD0100PA00X+172874Y+089069X0190Y         S0      
317GND              VIA   -    MD0100PA00X+172874Y+088400X0190Y         S0      
317GND              VIA   -    MD0100PA00X+172874Y+087730X0190Y         S0      
317GND              VIA   -    MD0100PA00X+172329Y+087061X0190Y         S0      
317GND              VIA   -    MD0100PA00X+173314Y+093921X0190Y         S0      
317GND              VIA   -    MD0100PA00X+172874Y+092750X0190Y         S0      
317GND              VIA   -    MD0100PA00X+172329Y+093419X0190Y         S0      
317GND              VIA   -    MD0100PA00X+172874Y+092081X0190Y         S0      
317GND              VIA   -    MD0100PA00X+172874Y+091411X0190Y         S0      
317GND              VIA   -    MD0100PA00X+172874Y+095762X0190Y         S0      
317GND              VIA   -    MD0100PA00X+172874Y+097100X0190Y         S0      
317GND              VIA   -    MD0100PA00X+172874Y+096431X0190Y         S0      
317GND              VIA   -    MD0100PA00X+172874Y+095092X0190Y         S0      
317GND              VIA   -    MD0100PA00X+172329Y+094423X0190Y         S0      
317GND              VIA   -    MD0100PA00X+172874Y+100447X0190Y         S0      
317GND              VIA   -    MD0100PA00X+172874Y+099108X0190Y         S0      
317GND              VIA   -    MD0100PA00X+172874Y+099778X0190Y         S0      
317GND              VIA   -    MD0100PA00X+172874Y+098439X0190Y         S0      
317GND              VIA   -    MD0100PA00X+172874Y+097770X0190Y         S0      
317GND              VIA   -    MD0100PA00X+172874Y+105132X0190Y         S0      
317GND              VIA   -    MD0100PA00X+172874Y+105801X0190Y         S0      
317GND              VIA   -    MD0100PA00X+172874Y+103124X0190Y         S0      
317GND              VIA   -    MD0100PA00X+172874Y+103793X0190Y         S0      
317GND              VIA   -    MD0100PA00X+172874Y+104463X0190Y         S0      
317GND              VIA   -    MD0100PA00X+172874Y+109817X0190Y         S0      
317GND              VIA   -    MD0100PA00X+172874Y+110486X0190Y         S0      
317GND              VIA   -    MD0100PA00X+172329Y+109148X0190Y         S0      
317GND              VIA   -    MD0100PA00X+172329Y+108144X0190Y         S0      
317GND              VIA   -    MD0100PA00X+173314Y+108646X0190Y         S0      
317GND              VIA   -    MD0100PA00X+172874Y+106805X0190Y         S0      
317GND              VIA   -    MD0100PA00X+172874Y+107474X0190Y         S0      
317GND              VIA   -    MD0100PA00X+172874Y+114837X0190Y         S0      
317GND              VIA   -    MD0100PA00X+172874Y+114167X0190Y         S0      
317GND              VIA   -    MD0100PA00X+172329Y+112829X0190Y         S0      
317GND              VIA   -    MD0100PA00X+173314Y+112327X0190Y         S0      
317GND              VIA   -    MD0100PA00X+172874Y+113498X0190Y         S0      
317GND              VIA   -    MD0100PA00X+172329Y+111825X0190Y         S0      
317GND              VIA   -    MD0100PA00X+172874Y+111156X0190Y         S0      
317GND              VIA   -    MD0100PA00X+172874Y+118518X0190Y         S0      
317GND              VIA   -    MD0100PA00X+172329Y+119187X0190Y         S0      
317GND              VIA   -    MD0100PA00X+172874Y+117848X0190Y         S0      
317GND              VIA   -    MD0100PA00X+172874Y+117179X0190Y         S0      
317GND              VIA   -    MD0100PA00X+172329Y+116510X0190Y         S0      
317GND              VIA   -    MD0100PA00X+173314Y+116008X0190Y         S0      
317GND              VIA   -    MD0100PA00X+172329Y+115506X0190Y         S0      
317GND              VIA   -    MD0100PA00X+172329Y+123872X0190Y         S0      
317GND              VIA   -    MD0100PA00X+172329Y+122868X0190Y         S0      
317GND              VIA   -    MD0100PA00X+173314Y+123370X0190Y         S0      
317GND              VIA   -    MD0100PA00X+172874Y+121530X0190Y         S0      
317GND              VIA   -    MD0100PA00X+172874Y+122199X0190Y         S0      
317GND              VIA   -    MD0100PA00X+172874Y+120860X0190Y         S0      
317GND              VIA   -    MD0100PA00X+173314Y+119689X0190Y         S0      
317GND              VIA   -    MD0100PA00X+172329Y+120191X0190Y         S0      
317GND              VIA   -    MD0100PA00X+172874Y+125211X0190Y         S0      
317GND              VIA   -    MD0100PA00X+172874Y+124541X0190Y         S0      
317GND              VIA   -    MD0100PA00X+174775Y+079030X0190Y    R180 S0      
317GND              VIA   -    MD0100PA00X+174230Y+078360X0190Y         S0      
317GND              VIA   -    MD0100PA00X+174230Y+077691X0190Y         S0      
317GND              VIA   -    MD0100PA00X+174230Y+081372X0190Y         S0      
317GND              VIA   -    MD0100PA00X+174230Y+082041X0190Y         S0      
317GND              VIA   -    MD0100PA00X+174230Y+080703X0190Y         S0      
317GND              VIA   -    MD0100PA00X+174775Y+080034X0190Y    R180 S0      
317GND              VIA   -    MD0100PA00X+174670Y+079532X0190Y         S0      
317GND              VIA   -    MD0100PA00X+174230Y+084384X0190Y         S0      
317GND              VIA   -    MD0100PA00X+174230Y+085053X0190Y         S0      
317GND              VIA   -    MD0100PA00X+174775Y+083715X0190Y    R180 S0      
317GND              VIA   -    MD0100PA00X+174670Y+083213X0190Y         S0      
317GND              VIA   -    MD0100PA00X+174775Y+082711X0190Y    R180 S0      
317GND              VIA   -    MD0100PA00X+174230Y+088065X0190Y         S0      
317GND              VIA   -    MD0100PA00X+174775Y+087396X0190Y    R180 S0      
317GND              VIA   -    MD0100PA00X+174670Y+086894X0190Y         S0      
317GND              VIA   -    MD0100PA00X+174230Y+085722X0190Y         S0      
317GND              VIA   -    MD0100PA00X+174775Y+086392X0190Y    R180 S0      
317GND              VIA   -    MD0100PA00X+174775Y+090073X0190Y    R180 S0      
317GND              VIA   -    MD0100PA00X+174775Y+091077X0190Y    R180 S0      
317GND              VIA   -    MD0100PA00X+174670Y+090575X0190Y         S0      
317GND              VIA   -    MD0100PA00X+174230Y+088734X0190Y         S0      
317GND              VIA   -    MD0100PA00X+174230Y+089404X0190Y         S0      
317GND              VIA   -    MD0100PA00X+174775Y+093754X0190Y    R180 S0      
317GND              VIA   -    MD0100PA00X+174230Y+093085X0190Y         S0      
317GND              VIA   -    MD0100PA00X+174230Y+092415X0190Y         S0      
317GND              VIA   -    MD0100PA00X+174230Y+091746X0190Y         S0      
317GND              VIA   -    MD0100PA00X+174230Y+096766X0190Y         S0      
317GND              VIA   -    MD0100PA00X+174230Y+095427X0190Y         S0      
317GND              VIA   -    MD0100PA00X+174775Y+094758X0190Y    R180 S0      
317GND              VIA   -    MD0100PA00X+174670Y+094256X0190Y         S0      
317GND              VIA   -    MD0100PA00X+174230Y+098774X0190Y         S0      
317GND              VIA   -    MD0100PA00X+174230Y+099443X0190Y         S0      
317GND              VIA   -    MD0100PA00X+174230Y+097435X0190Y         S0      
317GND              VIA   -    MD0100PA00X+174230Y+098104X0190Y         S0      
317GND              VIA   -    MD0100PA00X+174230Y+096096X0190Y         S0      
317GND              VIA   -    MD0100PA00X+174230Y+103459X0190Y         S0      
317GND              VIA   -    MD0100PA00X+174230Y+104128X0190Y         S0      
317GND              VIA   -    MD0100PA00X+174230Y+100447X0190Y         S0      
317GND              VIA   -    MD0100PA00X+174775Y+108478X0190Y    R180 S0      
317GND              VIA   -    MD0100PA00X+174670Y+108980X0190Y         S0      
317GND              VIA   -    MD0100PA00X+174230Y+107809X0190Y         S0      
317GND              VIA   -    MD0100PA00X+174230Y+107140X0190Y         S0      
317GND              VIA   -    MD0100PA00X+174230Y+106136X0190Y         S0      
317GND              VIA   -    MD0100PA00X+174230Y+104797X0190Y         S0      
317GND              VIA   -    MD0100PA00X+174230Y+105467X0190Y         S0      
317GND              VIA   -    MD0100PA00X+174230Y+111490X0190Y         S0      
317GND              VIA   -    MD0100PA00X+174230Y+110821X0190Y         S0      
317GND              VIA   -    MD0100PA00X+174230Y+110152X0190Y         S0      
317GND              VIA   -    MD0100PA00X+174775Y+109482X0190Y    R180 S0      
317GND              VIA   -    MD0100PA00X+174230Y+114502X0190Y         S0      
317GND              VIA   -    MD0100PA00X+174230Y+113833X0190Y         S0      
317GND              VIA   -    MD0100PA00X+174670Y+112662X0190Y         S0      
317GND              VIA   -    MD0100PA00X+174775Y+112160X0190Y    R180 S0      
317GND              VIA   -    MD0100PA00X+174775Y+113163X0190Y    R180 S0      
317GND              VIA   -    MD0100PA00X+174670Y+116343X0190Y         S0      
317GND              VIA   -    MD0100PA00X+174230Y+115171X0190Y         S0      
317GND              VIA   -    MD0100PA00X+174775Y+115841X0190Y    R180 S0      
317GND              VIA   -    MD0100PA00X+174230Y+118183X0190Y         S0      
317GND              VIA   -    MD0100PA00X+174230Y+118852X0190Y         S0      
317GND              VIA   -    MD0100PA00X+174230Y+117514X0190Y         S0      
317GND              VIA   -    MD0100PA00X+174775Y+116844X0190Y    R180 S0      
317GND              VIA   -    MD0100PA00X+174230Y+121195X0190Y         S0      
317GND              VIA   -    MD0100PA00X+174230Y+121864X0190Y         S0      
317GND              VIA   -    MD0100PA00X+174775Y+119522X0190Y    R180 S0      
317GND              VIA   -    MD0100PA00X+174670Y+120024X0190Y         S0      
317GND              VIA   -    MD0100PA00X+174775Y+120526X0190Y    R180 S0      
317GND              VIA   -    MD0100PA00X+174230Y+125545X0190Y         S0      
317GND              VIA   -    MD0100PA00X+174775Y+124207X0190Y    R180 S0      
317GND              VIA   -    MD0100PA00X+174230Y+124876X0190Y         S0      
317GND              VIA   -    MD0100PA00X+174775Y+123203X0190Y    R180 S0      
317GND              VIA   -    MD0100PA00X+174670Y+123705X0190Y         S0      
317GND              VIA   -    MD0100PA00X+174230Y+122534X0190Y         S0      
317GND              VIA   -    MD0100PA00X+175299Y+079699X0190Y         S0      
317GND              VIA   -    MD0100PA00X+175844Y+078026X0190Y         S0      
317GND              VIA   -    MD0100PA00X+175299Y+078695X0190Y         S0      
317GND              VIA   -    MD0100PA00X+176284Y+079197X0190Y         S0      
317GND              VIA   -    MD0100PA00X+176284Y+082878X0190Y         S0      
317GND              VIA   -    MD0100PA00X+175299Y+083380X0190Y         S0      
317GND              VIA   -    MD0100PA00X+175299Y+082376X0190Y         S0      
317GND              VIA   -    MD0100PA00X+175844Y+081037X0190Y         S0      
317GND              VIA   -    MD0100PA00X+175844Y+081707X0190Y         S0      
317GND              VIA   -    MD0100PA00X+175844Y+080368X0190Y         S0      
317GND              VIA   -    MD0100PA00X+176284Y+086559X0190Y         S0      
317GND              VIA   -    MD0100PA00X+175844Y+085388X0190Y         S0      
317GND              VIA   -    MD0100PA00X+175299Y+086057X0190Y         S0      
317GND              VIA   -    MD0100PA00X+175844Y+084049X0190Y         S0      
317GND              VIA   -    MD0100PA00X+175844Y+084718X0190Y         S0      
317GND              VIA   -    MD0100PA00X+175844Y+089069X0190Y         S0      
317GND              VIA   -    MD0100PA00X+175844Y+088400X0190Y         S0      
317GND              VIA   -    MD0100PA00X+175844Y+087730X0190Y         S0      
317GND              VIA   -    MD0100PA00X+175299Y+087061X0190Y         S0      
317GND              VIA   -    MD0100PA00X+175844Y+092081X0190Y         S0      
317GND              VIA   -    MD0100PA00X+175844Y+091411X0190Y         S0      
317GND              VIA   -    MD0100PA00X+176284Y+090240X0190Y         S0      
317GND              VIA   -    MD0100PA00X+175299Y+089738X0190Y         S0      
317GND              VIA   -    MD0100PA00X+175299Y+090742X0190Y         S0      
317GND              VIA   -    MD0100PA00X+175844Y+095762X0190Y         S0      
317GND              VIA   -    MD0100PA00X+175844Y+097100X0190Y         S0      
317GND              VIA   -    MD0100PA00X+175844Y+096431X0190Y         S0      
317GND              VIA   -    MD0100PA00X+175844Y+095092X0190Y         S0      
317GND              VIA   -    MD0100PA00X+175299Y+094423X0190Y         S0      
317GND              VIA   -    MD0100PA00X+176284Y+093921X0190Y         S0      
317GND              VIA   -    MD0100PA00X+175844Y+092750X0190Y         S0      
317GND              VIA   -    MD0100PA00X+175299Y+093419X0190Y         S0      
317GND              VIA   -    MD0100PA00X+175844Y+100447X0190Y         S0      
317GND              VIA   -    MD0100PA00X+175844Y+099108X0190Y         S0      
317GND              VIA   -    MD0100PA00X+175844Y+099778X0190Y         S0      
317GND              VIA   -    MD0100PA00X+175844Y+098439X0190Y         S0      
317GND              VIA   -    MD0100PA00X+175844Y+097770X0190Y         S0      
317GND              VIA   -    MD0100PA00X+175844Y+103124X0190Y         S0      
317GND              VIA   -    MD0100PA00X+175844Y+103793X0190Y         S0      
317GND              VIA   -    MD0100PA00X+175844Y+104463X0190Y         S0      
317GND              VIA   -    MD0100PA00X+175844Y+106805X0190Y         S0      
317GND              VIA   -    MD0100PA00X+175844Y+107474X0190Y         S0      
317GND              VIA   -    MD0100PA00X+175844Y+105132X0190Y         S0      
317GND              VIA   -    MD0100PA00X+175844Y+105801X0190Y         S0      
317GND              VIA   -    MD0100PA00X+175844Y+111156X0190Y         S0      
317GND              VIA   -    MD0100PA00X+175299Y+111825X0190Y         S0      
317GND              VIA   -    MD0100PA00X+175844Y+109817X0190Y         S0      
317GND              VIA   -    MD0100PA00X+175844Y+110486X0190Y         S0      
317GND              VIA   -    MD0100PA00X+175299Y+109148X0190Y         S0      
317GND              VIA   -    MD0100PA00X+176284Y+108646X0190Y         S0      
317GND              VIA   -    MD0100PA00X+175299Y+108144X0190Y         S0      
317GND              VIA   -    MD0100PA00X+175844Y+114837X0190Y         S0      
317GND              VIA   -    MD0100PA00X+175844Y+114167X0190Y         S0      
317GND              VIA   -    MD0100PA00X+176284Y+112327X0190Y         S0      
317GND              VIA   -    MD0100PA00X+175299Y+112829X0190Y         S0      
317GND              VIA   -    MD0100PA00X+175844Y+113498X0190Y         S0      
317GND              VIA   -    MD0100PA00X+175844Y+117848X0190Y         S0      
317GND              VIA   -    MD0100PA00X+175844Y+117179X0190Y         S0      
317GND              VIA   -    MD0100PA00X+176284Y+116008X0190Y         S0      
317GND              VIA   -    MD0100PA00X+175299Y+116510X0190Y         S0      
317GND              VIA   -    MD0100PA00X+175299Y+115506X0190Y         S0      
317GND              VIA   -    MD0100PA00X+175844Y+120860X0190Y         S0      
317GND              VIA   -    MD0100PA00X+176284Y+119689X0190Y         S0      
317GND              VIA   -    MD0100PA00X+175299Y+120191X0190Y         S0      
317GND              VIA   -    MD0100PA00X+175844Y+118518X0190Y         S0      
317GND              VIA   -    MD0100PA00X+175299Y+119187X0190Y         S0      
317GND              VIA   -    MD0100PA00X+175844Y+125211X0190Y         S0      
317GND              VIA   -    MD0100PA00X+175844Y+124541X0190Y         S0      
317GND              VIA   -    MD0100PA00X+176284Y+123370X0190Y         S0      
317GND              VIA   -    MD0100PA00X+175299Y+123872X0190Y         S0      
317GND              VIA   -    MD0100PA00X+175299Y+122868X0190Y         S0      
317GND              VIA   -    MD0100PA00X+175844Y+121530X0190Y         S0      
317GND              VIA   -    MD0100PA00X+175844Y+122199X0190Y         S0      
317GND              VIA   -    MD0100PA00X+177200Y+078360X0190Y         S0      
317GND              VIA   -    MD0100PA00X+177745Y+079030X0190Y    R180 S0      
317GND              VIA   -    MD0100PA00X+177200Y+077691X0190Y         S0      
317GND              VIA   -    MD0100PA00X+177200Y+082041X0190Y         S0      
317GND              VIA   -    MD0100PA00X+177200Y+081372X0190Y         S0      
317GND              VIA   -    MD0100PA00X+177745Y+080034X0190Y    R180 S0      
317GND              VIA   -    MD0100PA00X+177640Y+079532X0190Y         S0      
317GND              VIA   -    MD0100PA00X+177200Y+080703X0190Y         S0      
317GND              VIA   -    MD0100PA00X+177200Y+084384X0190Y         S0      
317GND              VIA   -    MD0100PA00X+177200Y+085053X0190Y         S0      
317GND              VIA   -    MD0100PA00X+177745Y+083715X0190Y    R180 S0      
317GND              VIA   -    MD0100PA00X+177640Y+083213X0190Y         S0      
317GND              VIA   -    MD0100PA00X+177745Y+082711X0190Y    R180 S0      
317GND              VIA   -    MD0100PA00X+177745Y+087396X0190Y    R180 S0      
317GND              VIA   -    MD0100PA00X+177200Y+088065X0190Y         S0      
317GND              VIA   -    MD0100PA00X+177640Y+086894X0190Y         S0      
317GND              VIA   -    MD0100PA00X+177745Y+086392X0190Y    R180 S0      
317GND              VIA   -    MD0100PA00X+177200Y+085722X0190Y         S0      
317GND              VIA   -    MD0100PA00X+177745Y+090073X0190Y    R180 S0      
317GND              VIA   -    MD0100PA00X+177745Y+091077X0190Y    R180 S0      
317GND              VIA   -    MD0100PA00X+177640Y+090575X0190Y         S0      
317GND              VIA   -    MD0100PA00X+177200Y+088734X0190Y         S0      
317GND              VIA   -    MD0100PA00X+177200Y+089404X0190Y         S0      
317GND              VIA   -    MD0100PA00X+177745Y+093754X0190Y    R180 S0      
317GND              VIA   -    MD0100PA00X+177200Y+093085X0190Y         S0      
317GND              VIA   -    MD0100PA00X+177200Y+092415X0190Y         S0      
317GND              VIA   -    MD0100PA00X+177200Y+091746X0190Y         S0      
317GND              VIA   -    MD0100PA00X+177200Y+097435X0190Y         S0      
317GND              VIA   -    MD0100PA00X+177200Y+098104X0190Y         S0      
317GND              VIA   -    MD0100PA00X+177200Y+096096X0190Y         S0      
317GND              VIA   -    MD0100PA00X+177200Y+096766X0190Y         S0      
317GND              VIA   -    MD0100PA00X+177200Y+095427X0190Y         S0      
317GND              VIA   -    MD0100PA00X+177745Y+094758X0190Y    R180 S0      
317GND              VIA   -    MD0100PA00X+177640Y+094256X0190Y         S0      
317GND              VIA   -    MD0100PA00X+177200Y+100447X0190Y         S0      
317GND              VIA   -    MD0100PA00X+177200Y+098774X0190Y         S0      
317GND              VIA   -    MD0100PA00X+177200Y+099443X0190Y         S0      
317GND              VIA   -    MD0100PA00X+177200Y+107140X0190Y         S0      
317GND              VIA   -    MD0100PA00X+177200Y+106136X0190Y         S0      
317GND              VIA   -    MD0100PA00X+177200Y+105467X0190Y         S0      
317GND              VIA   -    MD0100PA00X+177200Y+104797X0190Y         S0      
317GND              VIA   -    MD0100PA00X+177200Y+103459X0190Y         S0      
317GND              VIA   -    MD0100PA00X+177200Y+104128X0190Y         S0      
317GND              VIA   -    MD0100PA00X+177200Y+110152X0190Y         S0      
317GND              VIA   -    MD0100PA00X+177745Y+109482X0190Y    R180 S0      
317GND              VIA   -    MD0100PA00X+177745Y+108478X0190Y    R180 S0      
317GND              VIA   -    MD0100PA00X+177640Y+108980X0190Y         S0      
317GND              VIA   -    MD0100PA00X+177200Y+107809X0190Y         S0      
317GND              VIA   -    MD0100PA00X+177640Y+112662X0190Y         S0      
317GND              VIA   -    MD0100PA00X+177745Y+112160X0190Y    R180 S0      
317GND              VIA   -    MD0100PA00X+177745Y+113163X0190Y    R180 S0      
317GND              VIA   -    MD0100PA00X+177200Y+111490X0190Y         S0      
317GND              VIA   -    MD0100PA00X+177200Y+110821X0190Y         S0      
317GND              VIA   -    MD0100PA00X+177640Y+116343X0190Y         S0      
317GND              VIA   -    MD0100PA00X+177745Y+115841X0190Y    R180 S0      
317GND              VIA   -    MD0100PA00X+177200Y+115171X0190Y         S0      
317GND              VIA   -    MD0100PA00X+177200Y+114502X0190Y         S0      
317GND              VIA   -    MD0100PA00X+177200Y+113833X0190Y         S0      
317GND              VIA   -    MD0100PA00X+177200Y+118183X0190Y         S0      
317GND              VIA   -    MD0100PA00X+177200Y+118852X0190Y         S0      
317GND              VIA   -    MD0100PA00X+177200Y+117514X0190Y         S0      
317GND              VIA   -    MD0100PA00X+177745Y+116844X0190Y    R180 S0      
317GND              VIA   -    MD0100PA00X+177200Y+121195X0190Y         S0      
317GND              VIA   -    MD0100PA00X+177200Y+121864X0190Y         S0      
317GND              VIA   -    MD0100PA00X+177745Y+119522X0190Y    R180 S0      
317GND              VIA   -    MD0100PA00X+177640Y+120024X0190Y         S0      
317GND              VIA   -    MD0100PA00X+177745Y+120526X0190Y    R180 S0      
317GND              VIA   -    MD0100PA00X+177200Y+125545X0190Y         S0      
317GND              VIA   -    MD0100PA00X+177745Y+124207X0190Y    R180 S0      
317GND              VIA   -    MD0100PA00X+177200Y+124876X0190Y         S0      
317GND              VIA   -    MD0100PA00X+177745Y+123203X0190Y    R180 S0      
317GND              VIA   -    MD0100PA00X+177640Y+123705X0190Y         S0      
317GND              VIA   -    MD0100PA00X+177200Y+122534X0190Y         S0      
317GND              VIA   -    MD0100PA00X+178814Y+078026X0190Y         S0      
317GND              VIA   -    MD0100PA00X+178269Y+078695X0190Y         S0      
317GND              VIA   -    MD0100PA00X+179254Y+079197X0190Y         S0      
317GND              VIA   -    MD0100PA00X+178814Y+081037X0190Y         S0      
317GND              VIA   -    MD0100PA00X+178814Y+081707X0190Y         S0      
317GND              VIA   -    MD0100PA00X+178814Y+080368X0190Y         S0      
317GND              VIA   -    MD0100PA00X+178269Y+079699X0190Y         S0      
317GND              VIA   -    MD0100PA00X+178269Y+086057X0190Y         S0      
317GND              VIA   -    MD0100PA00X+178814Y+084049X0190Y         S0      
317GND              VIA   -    MD0100PA00X+178814Y+084718X0190Y         S0      
317GND              VIA   -    MD0100PA00X+179254Y+082878X0190Y         S0      
317GND              VIA   -    MD0100PA00X+178269Y+083380X0190Y         S0      
317GND              VIA   -    MD0100PA00X+178269Y+082376X0190Y         S0      
317GND              VIA   -    MD0100PA00X+178814Y+089069X0190Y         S0      
317GND              VIA   -    MD0100PA00X+178814Y+088400X0190Y         S0      
317GND              VIA   -    MD0100PA00X+178814Y+087730X0190Y         S0      
317GND              VIA   -    MD0100PA00X+178269Y+087061X0190Y         S0      
317GND              VIA   -    MD0100PA00X+179254Y+086559X0190Y         S0      
317GND              VIA   -    MD0100PA00X+178814Y+085388X0190Y         S0      
317GND              VIA   -    MD0100PA00X+178814Y+092081X0190Y         S0      
317GND              VIA   -    MD0100PA00X+178814Y+091411X0190Y         S0      
317GND              VIA   -    MD0100PA00X+179254Y+090240X0190Y         S0      
317GND              VIA   -    MD0100PA00X+178269Y+089738X0190Y         S0      
317GND              VIA   -    MD0100PA00X+178269Y+090742X0190Y         S0      
317GND              VIA   -    MD0100PA00X+178814Y+095092X0190Y         S0      
317GND              VIA   -    MD0100PA00X+178269Y+094423X0190Y         S0      
317GND              VIA   -    MD0100PA00X+179254Y+093921X0190Y         S0      
317GND              VIA   -    MD0100PA00X+178814Y+092750X0190Y         S0      
317GND              VIA   -    MD0100PA00X+178269Y+093419X0190Y         S0      
317GND              VIA   -    MD0100PA00X+178814Y+099108X0190Y         S0      
317GND              VIA   -    MD0100PA00X+178814Y+099778X0190Y         S0      
317GND              VIA   -    MD0100PA00X+178814Y+098439X0190Y         S0      
317GND              VIA   -    MD0100PA00X+178814Y+097770X0190Y         S0      
317GND              VIA   -    MD0100PA00X+178814Y+095762X0190Y         S0      
317GND              VIA   -    MD0100PA00X+178814Y+097100X0190Y         S0      
317GND              VIA   -    MD0100PA00X+178814Y+096431X0190Y         S0      
317GND              VIA   -    MD0100PA00X+178814Y+105132X0190Y         S0      
317GND              VIA   -    MD0100PA00X+178814Y+105801X0190Y         S0      
317GND              VIA   -    MD0100PA00X+178814Y+103124X0190Y         S0      
317GND              VIA   -    MD0100PA00X+178814Y+103793X0190Y         S0      
317GND              VIA   -    MD0100PA00X+178814Y+104463X0190Y         S0      
317GND              VIA   -    MD0100PA00X+178814Y+100447X0190Y         S0      
317GND              VIA   -    MD0100PA00X+179254Y+108646X0190Y         S0      
317GND              VIA   -    MD0100PA00X+178269Y+108144X0190Y         S0      
317GND              VIA   -    MD0100PA00X+178814Y+106805X0190Y         S0      
317GND              VIA   -    MD0100PA00X+178814Y+107474X0190Y         S0      
317GND              VIA   -    MD0100PA00X+178814Y+111156X0190Y         S0      
317GND              VIA   -    MD0100PA00X+178269Y+111825X0190Y         S0      
317GND              VIA   -    MD0100PA00X+178814Y+110486X0190Y         S0      
317GND              VIA   -    MD0100PA00X+178814Y+109817X0190Y         S0      
317GND              VIA   -    MD0100PA00X+178269Y+109148X0190Y         S0      
317GND              VIA   -    MD0100PA00X+178814Y+114837X0190Y         S0      
317GND              VIA   -    MD0100PA00X+178814Y+114167X0190Y         S0      
317GND              VIA   -    MD0100PA00X+179254Y+112327X0190Y         S0      
317GND              VIA   -    MD0100PA00X+178269Y+112829X0190Y         S0      
317GND              VIA   -    MD0100PA00X+178814Y+113498X0190Y         S0      
317GND              VIA   -    MD0100PA00X+178814Y+118518X0190Y         S0      
317GND              VIA   -    MD0100PA00X+178269Y+119187X0190Y         S0      
317GND              VIA   -    MD0100PA00X+178814Y+117848X0190Y         S0      
317GND              VIA   -    MD0100PA00X+178814Y+117179X0190Y         S0      
317GND              VIA   -    MD0100PA00X+179254Y+116008X0190Y         S0      
317GND              VIA   -    MD0100PA00X+178269Y+116510X0190Y         S0      
317GND              VIA   -    MD0100PA00X+178269Y+115506X0190Y         S0      
317GND              VIA   -    MD0100PA00X+178814Y+121530X0190Y         S0      
317GND              VIA   -    MD0100PA00X+178814Y+122199X0190Y         S0      
317GND              VIA   -    MD0100PA00X+178814Y+120860X0190Y         S0      
317GND              VIA   -    MD0100PA00X+179254Y+119689X0190Y         S0      
317GND              VIA   -    MD0100PA00X+178269Y+120191X0190Y         S0      
317GND              VIA   -    MD0100PA00X+178814Y+125211X0190Y         S0      
317GND              VIA   -    MD0100PA00X+178814Y+124541X0190Y         S0      
317GND              VIA   -    MD0100PA00X+179254Y+123370X0190Y         S0      
317GND              VIA   -    MD0100PA00X+178269Y+123872X0190Y         S0      
317GND              VIA   -    MD0100PA00X+178269Y+122868X0190Y         S0      
317GND              J18   -G2  MD0480PA00X+169097Y+102140X0680Y1370R090 S3      
317GND              J68   -G2  MD0480PA00X+172067Y+102140X0680Y1370R090 S3      
317GND              J20   -G2  MD0480PA00X+175037Y+102140X0680Y1370R090 S3      
317GND              J67   -G2  MD0480PA00X+178007Y+102140X0680Y1370R090 S3      
327GND              J67   -288        A01X+177200Y+125545X0205Y0590R090 S1      
327GND              J67   -286        A01X+177200Y+124876X0205Y0590R090 S1      
327GND              J67   -141        A01X+178814Y+124541X0205Y0590R090 S1      
327GND              J67   -143        A01X+178814Y+125211X0205Y0590R090 S1      
327GND              J67   -268        A01X+177200Y+118852X0205Y0590R090 S1      
327GND              J67   -277        A01X+177200Y+121864X0205Y0590R090 S1      
327GND              J67   -275        A01X+177200Y+121195X0205Y0590R090 S1      
327GND              J67   -279        A01X+177200Y+122534X0205Y0590R090 S1      
327GND              J67   -134        A01X+178814Y+122199X0205Y0590R090 S1      
327GND              J67   -130        A01X+178814Y+120860X0205Y0590R090 S1      
327GND              J67   -132        A01X+178814Y+121530X0205Y0590R090 S1      
327GND              J67   -253        A01X+177200Y+113833X0205Y0590R090 S1      
327GND              J67   -257        A01X+177200Y+115171X0205Y0590R090 S1      
327GND              J67   -255        A01X+177200Y+114502X0205Y0590R090 S1      
327GND              J67   -266        A01X+177200Y+118183X0205Y0590R090 S1      
327GND              J67   -264        A01X+177200Y+117514X0205Y0590R090 S1      
327GND              J67   -110        A01X+178814Y+114167X0205Y0590R090 S1      
327GND              J67   -108        A01X+178814Y+113498X0205Y0590R090 S1      
327GND              J67   -112        A01X+178814Y+114837X0205Y0590R090 S1      
327GND              J67   -119        A01X+178814Y+117179X0205Y0590R090 S1      
327GND              J67   -123        A01X+178814Y+118518X0205Y0590R090 S1      
327GND              J67   -121        A01X+178814Y+117848X0205Y0590R090 S1      
327GND              J67   -235        A01X+177200Y+107809X0205Y0590R090 S1      
327GND              J67   -244        A01X+177200Y+110821X0205Y0590R090 S1      
327GND              J67   -242        A01X+177200Y+110152X0205Y0590R090 S1      
327GND              J67   -246        A01X+177200Y+111490X0205Y0590R090 S1      
327GND              J67   -90         A01X+178814Y+107474X0205Y0590R090 S1      
327GND              J67   -97         A01X+178814Y+109817X0205Y0590R090 S1      
327GND              J67   -99         A01X+178814Y+110486X0205Y0590R090 S1      
327GND              J67   -101        A01X+178814Y+111156X0205Y0590R090 S1      
327GND              J67   -224        A01X+177200Y+104128X0205Y0590R090 S1      
327GND              J67   -222        A01X+177200Y+103459X0205Y0590R090 S1      
327GND              J67   -226        A01X+177200Y+104797X0205Y0590R090 S1      
327GND              J67   -230        A01X+177200Y+106136X0205Y0590R090 S1      
327GND              J67   -228        A01X+177200Y+105467X0205Y0590R090 S1      
327GND              J67   -233        A01X+177200Y+107140X0205Y0590R090 S1      
327GND              J67   -81         A01X+178814Y+104463X0205Y0590R090 S1      
327GND              J67   -79         A01X+178814Y+103793X0205Y0590R090 S1      
327GND              J67   -77         A01X+178814Y+103124X0205Y0590R090 S1      
327GND              J67   -85         A01X+178814Y+105801X0205Y0590R090 S1      
327GND              J67   -83         A01X+178814Y+105132X0205Y0590R090 S1      
327GND              J67   -88         A01X+178814Y+106805X0205Y0590R090 S1      
327GND              J67   -212        A01X+177200Y+098104X0205Y0590R090 S1      
327GND              J67   -210        A01X+177200Y+097435X0205Y0590R090 S1      
327GND              J67   -208        A01X+177200Y+096766X0205Y0590R090 S1      
327GND              J67   -216        A01X+177200Y+099443X0205Y0590R090 S1      
327GND              J67   -214        A01X+177200Y+098774X0205Y0590R090 S1      
327GND              J67   -219        A01X+177200Y+100447X0205Y0590R090 S1      
327GND              J67   -63         A01X+178814Y+096431X0205Y0590R090 S1      
327GND              J67   -67         A01X+178814Y+097770X0205Y0590R090 S1      
327GND              J67   -65         A01X+178814Y+097100X0205Y0590R090 S1      
327GND              J67   -73         A01X+178814Y+099778X0205Y0590R090 S1      
327GND              J67   -71         A01X+178814Y+099108X0205Y0590R090 S1      
327GND              J67   -69         A01X+178814Y+098439X0205Y0590R090 S1      
327GND              J67   -75         A01X+178814Y+100447X0205Y0590R090 S1      
327GND              J67   -193        A01X+177200Y+091746X0205Y0590R090 S1      
327GND              J67   -197        A01X+177200Y+093085X0205Y0590R090 S1      
327GND              J67   -195        A01X+177200Y+092415X0205Y0590R090 S1      
327GND              J67   -206        A01X+177200Y+096096X0205Y0590R090 S1      
327GND              J67   -204        A01X+177200Y+095427X0205Y0590R090 S1      
327GND              J67   -48         A01X+178814Y+091411X0205Y0590R090 S1      
327GND              J67   -52         A01X+178814Y+092750X0205Y0590R090 S1      
327GND              J67   -50         A01X+178814Y+092081X0205Y0590R090 S1      
327GND              J67   -59         A01X+178814Y+095092X0205Y0590R090 S1      
327GND              J67   -61         A01X+178814Y+095762X0205Y0590R090 S1      
327GND              J67   -173        A01X+177200Y+085053X0205Y0590R090 S1      
327GND              J67   -175        A01X+177200Y+085722X0205Y0590R090 S1      
327GND              J67   -182        A01X+177200Y+088065X0205Y0590R090 S1      
327GND              J67   -186        A01X+177200Y+089404X0205Y0590R090 S1      
327GND              J67   -184        A01X+177200Y+088734X0205Y0590R090 S1      
327GND              J67   -30         A01X+178814Y+085388X0205Y0590R090 S1      
327GND              J67   -39         A01X+178814Y+088400X0205Y0590R090 S1      
327GND              J67   -37         A01X+178814Y+087730X0205Y0590R090 S1      
327GND              J67   -41         A01X+178814Y+089069X0205Y0590R090 S1      
327GND              J67   -160        A01X+177200Y+080703X0205Y0590R090 S1      
327GND              J67   -162        A01X+177200Y+081372X0205Y0590R090 S1      
327GND              J67   -164        A01X+177200Y+082041X0205Y0590R090 S1      
327GND              J67   -171        A01X+177200Y+084384X0205Y0590R090 S1      
327GND              J67   -15         A01X+178814Y+080368X0205Y0590R090 S1      
327GND              J67   -19         A01X+178814Y+081707X0205Y0590R090 S1      
327GND              J67   -17         A01X+178814Y+081037X0205Y0590R090 S1      
327GND              J67   -28         A01X+178814Y+084718X0205Y0590R090 S1      
327GND              J67   -26         A01X+178814Y+084049X0205Y0590R090 S1      
327GND              J67   -153        A01X+177200Y+078360X0205Y0590R090 S1      
327GND              J67   -151        A01X+177200Y+077691X0205Y0590R090 S1      
327GND              J67   -8          A01X+178814Y+078026X0205Y0590R090 S1      
327GND              J68   -288        A01X+171260Y+125545X0205Y0590R090 S1      
327GND              J20   -288        A01X+174230Y+125545X0205Y0590R090 S1      
327GND              J68   -286        A01X+171260Y+124876X0205Y0590R090 S1      
327GND              J68   -141        A01X+172874Y+124541X0205Y0590R090 S1      
327GND              J68   -143        A01X+172874Y+125211X0205Y0590R090 S1      
327GND              J20   -286        A01X+174230Y+124876X0205Y0590R090 S1      
327GND              J20   -141        A01X+175844Y+124541X0205Y0590R090 S1      
327GND              J20   -143        A01X+175844Y+125211X0205Y0590R090 S1      
327GND              J68   -268        A01X+171260Y+118852X0205Y0590R090 S1      
327GND              J68   -277        A01X+171260Y+121864X0205Y0590R090 S1      
327GND              J68   -275        A01X+171260Y+121195X0205Y0590R090 S1      
327GND              J68   -279        A01X+171260Y+122534X0205Y0590R090 S1      
327GND              J68   -134        A01X+172874Y+122199X0205Y0590R090 S1      
327GND              J68   -130        A01X+172874Y+120860X0205Y0590R090 S1      
327GND              J68   -132        A01X+172874Y+121530X0205Y0590R090 S1      
327GND              J20   -268        A01X+174230Y+118852X0205Y0590R090 S1      
327GND              J20   -277        A01X+174230Y+121864X0205Y0590R090 S1      
327GND              J20   -275        A01X+174230Y+121195X0205Y0590R090 S1      
327GND              J20   -279        A01X+174230Y+122534X0205Y0590R090 S1      
327GND              J20   -134        A01X+175844Y+122199X0205Y0590R090 S1      
327GND              J20   -130        A01X+175844Y+120860X0205Y0590R090 S1      
327GND              J20   -132        A01X+175844Y+121530X0205Y0590R090 S1      
327GND              J68   -253        A01X+171260Y+113833X0205Y0590R090 S1      
327GND              J68   -257        A01X+171260Y+115171X0205Y0590R090 S1      
327GND              J68   -255        A01X+171260Y+114502X0205Y0590R090 S1      
327GND              J68   -266        A01X+171260Y+118183X0205Y0590R090 S1      
327GND              J68   -264        A01X+171260Y+117514X0205Y0590R090 S1      
327GND              J68   -110        A01X+172874Y+114167X0205Y0590R090 S1      
327GND              J68   -108        A01X+172874Y+113498X0205Y0590R090 S1      
327GND              J68   -112        A01X+172874Y+114837X0205Y0590R090 S1      
327GND              J68   -119        A01X+172874Y+117179X0205Y0590R090 S1      
327GND              J68   -123        A01X+172874Y+118518X0205Y0590R090 S1      
327GND              J68   -121        A01X+172874Y+117848X0205Y0590R090 S1      
327GND              J20   -253        A01X+174230Y+113833X0205Y0590R090 S1      
327GND              J20   -257        A01X+174230Y+115171X0205Y0590R090 S1      
327GND              J20   -255        A01X+174230Y+114502X0205Y0590R090 S1      
327GND              J20   -266        A01X+174230Y+118183X0205Y0590R090 S1      
327GND              J20   -264        A01X+174230Y+117514X0205Y0590R090 S1      
327GND              J20   -110        A01X+175844Y+114167X0205Y0590R090 S1      
327GND              J20   -108        A01X+175844Y+113498X0205Y0590R090 S1      
327GND              J20   -112        A01X+175844Y+114837X0205Y0590R090 S1      
327GND              J20   -119        A01X+175844Y+117179X0205Y0590R090 S1      
327GND              J20   -123        A01X+175844Y+118518X0205Y0590R090 S1      
327GND              J20   -121        A01X+175844Y+117848X0205Y0590R090 S1      
327GND              J68   -235        A01X+171260Y+107809X0205Y0590R090 S1      
327GND              J68   -244        A01X+171260Y+110821X0205Y0590R090 S1      
327GND              J68   -242        A01X+171260Y+110152X0205Y0590R090 S1      
327GND              J68   -246        A01X+171260Y+111490X0205Y0590R090 S1      
327GND              J68   -90         A01X+172874Y+107474X0205Y0590R090 S1      
327GND              J68   -99         A01X+172874Y+110486X0205Y0590R090 S1      
327GND              J68   -97         A01X+172874Y+109817X0205Y0590R090 S1      
327GND              J68   -101        A01X+172874Y+111156X0205Y0590R090 S1      
327GND              J20   -235        A01X+174230Y+107809X0205Y0590R090 S1      
327GND              J20   -244        A01X+174230Y+110821X0205Y0590R090 S1      
327GND              J20   -242        A01X+174230Y+110152X0205Y0590R090 S1      
327GND              J20   -246        A01X+174230Y+111490X0205Y0590R090 S1      
327GND              J20   -90         A01X+175844Y+107474X0205Y0590R090 S1      
327GND              J20   -99         A01X+175844Y+110486X0205Y0590R090 S1      
327GND              J20   -97         A01X+175844Y+109817X0205Y0590R090 S1      
327GND              J20   -101        A01X+175844Y+111156X0205Y0590R090 S1      
327GND              J68   -224        A01X+171260Y+104128X0205Y0590R090 S1      
327GND              J68   -222        A01X+171260Y+103459X0205Y0590R090 S1      
327GND              J68   -230        A01X+171260Y+106136X0205Y0590R090 S1      
327GND              J68   -228        A01X+171260Y+105467X0205Y0590R090 S1      
327GND              J68   -226        A01X+171260Y+104797X0205Y0590R090 S1      
327GND              J68   -233        A01X+171260Y+107140X0205Y0590R090 S1      
327GND              J68   -81         A01X+172874Y+104463X0205Y0590R090 S1      
327GND              J68   -79         A01X+172874Y+103793X0205Y0590R090 S1      
327GND              J68   -77         A01X+172874Y+103124X0205Y0590R090 S1      
327GND              J68   -85         A01X+172874Y+105801X0205Y0590R090 S1      
327GND              J68   -83         A01X+172874Y+105132X0205Y0590R090 S1      
327GND              J68   -88         A01X+172874Y+106805X0205Y0590R090 S1      
327GND              J20   -224        A01X+174230Y+104128X0205Y0590R090 S1      
327GND              J20   -222        A01X+174230Y+103459X0205Y0590R090 S1      
327GND              J20   -230        A01X+174230Y+106136X0205Y0590R090 S1      
327GND              J20   -228        A01X+174230Y+105467X0205Y0590R090 S1      
327GND              J20   -226        A01X+174230Y+104797X0205Y0590R090 S1      
327GND              J20   -233        A01X+174230Y+107140X0205Y0590R090 S1      
327GND              J20   -81         A01X+175844Y+104463X0205Y0590R090 S1      
327GND              J20   -79         A01X+175844Y+103793X0205Y0590R090 S1      
327GND              J20   -77         A01X+175844Y+103124X0205Y0590R090 S1      
327GND              J20   -85         A01X+175844Y+105801X0205Y0590R090 S1      
327GND              J20   -83         A01X+175844Y+105132X0205Y0590R090 S1      
327GND              J20   -88         A01X+175844Y+106805X0205Y0590R090 S1      
327GND              J68   -212        A01X+171260Y+098104X0205Y0590R090 S1      
327GND              J68   -210        A01X+171260Y+097435X0205Y0590R090 S1      
327GND              J68   -208        A01X+171260Y+096766X0205Y0590R090 S1      
327GND              J68   -216        A01X+171260Y+099443X0205Y0590R090 S1      
327GND              J68   -214        A01X+171260Y+098774X0205Y0590R090 S1      
327GND              J68   -219        A01X+171260Y+100447X0205Y0590R090 S1      
327GND              J68   -63         A01X+172874Y+096431X0205Y0590R090 S1      
327GND              J68   -67         A01X+172874Y+097770X0205Y0590R090 S1      
327GND              J68   -65         A01X+172874Y+097100X0205Y0590R090 S1      
327GND              J68   -73         A01X+172874Y+099778X0205Y0590R090 S1      
327GND              J68   -71         A01X+172874Y+099108X0205Y0590R090 S1      
327GND              J68   -69         A01X+172874Y+098439X0205Y0590R090 S1      
327GND              J68   -75         A01X+172874Y+100447X0205Y0590R090 S1      
327GND              J20   -212        A01X+174230Y+098104X0205Y0590R090 S1      
327GND              J20   -210        A01X+174230Y+097435X0205Y0590R090 S1      
327GND              J20   -208        A01X+174230Y+096766X0205Y0590R090 S1      
327GND              J20   -216        A01X+174230Y+099443X0205Y0590R090 S1      
327GND              J20   -214        A01X+174230Y+098774X0205Y0590R090 S1      
327GND              J20   -219        A01X+174230Y+100447X0205Y0590R090 S1      
327GND              J20   -63         A01X+175844Y+096431X0205Y0590R090 S1      
327GND              J20   -67         A01X+175844Y+097770X0205Y0590R090 S1      
327GND              J20   -65         A01X+175844Y+097100X0205Y0590R090 S1      
327GND              J20   -73         A01X+175844Y+099778X0205Y0590R090 S1      
327GND              J20   -71         A01X+175844Y+099108X0205Y0590R090 S1      
327GND              J20   -69         A01X+175844Y+098439X0205Y0590R090 S1      
327GND              J20   -75         A01X+175844Y+100447X0205Y0590R090 S1      
327GND              J68   -193        A01X+171260Y+091746X0205Y0590R090 S1      
327GND              J68   -197        A01X+171260Y+093085X0205Y0590R090 S1      
327GND              J68   -195        A01X+171260Y+092415X0205Y0590R090 S1      
327GND              J68   -206        A01X+171260Y+096096X0205Y0590R090 S1      
327GND              J68   -204        A01X+171260Y+095427X0205Y0590R090 S1      
327GND              J68   -48         A01X+172874Y+091411X0205Y0590R090 S1      
327GND              J68   -50         A01X+172874Y+092081X0205Y0590R090 S1      
327GND              J68   -52         A01X+172874Y+092750X0205Y0590R090 S1      
327GND              J68   -59         A01X+172874Y+095092X0205Y0590R090 S1      
327GND              J68   -61         A01X+172874Y+095762X0205Y0590R090 S1      
327GND              J20   -193        A01X+174230Y+091746X0205Y0590R090 S1      
327GND              J20   -197        A01X+174230Y+093085X0205Y0590R090 S1      
327GND              J20   -195        A01X+174230Y+092415X0205Y0590R090 S1      
327GND              J20   -206        A01X+174230Y+096096X0205Y0590R090 S1      
327GND              J20   -204        A01X+174230Y+095427X0205Y0590R090 S1      
327GND              J20   -48         A01X+175844Y+091411X0205Y0590R090 S1      
327GND              J20   -52         A01X+175844Y+092750X0205Y0590R090 S1      
327GND              J20   -50         A01X+175844Y+092081X0205Y0590R090 S1      
327GND              J20   -59         A01X+175844Y+095092X0205Y0590R090 S1      
327GND              J20   -61         A01X+175844Y+095762X0205Y0590R090 S1      
327GND              J68   -173        A01X+171260Y+085053X0205Y0590R090 S1      
327GND              J68   -175        A01X+171260Y+085722X0205Y0590R090 S1      
327GND              J68   -182        A01X+171260Y+088065X0205Y0590R090 S1      
327GND              J68   -186        A01X+171260Y+089404X0205Y0590R090 S1      
327GND              J68   -184        A01X+171260Y+088734X0205Y0590R090 S1      
327GND              J68   -30         A01X+172874Y+085388X0205Y0590R090 S1      
327GND              J68   -39         A01X+172874Y+088400X0205Y0590R090 S1      
327GND              J68   -37         A01X+172874Y+087730X0205Y0590R090 S1      
327GND              J68   -41         A01X+172874Y+089069X0205Y0590R090 S1      
327GND              J20   -173        A01X+174230Y+085053X0205Y0590R090 S1      
327GND              J20   -175        A01X+174230Y+085722X0205Y0590R090 S1      
327GND              J20   -182        A01X+174230Y+088065X0205Y0590R090 S1      
327GND              J20   -186        A01X+174230Y+089404X0205Y0590R090 S1      
327GND              J20   -184        A01X+174230Y+088734X0205Y0590R090 S1      
327GND              J20   -30         A01X+175844Y+085388X0205Y0590R090 S1      
327GND              J20   -39         A01X+175844Y+088400X0205Y0590R090 S1      
327GND              J20   -37         A01X+175844Y+087730X0205Y0590R090 S1      
327GND              J20   -41         A01X+175844Y+089069X0205Y0590R090 S1      
327GND              J68   -160        A01X+171260Y+080703X0205Y0590R090 S1      
327GND              J68   -164        A01X+171260Y+082041X0205Y0590R090 S1      
327GND              J68   -162        A01X+171260Y+081372X0205Y0590R090 S1      
327GND              J68   -171        A01X+171260Y+084384X0205Y0590R090 S1      
327GND              J68   -15         A01X+172874Y+080368X0205Y0590R090 S1      
327GND              J68   -19         A01X+172874Y+081707X0205Y0590R090 S1      
327GND              J68   -17         A01X+172874Y+081037X0205Y0590R090 S1      
327GND              J68   -28         A01X+172874Y+084718X0205Y0590R090 S1      
327GND              J68   -26         A01X+172874Y+084049X0205Y0590R090 S1      
327GND              J20   -160        A01X+174230Y+080703X0205Y0590R090 S1      
327GND              J20   -164        A01X+174230Y+082041X0205Y0590R090 S1      
327GND              J20   -162        A01X+174230Y+081372X0205Y0590R090 S1      
327GND              J20   -171        A01X+174230Y+084384X0205Y0590R090 S1      
327GND              J20   -15         A01X+175844Y+080368X0205Y0590R090 S1      
327GND              J20   -19         A01X+175844Y+081707X0205Y0590R090 S1      
327GND              J20   -17         A01X+175844Y+081037X0205Y0590R090 S1      
327GND              J20   -28         A01X+175844Y+084718X0205Y0590R090 S1      
327GND              J20   -26         A01X+175844Y+084049X0205Y0590R090 S1      
327GND              J68   -153        A01X+171260Y+078360X0205Y0590R090 S1      
327GND              J68   -151        A01X+171260Y+077691X0205Y0590R090 S1      
327GND              J68   -8          A01X+172874Y+078026X0205Y0590R090 S1      
327GND              J20   -153        A01X+174230Y+078360X0205Y0590R090 S1      
327GND              J20   -151        A01X+174230Y+077691X0205Y0590R090 S1      
327GND              J20   -8          A01X+175844Y+078026X0205Y0590R090 S1      
327GND              J18   -288        A01X+168290Y+125545X0205Y0590R090 S1      
327GND              J18   -286        A01X+168290Y+124876X0205Y0590R090 S1      
327GND              J18   -141        A01X+169904Y+124541X0205Y0590R090 S1      
327GND              J18   -143        A01X+169904Y+125211X0205Y0590R090 S1      
327GND              J18   -268        A01X+168290Y+118852X0205Y0590R090 S1      
327GND              J18   -275        A01X+168290Y+121195X0205Y0590R090 S1      
327GND              J18   -277        A01X+168290Y+121864X0205Y0590R090 S1      
327GND              J18   -279        A01X+168290Y+122534X0205Y0590R090 S1      
327GND              J18   -134        A01X+169904Y+122199X0205Y0590R090 S1      
327GND              J18   -130        A01X+169904Y+120860X0205Y0590R090 S1      
327GND              J18   -132        A01X+169904Y+121530X0205Y0590R090 S1      
327GND              J18   -253        A01X+168290Y+113833X0205Y0590R090 S1      
327GND              J18   -257        A01X+168290Y+115171X0205Y0590R090 S1      
327GND              J18   -255        A01X+168290Y+114502X0205Y0590R090 S1      
327GND              J18   -266        A01X+168290Y+118183X0205Y0590R090 S1      
327GND              J18   -264        A01X+168290Y+117514X0205Y0590R090 S1      
327GND              J18   -110        A01X+169904Y+114167X0205Y0590R090 S1      
327GND              J18   -108        A01X+169904Y+113498X0205Y0590R090 S1      
327GND              J18   -112        A01X+169904Y+114837X0205Y0590R090 S1      
327GND              J18   -119        A01X+169904Y+117179X0205Y0590R090 S1      
327GND              J18   -123        A01X+169904Y+118518X0205Y0590R090 S1      
327GND              J18   -121        A01X+169904Y+117848X0205Y0590R090 S1      
327GND              J18   -235        A01X+168290Y+107809X0205Y0590R090 S1      
327GND              J18   -244        A01X+168290Y+110821X0205Y0590R090 S1      
327GND              J18   -242        A01X+168290Y+110152X0205Y0590R090 S1      
327GND              J18   -246        A01X+168290Y+111490X0205Y0590R090 S1      
327GND              J18   -90         A01X+169904Y+107474X0205Y0590R090 S1      
327GND              J18   -99         A01X+169904Y+110486X0205Y0590R090 S1      
327GND              J18   -97         A01X+169904Y+109817X0205Y0590R090 S1      
327GND              J18   -101        A01X+169904Y+111156X0205Y0590R090 S1      
327GND              J18   -224        A01X+168290Y+104128X0205Y0590R090 S1      
327GND              J18   -222        A01X+168290Y+103459X0205Y0590R090 S1      
327GND              J18   -230        A01X+168290Y+106136X0205Y0590R090 S1      
327GND              J18   -228        A01X+168290Y+105467X0205Y0590R090 S1      
327GND              J18   -226        A01X+168290Y+104797X0205Y0590R090 S1      
327GND              J18   -233        A01X+168290Y+107140X0205Y0590R090 S1      
327GND              J18   -81         A01X+169904Y+104463X0205Y0590R090 S1      
327GND              J18   -79         A01X+169904Y+103793X0205Y0590R090 S1      
327GND              J18   -77         A01X+169904Y+103124X0205Y0590R090 S1      
327GND              J18   -85         A01X+169904Y+105801X0205Y0590R090 S1      
327GND              J18   -83         A01X+169904Y+105132X0205Y0590R090 S1      
327GND              J18   -88         A01X+169904Y+106805X0205Y0590R090 S1      
327GND              J18   -212        A01X+168290Y+098104X0205Y0590R090 S1      
327GND              J18   -210        A01X+168290Y+097435X0205Y0590R090 S1      
327GND              J18   -208        A01X+168290Y+096766X0205Y0590R090 S1      
327GND              J18   -216        A01X+168290Y+099443X0205Y0590R090 S1      
327GND              J18   -214        A01X+168290Y+098774X0205Y0590R090 S1      
327GND              J18   -219        A01X+168290Y+100447X0205Y0590R090 S1      
327GND              J18   -63         A01X+169904Y+096431X0205Y0590R090 S1      
327GND              J18   -67         A01X+169904Y+097770X0205Y0590R090 S1      
327GND              J18   -65         A01X+169904Y+097100X0205Y0590R090 S1      
327GND              J18   -73         A01X+169904Y+099778X0205Y0590R090 S1      
327GND              J18   -71         A01X+169904Y+099108X0205Y0590R090 S1      
327GND              J18   -69         A01X+169904Y+098439X0205Y0590R090 S1      
327GND              J18   -75         A01X+169904Y+100447X0205Y0590R090 S1      
327GND              J18   -193        A01X+168290Y+091746X0205Y0590R090 S1      
327GND              J18   -197        A01X+168290Y+093085X0205Y0590R090 S1      
327GND              J18   -195        A01X+168290Y+092415X0205Y0590R090 S1      
327GND              J18   -206        A01X+168290Y+096096X0205Y0590R090 S1      
327GND              J18   -204        A01X+168290Y+095427X0205Y0590R090 S1      
327GND              J18   -48         A01X+169904Y+091411X0205Y0590R090 S1      
327GND              J18   -52         A01X+169904Y+092750X0205Y0590R090 S1      
327GND              J18   -50         A01X+169904Y+092081X0205Y0590R090 S1      
327GND              J18   -59         A01X+169904Y+095092X0205Y0590R090 S1      
327GND              J18   -61         A01X+169904Y+095762X0205Y0590R090 S1      
327GND              J18   -173        A01X+168290Y+085053X0205Y0590R090 S1      
327GND              J18   -175        A01X+168290Y+085722X0205Y0590R090 S1      
327GND              J18   -182        A01X+168290Y+088065X0205Y0590R090 S1      
327GND              J18   -186        A01X+168290Y+089404X0205Y0590R090 S1      
327GND              J18   -184        A01X+168290Y+088734X0205Y0590R090 S1      
327GND              J18   -30         A01X+169904Y+085388X0205Y0590R090 S1      
327GND              J18   -39         A01X+169904Y+088400X0205Y0590R090 S1      
327GND              J18   -37         A01X+169904Y+087730X0205Y0590R090 S1      
327GND              J18   -41         A01X+169904Y+089069X0205Y0590R090 S1      
327GND              J18   -160        A01X+168290Y+080703X0205Y0590R090 S1      
327GND              J18   -164        A01X+168290Y+082041X0205Y0590R090 S1      
327GND              J18   -162        A01X+168290Y+081372X0205Y0590R090 S1      
327GND              J18   -171        A01X+168290Y+084384X0205Y0590R090 S1      
327GND              J18   -15         A01X+169904Y+080368X0205Y0590R090 S1      
327GND              J18   -19         A01X+169904Y+081707X0205Y0590R090 S1      
327GND              J18   -17         A01X+169904Y+081037X0205Y0590R090 S1      
327GND              J18   -28         A01X+169904Y+084718X0205Y0590R090 S1      
327GND              J18   -26         A01X+169904Y+084049X0205Y0590R090 S1      
327GND              J18   -153        A01X+168290Y+078360X0205Y0590R090 S1      
327GND              J18   -151        A01X+168290Y+077691X0205Y0590R090 S1      
327GND              J18   -8          A01X+169904Y+078026X0205Y0590R090 S1      
327GND              J67   -273        A01X+177200Y+120526X0205Y0590R090 S1      
327GND              J67   -270        A01X+177200Y+119522X0205Y0590R090 S1      
327GND              J67   -281        A01X+177200Y+123203X0205Y0590R090 S1      
327GND              J67   -284        A01X+177200Y+124207X0205Y0590R090 S1      
327GND              J67   -128        A01X+178814Y+120191X0205Y0590R090 S1      
327GND              J67   -125        A01X+178814Y+119187X0205Y0590R090 S1      
327GND              J67   -139        A01X+178814Y+123872X0205Y0590R090 S1      
327GND              J67   -136        A01X+178814Y+122868X0205Y0590R090 S1      
327GND              J67   -251        A01X+177200Y+113163X0205Y0590R090 S1      
327GND              J67   -259        A01X+177200Y+115841X0205Y0590R090 S1      
327GND              J67   -262        A01X+177200Y+116844X0205Y0590R090 S1      
327GND              J67   -114        A01X+178814Y+115506X0205Y0590R090 S1      
327GND              J67   -117        A01X+178814Y+116510X0205Y0590R090 S1      
327GND              J67   -240        A01X+177200Y+109482X0205Y0590R090 S1      
327GND              J67   -237        A01X+177200Y+108478X0205Y0590R090 S1      
327GND              J67   -248        A01X+177200Y+112160X0205Y0590R090 S1      
327GND              J67   -95         A01X+178814Y+109148X0205Y0590R090 S1      
327GND              J67   -92         A01X+178814Y+108144X0205Y0590R090 S1      
327GND              J67   -103        A01X+178814Y+111825X0205Y0590R090 S1      
327GND              J67   -106        A01X+178814Y+112829X0205Y0590R090 S1      
327GND              J67   -191        A01X+177200Y+091077X0205Y0590R090 S1      
327GND              J67   -202        A01X+177200Y+094758X0205Y0590R090 S1      
327GND              J67   -199        A01X+177200Y+093754X0205Y0590R090 S1      
327GND              J67   -46         A01X+178814Y+090742X0205Y0590R090 S1      
327GND              J67   -54         A01X+178814Y+093419X0205Y0590R090 S1      
327GND              J67   -57         A01X+178814Y+094423X0205Y0590R090 S1      
327GND              J67   -177        A01X+177200Y+086392X0205Y0590R090 S1      
327GND              J67   -180        A01X+177200Y+087396X0205Y0590R090 S1      
327GND              J67   -188        A01X+177200Y+090073X0205Y0590R090 S1      
327GND              J67   -35         A01X+178814Y+087061X0205Y0590R090 S1      
327GND              J67   -32         A01X+178814Y+086057X0205Y0590R090 S1      
327GND              J67   -43         A01X+178814Y+089738X0205Y0590R090 S1      
327GND              J67   -158        A01X+177200Y+080034X0205Y0590R090 S1      
327GND              J67   -166        A01X+177200Y+082711X0205Y0590R090 S1      
327GND              J67   -169        A01X+177200Y+083715X0205Y0590R090 S1      
327GND              J67   -13         A01X+178814Y+079699X0205Y0590R090 S1      
327GND              J67   -21         A01X+178814Y+082376X0205Y0590R090 S1      
327GND              J67   -24         A01X+178814Y+083380X0205Y0590R090 S1      
327GND              J67   -155        A01X+177200Y+079030X0205Y0590R090 S1      
327GND              J67   -10         A01X+178814Y+078695X0205Y0590R090 S1      
327GND              J68   -273        A01X+171260Y+120526X0205Y0590R090 S1      
327GND              J68   -270        A01X+171260Y+119522X0205Y0590R090 S1      
327GND              J68   -281        A01X+171260Y+123203X0205Y0590R090 S1      
327GND              J68   -284        A01X+171260Y+124207X0205Y0590R090 S1      
327GND              J68   -128        A01X+172874Y+120191X0205Y0590R090 S1      
327GND              J68   -125        A01X+172874Y+119187X0205Y0590R090 S1      
327GND              J68   -139        A01X+172874Y+123872X0205Y0590R090 S1      
327GND              J68   -136        A01X+172874Y+122868X0205Y0590R090 S1      
327GND              J20   -273        A01X+174230Y+120526X0205Y0590R090 S1      
327GND              J20   -270        A01X+174230Y+119522X0205Y0590R090 S1      
327GND              J20   -281        A01X+174230Y+123203X0205Y0590R090 S1      
327GND              J20   -284        A01X+174230Y+124207X0205Y0590R090 S1      
327GND              J20   -128        A01X+175844Y+120191X0205Y0590R090 S1      
327GND              J20   -125        A01X+175844Y+119187X0205Y0590R090 S1      
327GND              J20   -139        A01X+175844Y+123872X0205Y0590R090 S1      
327GND              J20   -136        A01X+175844Y+122868X0205Y0590R090 S1      
327GND              J68   -251        A01X+171260Y+113163X0205Y0590R090 S1      
327GND              J68   -259        A01X+171260Y+115841X0205Y0590R090 S1      
327GND              J68   -262        A01X+171260Y+116844X0205Y0590R090 S1      
327GND              J68   -114        A01X+172874Y+115506X0205Y0590R090 S1      
327GND              J68   -117        A01X+172874Y+116510X0205Y0590R090 S1      
327GND              J20   -251        A01X+174230Y+113163X0205Y0590R090 S1      
327GND              J20   -259        A01X+174230Y+115841X0205Y0590R090 S1      
327GND              J20   -262        A01X+174230Y+116844X0205Y0590R090 S1      
327GND              J20   -114        A01X+175844Y+115506X0205Y0590R090 S1      
327GND              J20   -117        A01X+175844Y+116510X0205Y0590R090 S1      
327GND              J68   -240        A01X+171260Y+109482X0205Y0590R090 S1      
327GND              J68   -237        A01X+171260Y+108478X0205Y0590R090 S1      
327GND              J68   -248        A01X+171260Y+112160X0205Y0590R090 S1      
327GND              J68   -95         A01X+172874Y+109148X0205Y0590R090 S1      
327GND              J68   -92         A01X+172874Y+108144X0205Y0590R090 S1      
327GND              J68   -103        A01X+172874Y+111825X0205Y0590R090 S1      
327GND              J68   -106        A01X+172874Y+112829X0205Y0590R090 S1      
327GND              J20   -240        A01X+174230Y+109482X0205Y0590R090 S1      
327GND              J20   -237        A01X+174230Y+108478X0205Y0590R090 S1      
327GND              J20   -248        A01X+174230Y+112160X0205Y0590R090 S1      
327GND              J20   -95         A01X+175844Y+109148X0205Y0590R090 S1      
327GND              J20   -92         A01X+175844Y+108144X0205Y0590R090 S1      
327GND              J20   -103        A01X+175844Y+111825X0205Y0590R090 S1      
327GND              J20   -106        A01X+175844Y+112829X0205Y0590R090 S1      
327GND              J68   -191        A01X+171260Y+091077X0205Y0590R090 S1      
327GND              J68   -202        A01X+171260Y+094758X0205Y0590R090 S1      
327GND              J68   -199        A01X+171260Y+093754X0205Y0590R090 S1      
327GND              J68   -46         A01X+172874Y+090742X0205Y0590R090 S1      
327GND              J68   -54         A01X+172874Y+093419X0205Y0590R090 S1      
327GND              J68   -57         A01X+172874Y+094423X0205Y0590R090 S1      
327GND              J20   -191        A01X+174230Y+091077X0205Y0590R090 S1      
327GND              J20   -202        A01X+174230Y+094758X0205Y0590R090 S1      
327GND              J20   -199        A01X+174230Y+093754X0205Y0590R090 S1      
327GND              J20   -46         A01X+175844Y+090742X0205Y0590R090 S1      
327GND              J20   -54         A01X+175844Y+093419X0205Y0590R090 S1      
327GND              J20   -57         A01X+175844Y+094423X0205Y0590R090 S1      
327GND              J68   -177        A01X+171260Y+086392X0205Y0590R090 S1      
327GND              J68   -180        A01X+171260Y+087396X0205Y0590R090 S1      
327GND              J68   -188        A01X+171260Y+090073X0205Y0590R090 S1      
327GND              J68   -35         A01X+172874Y+087061X0205Y0590R090 S1      
327GND              J68   -32         A01X+172874Y+086057X0205Y0590R090 S1      
327GND              J68   -43         A01X+172874Y+089738X0205Y0590R090 S1      
327GND              J20   -177        A01X+174230Y+086392X0205Y0590R090 S1      
327GND              J20   -180        A01X+174230Y+087396X0205Y0590R090 S1      
327GND              J20   -188        A01X+174230Y+090073X0205Y0590R090 S1      
327GND              J20   -35         A01X+175844Y+087061X0205Y0590R090 S1      
327GND              J20   -32         A01X+175844Y+086057X0205Y0590R090 S1      
327GND              J20   -43         A01X+175844Y+089738X0205Y0590R090 S1      
327GND              J68   -158        A01X+171260Y+080034X0205Y0590R090 S1      
327GND              J68   -166        A01X+171260Y+082711X0205Y0590R090 S1      
327GND              J68   -169        A01X+171260Y+083715X0205Y0590R090 S1      
327GND              J68   -13         A01X+172874Y+079699X0205Y0590R090 S1      
327GND              J68   -21         A01X+172874Y+082376X0205Y0590R090 S1      
327GND              J68   -24         A01X+172874Y+083380X0205Y0590R090 S1      
327GND              J20   -158        A01X+174230Y+080034X0205Y0590R090 S1      
327GND              J20   -166        A01X+174230Y+082711X0205Y0590R090 S1      
327GND              J20   -169        A01X+174230Y+083715X0205Y0590R090 S1      
327GND              J20   -13         A01X+175844Y+079699X0205Y0590R090 S1      
327GND              J20   -21         A01X+175844Y+082376X0205Y0590R090 S1      
327GND              J20   -24         A01X+175844Y+083380X0205Y0590R090 S1      
327GND              J68   -155        A01X+171260Y+079030X0205Y0590R090 S1      
327GND              J68   -10         A01X+172874Y+078695X0205Y0590R090 S1      
327GND              J20   -155        A01X+174230Y+079030X0205Y0590R090 S1      
327GND              J20   -10         A01X+175844Y+078695X0205Y0590R090 S1      
327GND              J18   -273        A01X+168290Y+120526X0205Y0590R090 S1      
327GND              J18   -270        A01X+168290Y+119522X0205Y0590R090 S1      
327GND              J18   -281        A01X+168290Y+123203X0205Y0590R090 S1      
327GND              J18   -284        A01X+168290Y+124207X0205Y0590R090 S1      
327GND              J18   -128        A01X+169904Y+120191X0205Y0590R090 S1      
327GND              J18   -125        A01X+169904Y+119187X0205Y0590R090 S1      
327GND              J18   -136        A01X+169904Y+122868X0205Y0590R090 S1      
327GND              J18   -139        A01X+169904Y+123872X0205Y0590R090 S1      
327GND              J18   -251        A01X+168290Y+113163X0205Y0590R090 S1      
327GND              J18   -259        A01X+168290Y+115841X0205Y0590R090 S1      
327GND              J18   -262        A01X+168290Y+116844X0205Y0590R090 S1      
327GND              J18   -114        A01X+169904Y+115506X0205Y0590R090 S1      
327GND              J18   -117        A01X+169904Y+116510X0205Y0590R090 S1      
327GND              J18   -240        A01X+168290Y+109482X0205Y0590R090 S1      
327GND              J18   -237        A01X+168290Y+108478X0205Y0590R090 S1      
327GND              J18   -248        A01X+168290Y+112160X0205Y0590R090 S1      
327GND              J18   -95         A01X+169904Y+109148X0205Y0590R090 S1      
327GND              J18   -92         A01X+169904Y+108144X0205Y0590R090 S1      
327GND              J18   -103        A01X+169904Y+111825X0205Y0590R090 S1      
327GND              J18   -106        A01X+169904Y+112829X0205Y0590R090 S1      
327GND              J18   -191        A01X+168290Y+091077X0205Y0590R090 S1      
327GND              J18   -202        A01X+168290Y+094758X0205Y0590R090 S1      
327GND              J18   -199        A01X+168290Y+093754X0205Y0590R090 S1      
327GND              J18   -46         A01X+169904Y+090742X0205Y0590R090 S1      
327GND              J18   -54         A01X+169904Y+093419X0205Y0590R090 S1      
327GND              J18   -57         A01X+169904Y+094423X0205Y0590R090 S1      
327GND              J18   -177        A01X+168290Y+086392X0205Y0590R090 S1      
327GND              J18   -180        A01X+168290Y+087396X0205Y0590R090 S1      
327GND              J18   -188        A01X+168290Y+090073X0205Y0590R090 S1      
327GND              J18   -35         A01X+169904Y+087061X0205Y0590R090 S1      
327GND              J18   -32         A01X+169904Y+086057X0205Y0590R090 S1      
327GND              J18   -43         A01X+169904Y+089738X0205Y0590R090 S1      
327GND              J18   -158        A01X+168290Y+080034X0205Y0590R090 S1      
327GND              J18   -166        A01X+168290Y+082711X0205Y0590R090 S1      
327GND              J18   -169        A01X+168290Y+083715X0205Y0590R090 S1      
327GND              J18   -13         A01X+169904Y+079699X0205Y0590R090 S1      
327GND              J18   -21         A01X+169904Y+082376X0205Y0590R090 S1      
327GND              J18   -24         A01X+169904Y+083380X0205Y0590R090 S1      
327GND              J18   -155        A01X+168290Y+079030X0205Y0590R090 S1      
327GND              J18   -10         A01X+169904Y+078695X0205Y0590R090 S1      
317GND              VIA   -    MD0100PA00X+166934Y+077356X0190Y         S0      
327GND              J69   -6          A01X+166934Y+077356X0205Y0590R090 S1      
317GND              VIA   -    MD0100PA00X+166479Y+076376X0190Y         S0      
327GND              C120  -2          A18X+166479Y+076376X0198Y0197     S2      
317GND              VIA   -    MD0100PA00X+165320Y+077691X0190Y         S0      
327GND              J69   -151        A01X+165320Y+077691X0205Y0590R090 S1      
317GND              VIA   -    MD0100PA00X+165775Y+076726X0190Y         S0      
327GND              R765  -2          A18X+165775Y+076726X0198Y0197R180 S2      
317GND              VIA   -    MD0100PA00X+163964Y+077356X0190Y         S0      
327GND              J16   -6          A01X+163964Y+077356X0205Y0590R090 S1      
317GND              VIA   -    MD0100PA00X+163509Y+076376X0190Y         S0      
327GND              C116  -2          A18X+163509Y+076376X0198Y0197     S2      
317GND              VIA   -    MD0100PA00X+162350Y+077691X0190Y         S0      
327GND              J16   -151        A01X+162350Y+077691X0205Y0590R090 S1      
317GND              VIA   -    MD0100PA00X+162805Y+076726X0190Y         S0      
327GND              R35   -2          A18X+162805Y+076726X0198Y0197R180 S2      
317GND              VIA   -    MD0100PA00X+120556Y+076376X0190Y         S0      
327GND              C88   -2          A18X+120843Y+076376X0198Y0197     S2      
317GND              VIA   -    MD0100PA00X+117586Y+076376X0190Y         S0      
327GND              C92   -2          A18X+117586Y+076376X0198Y0197     S2      
317GND              VIA   -    MD0100PA00X+114616Y+076376X0190Y         S0      
327GND              C96   -2          A18X+114616Y+076376X0198Y0197     S2      
317GND              VIA   -    MD0100PA00X+111646Y+076376X0190Y         S0      
327GND              C100  -2          A18X+111646Y+076376X0198Y0197     S2      
317GND              VIA   -    MD0100PA00X+108676Y+076376X0190Y         S0      
327GND              C104  -2          A18X+108676Y+076376X0198Y0197     S2      
317GND              VIA   -    MD0100PA00X+105706Y+076376X0190Y         S0      
327GND              C108  -2          A18X+105706Y+076376X0198Y0197     S2      
317GND              VIA   -    MD0100PA00X+105002Y+076726X0190Y         S0      
327GND              R764  -2          A18X+105002Y+076726X0198Y0197R180 S2      
317GND              J23   -G2  MD0480PA00X+105354Y+102140X0680Y1370R090 S3      
317GND              J21   -G2  MD0480PA00X+108324Y+102140X0680Y1370R090 S3      
317GND              J17   -G2  MD0480PA00X+114264Y+102140X0680Y1370R090 S3      
317GND              J19   -G2  MD0480PA00X+111294Y+102140X0680Y1370R090 S3      
327GND              J17   -141        A01X+115071Y+124541X0205Y0590R090 S1      
327GND              J17   -130        A01X+115071Y+120860X0205Y0590R090 S1      
327GND              J17   -132        A01X+115071Y+121530X0205Y0590R090 S1      
327GND              J17   -134        A01X+115071Y+122199X0205Y0590R090 S1      
327GND              J17   -110        A01X+115071Y+114167X0205Y0590R090 S1      
327GND              J17   -108        A01X+115071Y+113498X0205Y0590R090 S1      
327GND              J17   -112        A01X+115071Y+114837X0205Y0590R090 S1      
327GND              J17   -119        A01X+115071Y+117179X0205Y0590R090 S1      
327GND              J17   -121        A01X+115071Y+117848X0205Y0590R090 S1      
327GND              J17   -123        A01X+115071Y+118518X0205Y0590R090 S1      
327GND              J17   -90         A01X+115071Y+107474X0205Y0590R090 S1      
327GND              J17   -97         A01X+115071Y+109817X0205Y0590R090 S1      
327GND              J17   -99         A01X+115071Y+110486X0205Y0590R090 S1      
327GND              J17   -101        A01X+115071Y+111156X0205Y0590R090 S1      
327GND              J17   -77         A01X+115071Y+103124X0205Y0590R090 S1      
327GND              J17   -79         A01X+115071Y+103793X0205Y0590R090 S1      
327GND              J17   -81         A01X+115071Y+104463X0205Y0590R090 S1      
327GND              J17   -83         A01X+115071Y+105132X0205Y0590R090 S1      
327GND              J17   -85         A01X+115071Y+105801X0205Y0590R090 S1      
327GND              J17   -88         A01X+115071Y+106805X0205Y0590R090 S1      
327GND              J17   -63         A01X+115071Y+096431X0205Y0590R090 S1      
327GND              J17   -65         A01X+115071Y+097100X0205Y0590R090 S1      
327GND              J17   -67         A01X+115071Y+097770X0205Y0590R090 S1      
327GND              J17   -69         A01X+115071Y+098439X0205Y0590R090 S1      
327GND              J17   -71         A01X+115071Y+099108X0205Y0590R090 S1      
327GND              J17   -73         A01X+115071Y+099778X0205Y0590R090 S1      
327GND              J17   -75         A01X+115071Y+100447X0205Y0590R090 S1      
327GND              J17   -48         A01X+115071Y+091411X0205Y0590R090 S1      
327GND              J17   -50         A01X+115071Y+092081X0205Y0590R090 S1      
327GND              J17   -52         A01X+115071Y+092750X0205Y0590R090 S1      
327GND              J17   -59         A01X+115071Y+095092X0205Y0590R090 S1      
327GND              J17   -61         A01X+115071Y+095762X0205Y0590R090 S1      
327GND              J17   -30         A01X+115071Y+085388X0205Y0590R090 S1      
327GND              J17   -37         A01X+115071Y+087730X0205Y0590R090 S1      
327GND              J17   -39         A01X+115071Y+088400X0205Y0590R090 S1      
327GND              J17   -41         A01X+115071Y+089069X0205Y0590R090 S1      
327GND              J17   -15         A01X+115071Y+080368X0205Y0590R090 S1      
327GND              J17   -17         A01X+115071Y+081037X0205Y0590R090 S1      
327GND              J17   -19         A01X+115071Y+081707X0205Y0590R090 S1      
327GND              J17   -26         A01X+115071Y+084049X0205Y0590R090 S1      
327GND              J17   -28         A01X+115071Y+084718X0205Y0590R090 S1      
327GND              J17   -8          A01X+115071Y+078026X0205Y0590R090 S1      
327GND              J21   -141        A01X+109131Y+124541X0205Y0590R090 S1      
327GND              J19   -286        A01X+110487Y+124876X0205Y0590R090 S1      
327GND              J19   -141        A01X+112101Y+124541X0205Y0590R090 S1      
327GND              J17   -286        A01X+113457Y+124876X0205Y0590R090 S1      
327GND              J21   -130        A01X+109131Y+120860X0205Y0590R090 S1      
327GND              J21   -132        A01X+109131Y+121530X0205Y0590R090 S1      
327GND              J21   -134        A01X+109131Y+122199X0205Y0590R090 S1      
327GND              J19   -268        A01X+110487Y+118852X0205Y0590R090 S1      
327GND              J19   -275        A01X+110487Y+121195X0205Y0590R090 S1      
327GND              J19   -277        A01X+110487Y+121864X0205Y0590R090 S1      
327GND              J19   -279        A01X+110487Y+122534X0205Y0590R090 S1      
327GND              J19   -130        A01X+112101Y+120860X0205Y0590R090 S1      
327GND              J19   -132        A01X+112101Y+121530X0205Y0590R090 S1      
327GND              J19   -134        A01X+112101Y+122199X0205Y0590R090 S1      
327GND              J17   -268        A01X+113457Y+118852X0205Y0590R090 S1      
327GND              J17   -275        A01X+113457Y+121195X0205Y0590R090 S1      
327GND              J17   -277        A01X+113457Y+121864X0205Y0590R090 S1      
327GND              J17   -279        A01X+113457Y+122534X0205Y0590R090 S1      
327GND              J21   -110        A01X+109131Y+114167X0205Y0590R090 S1      
327GND              J21   -108        A01X+109131Y+113498X0205Y0590R090 S1      
327GND              J21   -112        A01X+109131Y+114837X0205Y0590R090 S1      
327GND              J21   -119        A01X+109131Y+117179X0205Y0590R090 S1      
327GND              J21   -121        A01X+109131Y+117848X0205Y0590R090 S1      
327GND              J21   -123        A01X+109131Y+118518X0205Y0590R090 S1      
327GND              J19   -253        A01X+110487Y+113833X0205Y0590R090 S1      
327GND              J19   -255        A01X+110487Y+114502X0205Y0590R090 S1      
327GND              J19   -257        A01X+110487Y+115171X0205Y0590R090 S1      
327GND              J19   -264        A01X+110487Y+117514X0205Y0590R090 S1      
327GND              J19   -266        A01X+110487Y+118183X0205Y0590R090 S1      
327GND              J19   -110        A01X+112101Y+114167X0205Y0590R090 S1      
327GND              J19   -108        A01X+112101Y+113498X0205Y0590R090 S1      
327GND              J19   -112        A01X+112101Y+114837X0205Y0590R090 S1      
327GND              J19   -119        A01X+112101Y+117179X0205Y0590R090 S1      
327GND              J19   -121        A01X+112101Y+117848X0205Y0590R090 S1      
327GND              J19   -123        A01X+112101Y+118518X0205Y0590R090 S1      
327GND              J17   -253        A01X+113457Y+113833X0205Y0590R090 S1      
327GND              J17   -255        A01X+113457Y+114502X0205Y0590R090 S1      
327GND              J17   -257        A01X+113457Y+115171X0205Y0590R090 S1      
327GND              J17   -264        A01X+113457Y+117514X0205Y0590R090 S1      
327GND              J17   -266        A01X+113457Y+118183X0205Y0590R090 S1      
327GND              J21   -90         A01X+109131Y+107474X0205Y0590R090 S1      
327GND              J21   -97         A01X+109131Y+109817X0205Y0590R090 S1      
327GND              J21   -99         A01X+109131Y+110486X0205Y0590R090 S1      
327GND              J21   -101        A01X+109131Y+111156X0205Y0590R090 S1      
327GND              J19   -235        A01X+110487Y+107809X0205Y0590R090 S1      
327GND              J19   -242        A01X+110487Y+110152X0205Y0590R090 S1      
327GND              J19   -244        A01X+110487Y+110821X0205Y0590R090 S1      
327GND              J19   -246        A01X+110487Y+111490X0205Y0590R090 S1      
327GND              J19   -90         A01X+112101Y+107474X0205Y0590R090 S1      
327GND              J19   -97         A01X+112101Y+109817X0205Y0590R090 S1      
327GND              J19   -99         A01X+112101Y+110486X0205Y0590R090 S1      
327GND              J19   -101        A01X+112101Y+111156X0205Y0590R090 S1      
327GND              J17   -235        A01X+113457Y+107809X0205Y0590R090 S1      
327GND              J17   -242        A01X+113457Y+110152X0205Y0590R090 S1      
327GND              J17   -244        A01X+113457Y+110821X0205Y0590R090 S1      
327GND              J17   -246        A01X+113457Y+111490X0205Y0590R090 S1      
327GND              J21   -77         A01X+109131Y+103124X0205Y0590R090 S1      
327GND              J21   -79         A01X+109131Y+103793X0205Y0590R090 S1      
327GND              J21   -81         A01X+109131Y+104463X0205Y0590R090 S1      
327GND              J21   -83         A01X+109131Y+105132X0205Y0590R090 S1      
327GND              J21   -85         A01X+109131Y+105801X0205Y0590R090 S1      
327GND              J21   -88         A01X+109131Y+106805X0205Y0590R090 S1      
327GND              J19   -222        A01X+110487Y+103459X0205Y0590R090 S1      
327GND              J19   -224        A01X+110487Y+104128X0205Y0590R090 S1      
327GND              J19   -226        A01X+110487Y+104797X0205Y0590R090 S1      
327GND              J19   -228        A01X+110487Y+105467X0205Y0590R090 S1      
327GND              J19   -230        A01X+110487Y+106136X0205Y0590R090 S1      
327GND              J19   -233        A01X+110487Y+107140X0205Y0590R090 S1      
327GND              J19   -77         A01X+112101Y+103124X0205Y0590R090 S1      
327GND              J19   -79         A01X+112101Y+103793X0205Y0590R090 S1      
327GND              J19   -81         A01X+112101Y+104463X0205Y0590R090 S1      
327GND              J19   -83         A01X+112101Y+105132X0205Y0590R090 S1      
327GND              J19   -85         A01X+112101Y+105801X0205Y0590R090 S1      
327GND              J19   -88         A01X+112101Y+106805X0205Y0590R090 S1      
327GND              J17   -222        A01X+113457Y+103459X0205Y0590R090 S1      
327GND              J17   -224        A01X+113457Y+104128X0205Y0590R090 S1      
327GND              J17   -226        A01X+113457Y+104797X0205Y0590R090 S1      
327GND              J17   -228        A01X+113457Y+105467X0205Y0590R090 S1      
327GND              J17   -230        A01X+113457Y+106136X0205Y0590R090 S1      
327GND              J17   -233        A01X+113457Y+107140X0205Y0590R090 S1      
327GND              J21   -63         A01X+109131Y+096431X0205Y0590R090 S1      
327GND              J21   -65         A01X+109131Y+097100X0205Y0590R090 S1      
327GND              J21   -67         A01X+109131Y+097770X0205Y0590R090 S1      
327GND              J21   -69         A01X+109131Y+098439X0205Y0590R090 S1      
327GND              J21   -71         A01X+109131Y+099108X0205Y0590R090 S1      
327GND              J21   -73         A01X+109131Y+099778X0205Y0590R090 S1      
327GND              J21   -75         A01X+109131Y+100447X0205Y0590R090 S1      
327GND              J19   -210        A01X+110487Y+097435X0205Y0590R090 S1      
327GND              J19   -212        A01X+110487Y+098104X0205Y0590R090 S1      
327GND              J19   -208        A01X+110487Y+096766X0205Y0590R090 S1      
327GND              J19   -214        A01X+110487Y+098774X0205Y0590R090 S1      
327GND              J19   -216        A01X+110487Y+099443X0205Y0590R090 S1      
327GND              J19   -219        A01X+110487Y+100447X0205Y0590R090 S1      
327GND              J19   -63         A01X+112101Y+096431X0205Y0590R090 S1      
327GND              J19   -65         A01X+112101Y+097100X0205Y0590R090 S1      
327GND              J19   -67         A01X+112101Y+097770X0205Y0590R090 S1      
327GND              J19   -69         A01X+112101Y+098439X0205Y0590R090 S1      
327GND              J19   -71         A01X+112101Y+099108X0205Y0590R090 S1      
327GND              J19   -73         A01X+112101Y+099778X0205Y0590R090 S1      
327GND              J19   -75         A01X+112101Y+100447X0205Y0590R090 S1      
327GND              J17   -210        A01X+113457Y+097435X0205Y0590R090 S1      
327GND              J17   -212        A01X+113457Y+098104X0205Y0590R090 S1      
327GND              J17   -208        A01X+113457Y+096766X0205Y0590R090 S1      
327GND              J17   -214        A01X+113457Y+098774X0205Y0590R090 S1      
327GND              J17   -216        A01X+113457Y+099443X0205Y0590R090 S1      
327GND              J17   -219        A01X+113457Y+100447X0205Y0590R090 S1      
327GND              J21   -48         A01X+109131Y+091411X0205Y0590R090 S1      
327GND              J21   -50         A01X+109131Y+092081X0205Y0590R090 S1      
327GND              J21   -52         A01X+109131Y+092750X0205Y0590R090 S1      
327GND              J21   -59         A01X+109131Y+095092X0205Y0590R090 S1      
327GND              J21   -61         A01X+109131Y+095762X0205Y0590R090 S1      
327GND              J19   -193        A01X+110487Y+091746X0205Y0590R090 S1      
327GND              J19   -195        A01X+110487Y+092415X0205Y0590R090 S1      
327GND              J19   -197        A01X+110487Y+093085X0205Y0590R090 S1      
327GND              J19   -204        A01X+110487Y+095427X0205Y0590R090 S1      
327GND              J19   -206        A01X+110487Y+096096X0205Y0590R090 S1      
327GND              J19   -48         A01X+112101Y+091411X0205Y0590R090 S1      
327GND              J19   -50         A01X+112101Y+092081X0205Y0590R090 S1      
327GND              J19   -52         A01X+112101Y+092750X0205Y0590R090 S1      
327GND              J19   -59         A01X+112101Y+095092X0205Y0590R090 S1      
327GND              J19   -61         A01X+112101Y+095762X0205Y0590R090 S1      
327GND              J17   -193        A01X+113457Y+091746X0205Y0590R090 S1      
327GND              J17   -195        A01X+113457Y+092415X0205Y0590R090 S1      
327GND              J17   -197        A01X+113457Y+093085X0205Y0590R090 S1      
327GND              J17   -204        A01X+113457Y+095427X0205Y0590R090 S1      
327GND              J17   -206        A01X+113457Y+096096X0205Y0590R090 S1      
327GND              J21   -30         A01X+109131Y+085388X0205Y0590R090 S1      
327GND              J21   -37         A01X+109131Y+087730X0205Y0590R090 S1      
327GND              J21   -39         A01X+109131Y+088400X0205Y0590R090 S1      
327GND              J21   -41         A01X+109131Y+089069X0205Y0590R090 S1      
327GND              J19   -173        A01X+110487Y+085053X0205Y0590R090 S1      
327GND              J19   -175        A01X+110487Y+085722X0205Y0590R090 S1      
327GND              J19   -182        A01X+110487Y+088065X0205Y0590R090 S1      
327GND              J19   -184        A01X+110487Y+088734X0205Y0590R090 S1      
327GND              J19   -186        A01X+110487Y+089404X0205Y0590R090 S1      
327GND              J19   -30         A01X+112101Y+085388X0205Y0590R090 S1      
327GND              J19   -37         A01X+112101Y+087730X0205Y0590R090 S1      
327GND              J19   -39         A01X+112101Y+088400X0205Y0590R090 S1      
327GND              J19   -41         A01X+112101Y+089069X0205Y0590R090 S1      
327GND              J17   -173        A01X+113457Y+085053X0205Y0590R090 S1      
327GND              J17   -175        A01X+113457Y+085722X0205Y0590R090 S1      
327GND              J17   -182        A01X+113457Y+088065X0205Y0590R090 S1      
327GND              J17   -184        A01X+113457Y+088734X0205Y0590R090 S1      
327GND              J17   -186        A01X+113457Y+089404X0205Y0590R090 S1      
327GND              J21   -15         A01X+109131Y+080368X0205Y0590R090 S1      
327GND              J21   -17         A01X+109131Y+081037X0205Y0590R090 S1      
327GND              J21   -19         A01X+109131Y+081707X0205Y0590R090 S1      
327GND              J21   -26         A01X+109131Y+084049X0205Y0590R090 S1      
327GND              J21   -28         A01X+109131Y+084718X0205Y0590R090 S1      
327GND              J19   -160        A01X+110487Y+080703X0205Y0590R090 S1      
327GND              J19   -162        A01X+110487Y+081372X0205Y0590R090 S1      
327GND              J19   -164        A01X+110487Y+082041X0205Y0590R090 S1      
327GND              J19   -171        A01X+110487Y+084384X0205Y0590R090 S1      
327GND              J19   -15         A01X+112101Y+080368X0205Y0590R090 S1      
327GND              J19   -17         A01X+112101Y+081037X0205Y0590R090 S1      
327GND              J19   -19         A01X+112101Y+081707X0205Y0590R090 S1      
327GND              J19   -26         A01X+112101Y+084049X0205Y0590R090 S1      
327GND              J19   -28         A01X+112101Y+084718X0205Y0590R090 S1      
327GND              J17   -160        A01X+113457Y+080703X0205Y0590R090 S1      
327GND              J17   -162        A01X+113457Y+081372X0205Y0590R090 S1      
327GND              J17   -164        A01X+113457Y+082041X0205Y0590R090 S1      
327GND              J17   -171        A01X+113457Y+084384X0205Y0590R090 S1      
327GND              J21   -8          A01X+109131Y+078026X0205Y0590R090 S1      
327GND              J19   -151        A01X+110487Y+077691X0205Y0590R090 S1      
327GND              J19   -153        A01X+110487Y+078360X0205Y0590R090 S1      
327GND              J19   -8          A01X+112101Y+078026X0205Y0590R090 S1      
327GND              J17   -151        A01X+113457Y+077691X0205Y0590R090 S1      
327GND              J17   -153        A01X+113457Y+078360X0205Y0590R090 S1      
327GND              J23   -286        A01X+104546Y+124876X0205Y0590R090 S1      
327GND              J23   -288        A01X+104546Y+125545X0205Y0590R090 S1      
327GND              J23   -141        A01X+106161Y+124541X0205Y0590R090 S1      
327GND              J21   -286        A01X+107517Y+124876X0205Y0590R090 S1      
327GND              J23   -268        A01X+104546Y+118852X0205Y0590R090 S1      
327GND              J23   -275        A01X+104546Y+121195X0205Y0590R090 S1      
327GND              J23   -277        A01X+104546Y+121864X0205Y0590R090 S1      
327GND              J23   -279        A01X+104546Y+122534X0205Y0590R090 S1      
327GND              J23   -130        A01X+106161Y+120860X0205Y0590R090 S1      
327GND              J23   -132        A01X+106161Y+121530X0205Y0590R090 S1      
327GND              J23   -134        A01X+106161Y+122199X0205Y0590R090 S1      
327GND              J21   -268        A01X+107517Y+118852X0205Y0590R090 S1      
327GND              J21   -275        A01X+107517Y+121195X0205Y0590R090 S1      
327GND              J21   -277        A01X+107517Y+121864X0205Y0590R090 S1      
327GND              J21   -279        A01X+107517Y+122534X0205Y0590R090 S1      
327GND              J23   -253        A01X+104546Y+113833X0205Y0590R090 S1      
327GND              J23   -255        A01X+104546Y+114502X0205Y0590R090 S1      
327GND              J23   -257        A01X+104546Y+115171X0205Y0590R090 S1      
327GND              J23   -266        A01X+104546Y+118183X0205Y0590R090 S1      
327GND              J23   -264        A01X+104546Y+117514X0205Y0590R090 S1      
327GND              J23   -110        A01X+106161Y+114167X0205Y0590R090 S1      
327GND              J23   -108        A01X+106161Y+113498X0205Y0590R090 S1      
327GND              J23   -112        A01X+106161Y+114837X0205Y0590R090 S1      
327GND              J23   -119        A01X+106161Y+117179X0205Y0590R090 S1      
327GND              J23   -121        A01X+106161Y+117848X0205Y0590R090 S1      
327GND              J23   -123        A01X+106161Y+118518X0205Y0590R090 S1      
327GND              J21   -253        A01X+107517Y+113833X0205Y0590R090 S1      
327GND              J21   -255        A01X+107517Y+114502X0205Y0590R090 S1      
327GND              J21   -257        A01X+107517Y+115171X0205Y0590R090 S1      
327GND              J21   -264        A01X+107517Y+117514X0205Y0590R090 S1      
327GND              J21   -266        A01X+107517Y+118183X0205Y0590R090 S1      
327GND              J23   -235        A01X+104546Y+107809X0205Y0590R090 S1      
327GND              J23   -242        A01X+104546Y+110152X0205Y0590R090 S1      
327GND              J23   -244        A01X+104546Y+110821X0205Y0590R090 S1      
327GND              J23   -246        A01X+104546Y+111490X0205Y0590R090 S1      
327GND              J23   -90         A01X+106161Y+107474X0205Y0590R090 S1      
327GND              J23   -97         A01X+106161Y+109817X0205Y0590R090 S1      
327GND              J23   -99         A01X+106161Y+110486X0205Y0590R090 S1      
327GND              J23   -101        A01X+106161Y+111156X0205Y0590R090 S1      
327GND              J21   -235        A01X+107517Y+107809X0205Y0590R090 S1      
327GND              J21   -242        A01X+107517Y+110152X0205Y0590R090 S1      
327GND              J21   -244        A01X+107517Y+110821X0205Y0590R090 S1      
327GND              J21   -246        A01X+107517Y+111490X0205Y0590R090 S1      
327GND              J23   -222        A01X+104546Y+103459X0205Y0590R090 S1      
327GND              J23   -224        A01X+104546Y+104128X0205Y0590R090 S1      
327GND              J23   -226        A01X+104546Y+104797X0205Y0590R090 S1      
327GND              J23   -228        A01X+104546Y+105467X0205Y0590R090 S1      
327GND              J23   -230        A01X+104546Y+106136X0205Y0590R090 S1      
327GND              J23   -233        A01X+104546Y+107140X0205Y0590R090 S1      
327GND              J23   -79         A01X+106161Y+103793X0205Y0590R090 S1      
327GND              J23   -81         A01X+106161Y+104463X0205Y0590R090 S1      
327GND              J23   -77         A01X+106161Y+103124X0205Y0590R090 S1      
327GND              J23   -83         A01X+106161Y+105132X0205Y0590R090 S1      
327GND              J23   -85         A01X+106161Y+105801X0205Y0590R090 S1      
327GND              J23   -88         A01X+106161Y+106805X0205Y0590R090 S1      
327GND              J21   -222        A01X+107517Y+103459X0205Y0590R090 S1      
327GND              J21   -224        A01X+107517Y+104128X0205Y0590R090 S1      
327GND              J21   -226        A01X+107517Y+104797X0205Y0590R090 S1      
327GND              J21   -228        A01X+107517Y+105467X0205Y0590R090 S1      
327GND              J21   -230        A01X+107517Y+106136X0205Y0590R090 S1      
327GND              J21   -233        A01X+107517Y+107140X0205Y0590R090 S1      
327GND              J23   -210        A01X+104546Y+097435X0205Y0590R090 S1      
327GND              J23   -212        A01X+104546Y+098104X0205Y0590R090 S1      
327GND              J23   -208        A01X+104546Y+096766X0205Y0590R090 S1      
327GND              J23   -214        A01X+104546Y+098774X0205Y0590R090 S1      
327GND              J23   -216        A01X+104546Y+099443X0205Y0590R090 S1      
327GND              J23   -219        A01X+104546Y+100447X0205Y0590R090 S1      
327GND              J23   -63         A01X+106161Y+096431X0205Y0590R090 S1      
327GND              J23   -65         A01X+106161Y+097100X0205Y0590R090 S1      
327GND              J23   -67         A01X+106161Y+097770X0205Y0590R090 S1      
327GND              J23   -69         A01X+106161Y+098439X0205Y0590R090 S1      
327GND              J23   -71         A01X+106161Y+099108X0205Y0590R090 S1      
327GND              J23   -73         A01X+106161Y+099778X0205Y0590R090 S1      
327GND              J23   -75         A01X+106161Y+100447X0205Y0590R090 S1      
327GND              J21   -210        A01X+107517Y+097435X0205Y0590R090 S1      
327GND              J21   -212        A01X+107517Y+098104X0205Y0590R090 S1      
327GND              J21   -208        A01X+107517Y+096766X0205Y0590R090 S1      
327GND              J21   -214        A01X+107517Y+098774X0205Y0590R090 S1      
327GND              J21   -216        A01X+107517Y+099443X0205Y0590R090 S1      
327GND              J21   -219        A01X+107517Y+100447X0205Y0590R090 S1      
327GND              J23   -193        A01X+104546Y+091746X0205Y0590R090 S1      
327GND              J23   -195        A01X+104546Y+092415X0205Y0590R090 S1      
327GND              J23   -197        A01X+104546Y+093085X0205Y0590R090 S1      
327GND              J23   -204        A01X+104546Y+095427X0205Y0590R090 S1      
327GND              J23   -206        A01X+104546Y+096096X0205Y0590R090 S1      
327GND              J23   -48         A01X+106161Y+091411X0205Y0590R090 S1      
327GND              J23   -52         A01X+106161Y+092750X0205Y0590R090 S1      
327GND              J23   -50         A01X+106161Y+092081X0205Y0590R090 S1      
327GND              J23   -59         A01X+106161Y+095092X0205Y0590R090 S1      
327GND              J23   -61         A01X+106161Y+095762X0205Y0590R090 S1      
327GND              J21   -193        A01X+107517Y+091746X0205Y0590R090 S1      
327GND              J21   -195        A01X+107517Y+092415X0205Y0590R090 S1      
327GND              J21   -197        A01X+107517Y+093085X0205Y0590R090 S1      
327GND              J21   -204        A01X+107517Y+095427X0205Y0590R090 S1      
327GND              J21   -206        A01X+107517Y+096096X0205Y0590R090 S1      
327GND              J23   -173        A01X+104546Y+085053X0205Y0590R090 S1      
327GND              J23   -175        A01X+104546Y+085722X0205Y0590R090 S1      
327GND              J23   -182        A01X+104546Y+088065X0205Y0590R090 S1      
327GND              J23   -184        A01X+104546Y+088734X0205Y0590R090 S1      
327GND              J23   -186        A01X+104546Y+089404X0205Y0590R090 S1      
327GND              J23   -30         A01X+106161Y+085388X0205Y0590R090 S1      
327GND              J23   -37         A01X+106161Y+087730X0205Y0590R090 S1      
327GND              J23   -39         A01X+106161Y+088400X0205Y0590R090 S1      
327GND              J23   -41         A01X+106161Y+089069X0205Y0590R090 S1      
327GND              J21   -173        A01X+107517Y+085053X0205Y0590R090 S1      
327GND              J21   -175        A01X+107517Y+085722X0205Y0590R090 S1      
327GND              J21   -182        A01X+107517Y+088065X0205Y0590R090 S1      
327GND              J21   -184        A01X+107517Y+088734X0205Y0590R090 S1      
327GND              J21   -186        A01X+107517Y+089404X0205Y0590R090 S1      
327GND              J23   -160        A01X+104546Y+080703X0205Y0590R090 S1      
327GND              J23   -162        A01X+104546Y+081372X0205Y0590R090 S1      
327GND              J23   -164        A01X+104546Y+082041X0205Y0590R090 S1      
327GND              J23   -171        A01X+104546Y+084384X0205Y0590R090 S1      
327GND              J23   -15         A01X+106161Y+080368X0205Y0590R090 S1      
327GND              J23   -17         A01X+106161Y+081037X0205Y0590R090 S1      
327GND              J23   -19         A01X+106161Y+081707X0205Y0590R090 S1      
327GND              J23   -28         A01X+106161Y+084718X0205Y0590R090 S1      
327GND              J23   -26         A01X+106161Y+084049X0205Y0590R090 S1      
327GND              J21   -160        A01X+107517Y+080703X0205Y0590R090 S1      
327GND              J21   -162        A01X+107517Y+081372X0205Y0590R090 S1      
327GND              J21   -164        A01X+107517Y+082041X0205Y0590R090 S1      
327GND              J21   -171        A01X+107517Y+084384X0205Y0590R090 S1      
327GND              J23   -151        A01X+104546Y+077691X0205Y0590R090 S1      
327GND              J23   -153        A01X+104546Y+078360X0205Y0590R090 S1      
327GND              J23   -8          A01X+106161Y+078026X0205Y0590R090 S1      
327GND              J21   -151        A01X+107517Y+077691X0205Y0590R090 S1      
327GND              J21   -153        A01X+107517Y+078360X0205Y0590R090 S1      
327GND              J17   -128        A01X+115071Y+120191X0205Y0590R090 S1      
327GND              J17   -125        A01X+115071Y+119187X0205Y0590R090 S1      
327GND              J17   -139        A01X+115071Y+123872X0205Y0590R090 S1      
327GND              J17   -136        A01X+115071Y+122868X0205Y0590R090 S1      
327GND              J17   -114        A01X+115071Y+115506X0205Y0590R090 S1      
327GND              J17   -117        A01X+115071Y+116510X0205Y0590R090 S1      
327GND              J17   -95         A01X+115071Y+109148X0205Y0590R090 S1      
327GND              J17   -92         A01X+115071Y+108144X0205Y0590R090 S1      
327GND              J17   -103        A01X+115071Y+111825X0205Y0590R090 S1      
327GND              J17   -106        A01X+115071Y+112829X0205Y0590R090 S1      
327GND              J17   -46         A01X+115071Y+090742X0205Y0590R090 S1      
327GND              J17   -54         A01X+115071Y+093419X0205Y0590R090 S1      
327GND              J17   -57         A01X+115071Y+094423X0205Y0590R090 S1      
327GND              J17   -32         A01X+115071Y+086057X0205Y0590R090 S1      
327GND              J17   -35         A01X+115071Y+087061X0205Y0590R090 S1      
327GND              J17   -43         A01X+115071Y+089738X0205Y0590R090 S1      
327GND              J17   -13         A01X+115071Y+079699X0205Y0590R090 S1      
327GND              J17   -21         A01X+115071Y+082376X0205Y0590R090 S1      
327GND              J17   -24         A01X+115071Y+083380X0205Y0590R090 S1      
327GND              J17   -10         A01X+115071Y+078695X0205Y0590R090 S1      
327GND              J21   -128        A01X+109131Y+120191X0205Y0590R090 S1      
327GND              J21   -125        A01X+109131Y+119187X0205Y0590R090 S1      
327GND              J21   -139        A01X+109131Y+123872X0205Y0590R090 S1      
327GND              J21   -136        A01X+109131Y+122868X0205Y0590R090 S1      
327GND              J19   -273        A01X+110487Y+120526X0205Y0590R090 S1      
327GND              J19   -270        A01X+110487Y+119522X0205Y0590R090 S1      
327GND              J19   -281        A01X+110487Y+123203X0205Y0590R090 S1      
327GND              J19   -284        A01X+110487Y+124207X0205Y0590R090 S1      
327GND              J19   -128        A01X+112101Y+120191X0205Y0590R090 S1      
327GND              J19   -125        A01X+112101Y+119187X0205Y0590R090 S1      
327GND              J19   -139        A01X+112101Y+123872X0205Y0590R090 S1      
327GND              J19   -136        A01X+112101Y+122868X0205Y0590R090 S1      
327GND              J17   -273        A01X+113457Y+120526X0205Y0590R090 S1      
327GND              J17   -270        A01X+113457Y+119522X0205Y0590R090 S1      
327GND              J17   -281        A01X+113457Y+123203X0205Y0590R090 S1      
327GND              J17   -284        A01X+113457Y+124207X0205Y0590R090 S1      
327GND              J21   -114        A01X+109131Y+115506X0205Y0590R090 S1      
327GND              J21   -117        A01X+109131Y+116510X0205Y0590R090 S1      
327GND              J19   -251        A01X+110487Y+113163X0205Y0590R090 S1      
327GND              J19   -259        A01X+110487Y+115841X0205Y0590R090 S1      
327GND              J19   -262        A01X+110487Y+116844X0205Y0590R090 S1      
327GND              J19   -114        A01X+112101Y+115506X0205Y0590R090 S1      
327GND              J19   -117        A01X+112101Y+116510X0205Y0590R090 S1      
327GND              J17   -251        A01X+113457Y+113163X0205Y0590R090 S1      
327GND              J17   -259        A01X+113457Y+115841X0205Y0590R090 S1      
327GND              J17   -262        A01X+113457Y+116844X0205Y0590R090 S1      
327GND              J21   -95         A01X+109131Y+109148X0205Y0590R090 S1      
327GND              J21   -92         A01X+109131Y+108144X0205Y0590R090 S1      
327GND              J21   -103        A01X+109131Y+111825X0205Y0590R090 S1      
327GND              J21   -106        A01X+109131Y+112829X0205Y0590R090 S1      
327GND              J19   -237        A01X+110487Y+108478X0205Y0590R090 S1      
327GND              J19   -240        A01X+110487Y+109482X0205Y0590R090 S1      
327GND              J19   -248        A01X+110487Y+112160X0205Y0590R090 S1      
327GND              J19   -95         A01X+112101Y+109148X0205Y0590R090 S1      
327GND              J19   -92         A01X+112101Y+108144X0205Y0590R090 S1      
327GND              J19   -103        A01X+112101Y+111825X0205Y0590R090 S1      
327GND              J19   -106        A01X+112101Y+112829X0205Y0590R090 S1      
327GND              J17   -237        A01X+113457Y+108478X0205Y0590R090 S1      
327GND              J17   -240        A01X+113457Y+109482X0205Y0590R090 S1      
327GND              J17   -248        A01X+113457Y+112160X0205Y0590R090 S1      
327GND              J21   -46         A01X+109131Y+090742X0205Y0590R090 S1      
327GND              J21   -54         A01X+109131Y+093419X0205Y0590R090 S1      
327GND              J21   -57         A01X+109131Y+094423X0205Y0590R090 S1      
327GND              J19   -191        A01X+110487Y+091077X0205Y0590R090 S1      
327GND              J19   -199        A01X+110487Y+093754X0205Y0590R090 S1      
327GND              J19   -202        A01X+110487Y+094758X0205Y0590R090 S1      
327GND              J19   -46         A01X+112101Y+090742X0205Y0590R090 S1      
327GND              J19   -54         A01X+112101Y+093419X0205Y0590R090 S1      
327GND              J19   -57         A01X+112101Y+094423X0205Y0590R090 S1      
327GND              J17   -191        A01X+113457Y+091077X0205Y0590R090 S1      
327GND              J17   -199        A01X+113457Y+093754X0205Y0590R090 S1      
327GND              J17   -202        A01X+113457Y+094758X0205Y0590R090 S1      
327GND              J21   -32         A01X+109131Y+086057X0205Y0590R090 S1      
327GND              J21   -35         A01X+109131Y+087061X0205Y0590R090 S1      
327GND              J21   -43         A01X+109131Y+089738X0205Y0590R090 S1      
327GND              J19   -177        A01X+110487Y+086392X0205Y0590R090 S1      
327GND              J19   -180        A01X+110487Y+087396X0205Y0590R090 S1      
327GND              J19   -188        A01X+110487Y+090073X0205Y0590R090 S1      
327GND              J19   -32         A01X+112101Y+086057X0205Y0590R090 S1      
327GND              J19   -35         A01X+112101Y+087061X0205Y0590R090 S1      
327GND              J19   -43         A01X+112101Y+089738X0205Y0590R090 S1      
327GND              J17   -177        A01X+113457Y+086392X0205Y0590R090 S1      
327GND              J17   -180        A01X+113457Y+087396X0205Y0590R090 S1      
327GND              J17   -188        A01X+113457Y+090073X0205Y0590R090 S1      
327GND              J21   -13         A01X+109131Y+079699X0205Y0590R090 S1      
327GND              J21   -21         A01X+109131Y+082376X0205Y0590R090 S1      
327GND              J21   -24         A01X+109131Y+083380X0205Y0590R090 S1      
327GND              J19   -158        A01X+110487Y+080034X0205Y0590R090 S1      
327GND              J19   -166        A01X+110487Y+082711X0205Y0590R090 S1      
327GND              J19   -169        A01X+110487Y+083715X0205Y0590R090 S1      
327GND              J19   -13         A01X+112101Y+079699X0205Y0590R090 S1      
327GND              J19   -21         A01X+112101Y+082376X0205Y0590R090 S1      
327GND              J19   -24         A01X+112101Y+083380X0205Y0590R090 S1      
327GND              J17   -158        A01X+113457Y+080034X0205Y0590R090 S1      
327GND              J17   -166        A01X+113457Y+082711X0205Y0590R090 S1      
327GND              J17   -169        A01X+113457Y+083715X0205Y0590R090 S1      
327GND              J21   -10         A01X+109131Y+078695X0205Y0590R090 S1      
327GND              J19   -155        A01X+110487Y+079030X0205Y0590R090 S1      
327GND              J19   -10         A01X+112101Y+078695X0205Y0590R090 S1      
327GND              J17   -155        A01X+113457Y+079030X0205Y0590R090 S1      
327GND              J23   -273        A01X+104546Y+120526X0205Y0590R090 S1      
327GND              J23   -270        A01X+104546Y+119522X0205Y0590R090 S1      
327GND              J23   -281        A01X+104546Y+123203X0205Y0590R090 S1      
327GND              J23   -284        A01X+104546Y+124207X0205Y0590R090 S1      
327GND              J23   -128        A01X+106161Y+120191X0205Y0590R090 S1      
327GND              J23   -125        A01X+106161Y+119187X0205Y0590R090 S1      
327GND              J23   -139        A01X+106161Y+123872X0205Y0590R090 S1      
327GND              J23   -136        A01X+106161Y+122868X0205Y0590R090 S1      
327GND              J21   -273        A01X+107517Y+120526X0205Y0590R090 S1      
327GND              J21   -270        A01X+107517Y+119522X0205Y0590R090 S1      
327GND              J21   -281        A01X+107517Y+123203X0205Y0590R090 S1      
327GND              J21   -284        A01X+107517Y+124207X0205Y0590R090 S1      
327GND              J23   -251        A01X+104546Y+113163X0205Y0590R090 S1      
327GND              J23   -259        A01X+104546Y+115841X0205Y0590R090 S1      
327GND              J23   -262        A01X+104546Y+116844X0205Y0590R090 S1      
327GND              J23   -114        A01X+106161Y+115506X0205Y0590R090 S1      
327GND              J23   -117        A01X+106161Y+116510X0205Y0590R090 S1      
327GND              J21   -251        A01X+107517Y+113163X0205Y0590R090 S1      
327GND              J21   -259        A01X+107517Y+115841X0205Y0590R090 S1      
327GND              J21   -262        A01X+107517Y+116844X0205Y0590R090 S1      
327GND              J23   -237        A01X+104546Y+108478X0205Y0590R090 S1      
327GND              J23   -240        A01X+104546Y+109482X0205Y0590R090 S1      
327GND              J23   -248        A01X+104546Y+112160X0205Y0590R090 S1      
327GND              J23   -95         A01X+106161Y+109148X0205Y0590R090 S1      
327GND              J23   -92         A01X+106161Y+108144X0205Y0590R090 S1      
327GND              J23   -103        A01X+106161Y+111825X0205Y0590R090 S1      
327GND              J23   -106        A01X+106161Y+112829X0205Y0590R090 S1      
327GND              J21   -237        A01X+107517Y+108478X0205Y0590R090 S1      
327GND              J21   -240        A01X+107517Y+109482X0205Y0590R090 S1      
327GND              J21   -248        A01X+107517Y+112160X0205Y0590R090 S1      
327GND              J23   -191        A01X+104546Y+091077X0205Y0590R090 S1      
327GND              J23   -199        A01X+104546Y+093754X0205Y0590R090 S1      
327GND              J23   -202        A01X+104546Y+094758X0205Y0590R090 S1      
327GND              J23   -46         A01X+106161Y+090742X0205Y0590R090 S1      
327GND              J23   -54         A01X+106161Y+093419X0205Y0590R090 S1      
327GND              J23   -57         A01X+106161Y+094423X0205Y0590R090 S1      
327GND              J21   -191        A01X+107517Y+091077X0205Y0590R090 S1      
327GND              J21   -199        A01X+107517Y+093754X0205Y0590R090 S1      
327GND              J21   -202        A01X+107517Y+094758X0205Y0590R090 S1      
327GND              J23   -177        A01X+104546Y+086392X0205Y0590R090 S1      
327GND              J23   -180        A01X+104546Y+087396X0205Y0590R090 S1      
327GND              J23   -188        A01X+104546Y+090073X0205Y0590R090 S1      
327GND              J23   -32         A01X+106161Y+086057X0205Y0590R090 S1      
327GND              J23   -35         A01X+106161Y+087061X0205Y0590R090 S1      
327GND              J23   -43         A01X+106161Y+089738X0205Y0590R090 S1      
327GND              J21   -177        A01X+107517Y+086392X0205Y0590R090 S1      
327GND              J21   -180        A01X+107517Y+087396X0205Y0590R090 S1      
327GND              J21   -188        A01X+107517Y+090073X0205Y0590R090 S1      
327GND              J23   -158        A01X+104546Y+080034X0205Y0590R090 S1      
327GND              J23   -166        A01X+104546Y+082711X0205Y0590R090 S1      
327GND              J23   -169        A01X+104546Y+083715X0205Y0590R090 S1      
327GND              J23   -13         A01X+106161Y+079699X0205Y0590R090 S1      
327GND              J23   -21         A01X+106161Y+082376X0205Y0590R090 S1      
327GND              J23   -24         A01X+106161Y+083380X0205Y0590R090 S1      
327GND              J21   -158        A01X+107517Y+080034X0205Y0590R090 S1      
327GND              J21   -166        A01X+107517Y+082711X0205Y0590R090 S1      
327GND              J21   -169        A01X+107517Y+083715X0205Y0590R090 S1      
327GND              J23   -155        A01X+104546Y+079030X0205Y0590R090 S1      
327GND              J23   -10         A01X+106161Y+078695X0205Y0590R090 S1      
327GND              J21   -155        A01X+107517Y+079030X0205Y0590R090 S1      
317GND              VIA   -    MD0100PA00X+115071Y+125211X0190Y         S0      
317GND              VIA   -    MD0100PA00X+115071Y+124541X0190Y         S0      
317GND              VIA   -    MD0100PA00X+115071Y+120860X0190Y         S0      
317GND              VIA   -    MD0100PA00X+114631Y+119689X0190Y         S0      
317GND              VIA   -    MD0100PA00X+114526Y+120191X0190Y         S0      
317GND              VIA   -    MD0100PA00X+115071Y+122199X0190Y         S0      
317GND              VIA   -    MD0100PA00X+115071Y+121530X0190Y         S0      
317GND              VIA   -    MD0100PA00X+114526Y+122868X0190Y         S0      
317GND              VIA   -    MD0100PA00X+114631Y+123370X0190Y         S0      
317GND              VIA   -    MD0100PA00X+114526Y+123872X0190Y         S0      
317GND              VIA   -    MD0100PA00X+114526Y+116510X0190Y         S0      
317GND              VIA   -    MD0100PA00X+114631Y+116008X0190Y         S0      
317GND              VIA   -    MD0100PA00X+114526Y+115506X0190Y         S0      
317GND              VIA   -    MD0100PA00X+115071Y+117848X0190Y         S0      
317GND              VIA   -    MD0100PA00X+115071Y+117179X0190Y         S0      
317GND              VIA   -    MD0100PA00X+115071Y+118518X0190Y         S0      
317GND              VIA   -    MD0100PA00X+114526Y+119187X0190Y         S0      
317GND              VIA   -    MD0100PA00X+115071Y+111156X0190Y         S0      
317GND              VIA   -    MD0100PA00X+114526Y+111825X0190Y         S0      
317GND              VIA   -    MD0100PA00X+114526Y+112829X0190Y         S0      
317GND              VIA   -    MD0100PA00X+114631Y+112327X0190Y         S0      
317GND              VIA   -    MD0100PA00X+115071Y+113498X0190Y         S0      
317GND              VIA   -    MD0100PA00X+115071Y+114837X0190Y         S0      
317GND              VIA   -    MD0100PA00X+115071Y+114167X0190Y         S0      
317GND              VIA   -    MD0100PA00X+115071Y+106805X0190Y         S0      
317GND              VIA   -    MD0100PA00X+115071Y+107474X0190Y         S0      
317GND              VIA   -    MD0100PA00X+114526Y+108144X0190Y         S0      
317GND              VIA   -    MD0100PA00X+114631Y+108646X0190Y         S0      
317GND              VIA   -    MD0100PA00X+115071Y+110486X0190Y         S0      
317GND              VIA   -    MD0100PA00X+115071Y+109817X0190Y         S0      
317GND              VIA   -    MD0100PA00X+114526Y+109148X0190Y         S0      
317GND              VIA   -    MD0100PA00X+115071Y+104463X0190Y         S0      
317GND              VIA   -    MD0100PA00X+115071Y+103793X0190Y         S0      
317GND              VIA   -    MD0100PA00X+115071Y+103124X0190Y         S0      
317GND              VIA   -    MD0100PA00X+115071Y+105801X0190Y         S0      
317GND              VIA   -    MD0100PA00X+115071Y+105132X0190Y         S0      
317GND              VIA   -    MD0100PA00X+115071Y+095762X0190Y         S0      
317GND              VIA   -    MD0100PA00X+115071Y+097100X0190Y         S0      
317GND              VIA   -    MD0100PA00X+115071Y+096431X0190Y         S0      
317GND              VIA   -    MD0100PA00X+115071Y+098439X0190Y         S0      
317GND              VIA   -    MD0100PA00X+115071Y+097770X0190Y         S0      
317GND              VIA   -    MD0100PA00X+115071Y+099778X0190Y         S0      
317GND              VIA   -    MD0100PA00X+115071Y+099108X0190Y         S0      
317GND              VIA   -    MD0100PA00X+115071Y+100447X0190Y         S0      
317GND              VIA   -    MD0100PA00X+115071Y+092081X0190Y         S0      
317GND              VIA   -    MD0100PA00X+115071Y+091411X0190Y         S0      
317GND              VIA   -    MD0100PA00X+115071Y+092750X0190Y         S0      
317GND              VIA   -    MD0100PA00X+114631Y+093921X0190Y         S0      
317GND              VIA   -    MD0100PA00X+114526Y+093419X0190Y         S0      
317GND              VIA   -    MD0100PA00X+115071Y+095092X0190Y         S0      
317GND              VIA   -    MD0100PA00X+114526Y+094423X0190Y         S0      
317GND              VIA   -    MD0100PA00X+115071Y+087730X0190Y         S0      
317GND              VIA   -    MD0100PA00X+114526Y+087061X0190Y         S0      
317GND              VIA   -    MD0100PA00X+115071Y+089069X0190Y         S0      
317GND              VIA   -    MD0100PA00X+115071Y+088400X0190Y         S0      
317GND              VIA   -    MD0100PA00X+114526Y+089738X0190Y         S0      
317GND              VIA   -    MD0100PA00X+114631Y+090240X0190Y         S0      
317GND              VIA   -    MD0100PA00X+114526Y+090742X0190Y         S0      
317GND              VIA   -    MD0100PA00X+114526Y+083380X0190Y         S0      
317GND              VIA   -    MD0100PA00X+114526Y+082376X0190Y         S0      
317GND              VIA   -    MD0100PA00X+114631Y+082878X0190Y         S0      
317GND              VIA   -    MD0100PA00X+115071Y+084718X0190Y         S0      
317GND              VIA   -    MD0100PA00X+115071Y+084049X0190Y         S0      
317GND              VIA   -    MD0100PA00X+115071Y+085388X0190Y         S0      
317GND              VIA   -    MD0100PA00X+114526Y+086057X0190Y         S0      
317GND              VIA   -    MD0100PA00X+114631Y+086559X0190Y         S0      
317GND              VIA   -    MD0100PA00X+115071Y+078026X0190Y         S0      
317GND              VIA   -    MD0100PA00X+114526Y+078695X0190Y         S0      
317GND              VIA   -    MD0100PA00X+114631Y+079197X0190Y         S0      
317GND              VIA   -    MD0100PA00X+115071Y+080368X0190Y         S0      
317GND              VIA   -    MD0100PA00X+114526Y+079699X0190Y         S0      
317GND              VIA   -    MD0100PA00X+115071Y+081707X0190Y         S0      
317GND              VIA   -    MD0100PA00X+115071Y+081037X0190Y         S0      
317GND              VIA   -    MD0100PA00X+114002Y+124207X0190Y    R180 S0      
317GND              VIA   -    MD0100PA00X+113457Y+124876X0190Y         S0      
317GND              VIA   -    MD0100PA00X+113457Y+125545X0190Y         S0      
317GND              VIA   -    MD0100PA00X+114002Y+119522X0190Y    R180 S0      
317GND              VIA   -    MD0100PA00X+114002Y+120526X0190Y    R180 S0      
317GND              VIA   -    MD0100PA00X+113017Y+120024X0190Y         S0      
317GND              VIA   -    MD0100PA00X+113457Y+121864X0190Y         S0      
317GND              VIA   -    MD0100PA00X+113457Y+121195X0190Y         S0      
317GND              VIA   -    MD0100PA00X+113457Y+122534X0190Y         S0      
317GND              VIA   -    MD0100PA00X+114002Y+123203X0190Y    R180 S0      
317GND              VIA   -    MD0100PA00X+113017Y+123705X0190Y         S0      
317GND              VIA   -    MD0100PA00X+114002Y+115841X0190Y    R180 S0      
317GND              VIA   -    MD0100PA00X+113457Y+115171X0190Y         S0      
317GND              VIA   -    MD0100PA00X+113017Y+116343X0190Y         S0      
317GND              VIA   -    MD0100PA00X+113457Y+117514X0190Y         S0      
317GND              VIA   -    MD0100PA00X+114002Y+116844X0190Y    R180 S0      
317GND              VIA   -    MD0100PA00X+113457Y+118183X0190Y         S0      
317GND              VIA   -    MD0100PA00X+113457Y+118852X0190Y         S0      
317GND              VIA   -    MD0100PA00X+114002Y+112160X0190Y    R180 S0      
317GND              VIA   -    MD0100PA00X+113017Y+112662X0190Y         S0      
317GND              VIA   -    MD0100PA00X+114002Y+113163X0190Y    R180 S0      
317GND              VIA   -    MD0100PA00X+113457Y+114502X0190Y         S0      
317GND              VIA   -    MD0100PA00X+113457Y+113833X0190Y         S0      
317GND              VIA   -    MD0100PA00X+114002Y+108478X0190Y    R180 S0      
317GND              VIA   -    MD0100PA00X+113457Y+107809X0190Y         S0      
317GND              VIA   -    MD0100PA00X+113017Y+108980X0190Y         S0      
317GND              VIA   -    MD0100PA00X+113457Y+110152X0190Y         S0      
317GND              VIA   -    MD0100PA00X+114002Y+109482X0190Y    R180 S0      
317GND              VIA   -    MD0100PA00X+113457Y+111490X0190Y         S0      
317GND              VIA   -    MD0100PA00X+113457Y+110821X0190Y         S0      
317GND              VIA   -    MD0100PA00X+113457Y+099443X0190Y         S0      
317GND              VIA   -    MD0100PA00X+113457Y+098774X0190Y         S0      
317GND              VIA   -    MD0100PA00X+113457Y+100447X0190Y         S0      
317GND              VIA   -    MD0100PA00X+113457Y+104128X0190Y         S0      
317GND              VIA   -    MD0100PA00X+113457Y+103459X0190Y         S0      
317GND              VIA   -    MD0100PA00X+113457Y+105467X0190Y         S0      
317GND              VIA   -    MD0100PA00X+113457Y+104797X0190Y         S0      
317GND              VIA   -    MD0100PA00X+113457Y+107140X0190Y         S0      
317GND              VIA   -    MD0100PA00X+113457Y+106136X0190Y         S0      
317GND              VIA   -    MD0100PA00X+113457Y+096096X0190Y         S0      
317GND              VIA   -    MD0100PA00X+113457Y+096766X0190Y         S0      
317GND              VIA   -    MD0100PA00X+113457Y+098104X0190Y         S0      
317GND              VIA   -    MD0100PA00X+113457Y+097435X0190Y         S0      
317GND              VIA   -    MD0100PA00X+113457Y+092415X0190Y         S0      
317GND              VIA   -    MD0100PA00X+113457Y+091746X0190Y         S0      
317GND              VIA   -    MD0100PA00X+114002Y+093754X0190Y    R180 S0      
317GND              VIA   -    MD0100PA00X+113457Y+093085X0190Y         S0      
317GND              VIA   -    MD0100PA00X+113457Y+095427X0190Y         S0      
317GND              VIA   -    MD0100PA00X+114002Y+094758X0190Y    R180 S0      
317GND              VIA   -    MD0100PA00X+113017Y+094256X0190Y         S0      
317GND              VIA   -    MD0100PA00X+113457Y+088065X0190Y         S0      
317GND              VIA   -    MD0100PA00X+114002Y+087396X0190Y    R180 S0      
317GND              VIA   -    MD0100PA00X+113017Y+086894X0190Y         S0      
317GND              VIA   -    MD0100PA00X+113457Y+089404X0190Y         S0      
317GND              VIA   -    MD0100PA00X+113457Y+088734X0190Y         S0      
317GND              VIA   -    MD0100PA00X+114002Y+090073X0190Y    R180 S0      
317GND              VIA   -    MD0100PA00X+114002Y+091077X0190Y    R180 S0      
317GND              VIA   -    MD0100PA00X+113017Y+090575X0190Y         S0      
317GND              VIA   -    MD0100PA00X+114002Y+083715X0190Y    R180 S0      
317GND              VIA   -    MD0100PA00X+114002Y+082711X0190Y    R180 S0      
317GND              VIA   -    MD0100PA00X+113017Y+083213X0190Y         S0      
317GND              VIA   -    MD0100PA00X+113457Y+084384X0190Y         S0      
317GND              VIA   -    MD0100PA00X+113457Y+085053X0190Y         S0      
317GND              VIA   -    MD0100PA00X+113457Y+085722X0190Y         S0      
317GND              VIA   -    MD0100PA00X+114002Y+086392X0190Y    R180 S0      
317GND              VIA   -    MD0100PA00X+113457Y+078360X0190Y         S0      
317GND              VIA   -    MD0100PA00X+114002Y+079030X0190Y    R180 S0      
317GND              VIA   -    MD0100PA00X+113457Y+080703X0190Y         S0      
317GND              VIA   -    MD0100PA00X+114002Y+080034X0190Y    R180 S0      
317GND              VIA   -    MD0100PA00X+113017Y+079532X0190Y         S0      
317GND              VIA   -    MD0100PA00X+113457Y+082041X0190Y         S0      
317GND              VIA   -    MD0100PA00X+113457Y+081372X0190Y         S0      
317GND              VIA   -    MD0100PA00X+113457Y+077691X0190Y         S0      
317GND              VIA   -    MD0100PA00X+112101Y+120860X0190Y         S0      
317GND              VIA   -    MD0100PA00X+111661Y+119689X0190Y         S0      
317GND              VIA   -    MD0100PA00X+111556Y+120191X0190Y         S0      
317GND              VIA   -    MD0100PA00X+112101Y+122199X0190Y         S0      
317GND              VIA   -    MD0100PA00X+112101Y+121530X0190Y         S0      
317GND              VIA   -    MD0100PA00X+111661Y+123370X0190Y         S0      
317GND              VIA   -    MD0100PA00X+111556Y+122868X0190Y         S0      
317GND              VIA   -    MD0100PA00X+111556Y+123872X0190Y         S0      
317GND              VIA   -    MD0100PA00X+112101Y+125211X0190Y         S0      
317GND              VIA   -    MD0100PA00X+112101Y+124541X0190Y         S0      
317GND              VIA   -    MD0100PA00X+111661Y+116008X0190Y         S0      
317GND              VIA   -    MD0100PA00X+111556Y+116510X0190Y         S0      
317GND              VIA   -    MD0100PA00X+111556Y+115506X0190Y         S0      
317GND              VIA   -    MD0100PA00X+112101Y+117848X0190Y         S0      
317GND              VIA   -    MD0100PA00X+112101Y+117179X0190Y         S0      
317GND              VIA   -    MD0100PA00X+112101Y+118518X0190Y         S0      
317GND              VIA   -    MD0100PA00X+111556Y+119187X0190Y         S0      
317GND              VIA   -    MD0100PA00X+112101Y+111156X0190Y         S0      
317GND              VIA   -    MD0100PA00X+111556Y+111825X0190Y         S0      
317GND              VIA   -    MD0100PA00X+111556Y+112829X0190Y         S0      
317GND              VIA   -    MD0100PA00X+111661Y+112327X0190Y         S0      
317GND              VIA   -    MD0100PA00X+112101Y+113498X0190Y         S0      
317GND              VIA   -    MD0100PA00X+112101Y+114837X0190Y         S0      
317GND              VIA   -    MD0100PA00X+112101Y+114167X0190Y         S0      
317GND              VIA   -    MD0100PA00X+112101Y+106805X0190Y         S0      
317GND              VIA   -    MD0100PA00X+112101Y+107474X0190Y         S0      
317GND              VIA   -    MD0100PA00X+111556Y+108144X0190Y         S0      
317GND              VIA   -    MD0100PA00X+111661Y+108646X0190Y         S0      
317GND              VIA   -    MD0100PA00X+112101Y+110486X0190Y         S0      
317GND              VIA   -    MD0100PA00X+112101Y+109817X0190Y         S0      
317GND              VIA   -    MD0100PA00X+111556Y+109148X0190Y         S0      
317GND              VIA   -    MD0100PA00X+112101Y+099778X0190Y         S0      
317GND              VIA   -    MD0100PA00X+112101Y+099108X0190Y         S0      
317GND              VIA   -    MD0100PA00X+112101Y+100447X0190Y         S0      
317GND              VIA   -    MD0100PA00X+112101Y+104463X0190Y         S0      
317GND              VIA   -    MD0100PA00X+112101Y+103793X0190Y         S0      
317GND              VIA   -    MD0100PA00X+112101Y+103124X0190Y         S0      
317GND              VIA   -    MD0100PA00X+112101Y+105801X0190Y         S0      
317GND              VIA   -    MD0100PA00X+112101Y+105132X0190Y         S0      
317GND              VIA   -    MD0100PA00X+112101Y+095092X0190Y         S0      
317GND              VIA   -    MD0100PA00X+111556Y+094423X0190Y         S0      
317GND              VIA   -    MD0100PA00X+112101Y+095762X0190Y         S0      
317GND              VIA   -    MD0100PA00X+112101Y+097100X0190Y         S0      
317GND              VIA   -    MD0100PA00X+112101Y+096431X0190Y         S0      
317GND              VIA   -    MD0100PA00X+112101Y+098439X0190Y         S0      
317GND              VIA   -    MD0100PA00X+112101Y+097770X0190Y         S0      
317GND              VIA   -    MD0100PA00X+111661Y+090240X0190Y         S0      
317GND              VIA   -    MD0100PA00X+111556Y+089738X0190Y         S0      
317GND              VIA   -    MD0100PA00X+111556Y+090742X0190Y         S0      
317GND              VIA   -    MD0100PA00X+112101Y+092081X0190Y         S0      
317GND              VIA   -    MD0100PA00X+112101Y+091411X0190Y         S0      
317GND              VIA   -    MD0100PA00X+111661Y+093921X0190Y         S0      
317GND              VIA   -    MD0100PA00X+112101Y+092750X0190Y         S0      
317GND              VIA   -    MD0100PA00X+111556Y+093419X0190Y         S0      
317GND              VIA   -    MD0100PA00X+112101Y+084049X0190Y         S0      
317GND              VIA   -    MD0100PA00X+111661Y+086559X0190Y         S0      
317GND              VIA   -    MD0100PA00X+111556Y+086057X0190Y         S0      
317GND              VIA   -    MD0100PA00X+112101Y+085388X0190Y         S0      
317GND              VIA   -    MD0100PA00X+112101Y+087730X0190Y         S0      
317GND              VIA   -    MD0100PA00X+111556Y+087061X0190Y         S0      
317GND              VIA   -    MD0100PA00X+112101Y+089069X0190Y         S0      
317GND              VIA   -    MD0100PA00X+112101Y+088400X0190Y         S0      
317GND              VIA   -    MD0100PA00X+111556Y+079699X0190Y         S0      
317GND              VIA   -    MD0100PA00X+112101Y+080368X0190Y         S0      
317GND              VIA   -    MD0100PA00X+112101Y+081707X0190Y         S0      
317GND              VIA   -    MD0100PA00X+112101Y+081037X0190Y         S0      
317GND              VIA   -    MD0100PA00X+111661Y+082878X0190Y         S0      
317GND              VIA   -    MD0100PA00X+111556Y+083380X0190Y         S0      
317GND              VIA   -    MD0100PA00X+111556Y+082376X0190Y         S0      
317GND              VIA   -    MD0100PA00X+112101Y+084718X0190Y         S0      
317GND              VIA   -    MD0100PA00X+111556Y+078695X0190Y         S0      
317GND              VIA   -    MD0100PA00X+112101Y+078026X0190Y         S0      
317GND              VIA   -    MD0100PA00X+111661Y+079197X0190Y         S0      
317GND              VIA   -    MD0100PA00X+110487Y+121864X0190Y         S0      
317GND              VIA   -    MD0100PA00X+110487Y+121195X0190Y         S0      
317GND              VIA   -    MD0100PA00X+110487Y+122534X0190Y         S0      
317GND              VIA   -    MD0100PA00X+111032Y+123203X0190Y    R180 S0      
317GND              VIA   -    MD0100PA00X+110047Y+123705X0190Y         S0      
317GND              VIA   -    MD0100PA00X+111032Y+124207X0190Y    R180 S0      
317GND              VIA   -    MD0100PA00X+110487Y+124876X0190Y         S0      
317GND              VIA   -    MD0100PA00X+110487Y+125545X0190Y         S0      
317GND              VIA   -    MD0100PA00X+110487Y+117514X0190Y         S0      
317GND              VIA   -    MD0100PA00X+111032Y+116844X0190Y    R180 S0      
317GND              VIA   -    MD0100PA00X+110487Y+118183X0190Y         S0      
317GND              VIA   -    MD0100PA00X+110487Y+118852X0190Y         S0      
317GND              VIA   -    MD0100PA00X+110047Y+120024X0190Y         S0      
317GND              VIA   -    MD0100PA00X+111032Y+119522X0190Y    R180 S0      
317GND              VIA   -    MD0100PA00X+111032Y+120526X0190Y    R180 S0      
317GND              VIA   -    MD0100PA00X+110047Y+112662X0190Y         S0      
317GND              VIA   -    MD0100PA00X+111032Y+112160X0190Y    R180 S0      
317GND              VIA   -    MD0100PA00X+111032Y+113163X0190Y    R180 S0      
317GND              VIA   -    MD0100PA00X+110487Y+114502X0190Y         S0      
317GND              VIA   -    MD0100PA00X+110487Y+113833X0190Y         S0      
317GND              VIA   -    MD0100PA00X+110047Y+116343X0190Y         S0      
317GND              VIA   -    MD0100PA00X+110487Y+115171X0190Y         S0      
317GND              VIA   -    MD0100PA00X+111032Y+115841X0190Y    R180 S0      
317GND              VIA   -    MD0100PA00X+110487Y+106136X0190Y         S0      
317GND              VIA   -    MD0100PA00X+110047Y+108980X0190Y         S0      
317GND              VIA   -    MD0100PA00X+111032Y+108478X0190Y    R180 S0      
317GND              VIA   -    MD0100PA00X+110487Y+107809X0190Y         S0      
317GND              VIA   -    MD0100PA00X+110487Y+110152X0190Y         S0      
317GND              VIA   -    MD0100PA00X+111032Y+109482X0190Y    R180 S0      
317GND              VIA   -    MD0100PA00X+110487Y+111490X0190Y         S0      
317GND              VIA   -    MD0100PA00X+110487Y+110821X0190Y         S0      
317GND              VIA   -    MD0100PA00X+110487Y+099443X0190Y         S0      
317GND              VIA   -    MD0100PA00X+110487Y+098774X0190Y         S0      
317GND              VIA   -    MD0100PA00X+110487Y+100447X0190Y         S0      
317GND              VIA   -    MD0100PA00X+110487Y+104128X0190Y         S0      
317GND              VIA   -    MD0100PA00X+110487Y+103459X0190Y         S0      
317GND              VIA   -    MD0100PA00X+110487Y+105467X0190Y         S0      
317GND              VIA   -    MD0100PA00X+110487Y+104797X0190Y         S0      
317GND              VIA   -    MD0100PA00X+110487Y+107140X0190Y         S0      
317GND              VIA   -    MD0100PA00X+110487Y+095427X0190Y         S0      
317GND              VIA   -    MD0100PA00X+110047Y+094256X0190Y         S0      
317GND              VIA   -    MD0100PA00X+111032Y+094758X0190Y    R180 S0      
317GND              VIA   -    MD0100PA00X+110487Y+096096X0190Y         S0      
317GND              VIA   -    MD0100PA00X+110487Y+096766X0190Y         S0      
317GND              VIA   -    MD0100PA00X+110487Y+098104X0190Y         S0      
317GND              VIA   -    MD0100PA00X+110487Y+097435X0190Y         S0      
317GND              VIA   -    MD0100PA00X+111032Y+090073X0190Y    R180 S0      
317GND              VIA   -    MD0100PA00X+110047Y+090575X0190Y         S0      
317GND              VIA   -    MD0100PA00X+111032Y+091077X0190Y    R180 S0      
317GND              VIA   -    MD0100PA00X+110487Y+092415X0190Y         S0      
317GND              VIA   -    MD0100PA00X+110487Y+091746X0190Y         S0      
317GND              VIA   -    MD0100PA00X+111032Y+093754X0190Y    R180 S0      
317GND              VIA   -    MD0100PA00X+110487Y+093085X0190Y         S0      
317GND              VIA   -    MD0100PA00X+111032Y+086392X0190Y    R180 S0      
317GND              VIA   -    MD0100PA00X+110487Y+085722X0190Y         S0      
317GND              VIA   -    MD0100PA00X+110487Y+088065X0190Y         S0      
317GND              VIA   -    MD0100PA00X+111032Y+087396X0190Y    R180 S0      
317GND              VIA   -    MD0100PA00X+110047Y+086894X0190Y         S0      
317GND              VIA   -    MD0100PA00X+110487Y+089404X0190Y         S0      
317GND              VIA   -    MD0100PA00X+110487Y+088734X0190Y         S0      
317GND              VIA   -    MD0100PA00X+110487Y+082041X0190Y         S0      
317GND              VIA   -    MD0100PA00X+110487Y+081372X0190Y         S0      
317GND              VIA   -    MD0100PA00X+110047Y+083213X0190Y         S0      
317GND              VIA   -    MD0100PA00X+111032Y+083715X0190Y    R180 S0      
317GND              VIA   -    MD0100PA00X+111032Y+082711X0190Y    R180 S0      
317GND              VIA   -    MD0100PA00X+110487Y+084384X0190Y         S0      
317GND              VIA   -    MD0100PA00X+110487Y+085053X0190Y         S0      
317GND              VIA   -    MD0100PA00X+110487Y+077691X0190Y         S0      
317GND              VIA   -    MD0100PA00X+111032Y+079030X0190Y    R180 S0      
317GND              VIA   -    MD0100PA00X+110487Y+078360X0190Y         S0      
317GND              VIA   -    MD0100PA00X+110487Y+080703X0190Y         S0      
317GND              VIA   -    MD0100PA00X+110047Y+079532X0190Y         S0      
317GND              VIA   -    MD0100PA00X+111032Y+080034X0190Y    R180 S0      
317GND              VIA   -    MD0100PA00X+109131Y+125211X0190Y         S0      
317GND              VIA   -    MD0100PA00X+109131Y+124541X0190Y         S0      
317GND              VIA   -    MD0100PA00X+109131Y+118518X0190Y         S0      
317GND              VIA   -    MD0100PA00X+108586Y+119187X0190Y         S0      
317GND              VIA   -    MD0100PA00X+109131Y+120860X0190Y         S0      
317GND              VIA   -    MD0100PA00X+108691Y+119689X0190Y         S0      
317GND              VIA   -    MD0100PA00X+108586Y+120191X0190Y         S0      
317GND              VIA   -    MD0100PA00X+109131Y+122199X0190Y         S0      
317GND              VIA   -    MD0100PA00X+109131Y+121530X0190Y         S0      
317GND              VIA   -    MD0100PA00X+108691Y+123370X0190Y         S0      
317GND              VIA   -    MD0100PA00X+108586Y+122868X0190Y         S0      
317GND              VIA   -    MD0100PA00X+108586Y+123872X0190Y         S0      
317GND              VIA   -    MD0100PA00X+109131Y+114837X0190Y         S0      
317GND              VIA   -    MD0100PA00X+109131Y+114167X0190Y         S0      
317GND              VIA   -    MD0100PA00X+108691Y+116008X0190Y         S0      
317GND              VIA   -    MD0100PA00X+108586Y+116510X0190Y         S0      
317GND              VIA   -    MD0100PA00X+108586Y+115506X0190Y         S0      
317GND              VIA   -    MD0100PA00X+109131Y+117848X0190Y         S0      
317GND              VIA   -    MD0100PA00X+109131Y+117179X0190Y         S0      
317GND              VIA   -    MD0100PA00X+108586Y+108144X0190Y         S0      
317GND              VIA   -    MD0100PA00X+108691Y+108646X0190Y         S0      
317GND              VIA   -    MD0100PA00X+109131Y+110486X0190Y         S0      
317GND              VIA   -    MD0100PA00X+109131Y+109817X0190Y         S0      
317GND              VIA   -    MD0100PA00X+108586Y+109148X0190Y         S0      
317GND              VIA   -    MD0100PA00X+109131Y+111156X0190Y         S0      
317GND              VIA   -    MD0100PA00X+108586Y+111825X0190Y         S0      
317GND              VIA   -    MD0100PA00X+108586Y+112829X0190Y         S0      
317GND              VIA   -    MD0100PA00X+108691Y+112327X0190Y         S0      
317GND              VIA   -    MD0100PA00X+109131Y+113498X0190Y         S0      
317GND              VIA   -    MD0100PA00X+109131Y+104463X0190Y         S0      
317GND              VIA   -    MD0100PA00X+109131Y+103793X0190Y         S0      
317GND              VIA   -    MD0100PA00X+109131Y+103124X0190Y         S0      
317GND              VIA   -    MD0100PA00X+109131Y+105801X0190Y         S0      
317GND              VIA   -    MD0100PA00X+109131Y+105132X0190Y         S0      
317GND              VIA   -    MD0100PA00X+109131Y+106805X0190Y         S0      
317GND              VIA   -    MD0100PA00X+109131Y+107474X0190Y         S0      
317GND              VIA   -    MD0100PA00X+109131Y+095762X0190Y         S0      
317GND              VIA   -    MD0100PA00X+109131Y+097100X0190Y         S0      
317GND              VIA   -    MD0100PA00X+109131Y+096431X0190Y         S0      
317GND              VIA   -    MD0100PA00X+109131Y+098439X0190Y         S0      
317GND              VIA   -    MD0100PA00X+109131Y+097770X0190Y         S0      
317GND              VIA   -    MD0100PA00X+109131Y+099778X0190Y         S0      
317GND              VIA   -    MD0100PA00X+109131Y+099108X0190Y         S0      
317GND              VIA   -    MD0100PA00X+109131Y+100447X0190Y         S0      
317GND              VIA   -    MD0100PA00X+108691Y+090240X0190Y         S0      
317GND              VIA   -    MD0100PA00X+108586Y+089738X0190Y         S0      
317GND              VIA   -    MD0100PA00X+108586Y+090742X0190Y         S0      
317GND              VIA   -    MD0100PA00X+109131Y+092081X0190Y         S0      
317GND              VIA   -    MD0100PA00X+109131Y+091411X0190Y         S0      
317GND              VIA   -    MD0100PA00X+108691Y+093921X0190Y         S0      
317GND              VIA   -    MD0100PA00X+109131Y+092750X0190Y         S0      
317GND              VIA   -    MD0100PA00X+108586Y+093419X0190Y         S0      
317GND              VIA   -    MD0100PA00X+109131Y+095092X0190Y         S0      
317GND              VIA   -    MD0100PA00X+108586Y+094423X0190Y         S0      
317GND              VIA   -    MD0100PA00X+108691Y+086559X0190Y         S0      
317GND              VIA   -    MD0100PA00X+108586Y+086057X0190Y         S0      
317GND              VIA   -    MD0100PA00X+109131Y+085388X0190Y         S0      
317GND              VIA   -    MD0100PA00X+109131Y+087730X0190Y         S0      
317GND              VIA   -    MD0100PA00X+108586Y+087061X0190Y         S0      
317GND              VIA   -    MD0100PA00X+109131Y+089069X0190Y         S0      
317GND              VIA   -    MD0100PA00X+109131Y+088400X0190Y         S0      
317GND              VIA   -    MD0100PA00X+108586Y+079699X0190Y         S0      
317GND              VIA   -    MD0100PA00X+109131Y+080368X0190Y         S0      
317GND              VIA   -    MD0100PA00X+109131Y+081707X0190Y         S0      
317GND              VIA   -    MD0100PA00X+109131Y+081037X0190Y         S0      
317GND              VIA   -    MD0100PA00X+108691Y+082878X0190Y         S0      
317GND              VIA   -    MD0100PA00X+108586Y+083380X0190Y         S0      
317GND              VIA   -    MD0100PA00X+108586Y+082376X0190Y         S0      
317GND              VIA   -    MD0100PA00X+109131Y+084718X0190Y         S0      
317GND              VIA   -    MD0100PA00X+109131Y+084049X0190Y         S0      
317GND              VIA   -    MD0100PA00X+108586Y+078695X0190Y         S0      
317GND              VIA   -    MD0100PA00X+109131Y+078026X0190Y         S0      
317GND              VIA   -    MD0100PA00X+108691Y+079197X0190Y         S0      
317GND              VIA   -    MD0100PA00X+107517Y+121864X0190Y         S0      
317GND              VIA   -    MD0100PA00X+107517Y+121195X0190Y         S0      
317GND              VIA   -    MD0100PA00X+107517Y+122534X0190Y         S0      
317GND              VIA   -    MD0100PA00X+108062Y+123203X0190Y    R180 S0      
317GND              VIA   -    MD0100PA00X+107077Y+123705X0190Y         S0      
317GND              VIA   -    MD0100PA00X+108062Y+124207X0190Y    R180 S0      
317GND              VIA   -    MD0100PA00X+107517Y+124876X0190Y         S0      
317GND              VIA   -    MD0100PA00X+107517Y+125545X0190Y         S0      
317GND              VIA   -    MD0100PA00X+107077Y+116343X0190Y         S0      
317GND              VIA   -    MD0100PA00X+107517Y+115171X0190Y         S0      
317GND              VIA   -    MD0100PA00X+108062Y+115841X0190Y    R180 S0      
317GND              VIA   -    MD0100PA00X+107517Y+117514X0190Y         S0      
317GND              VIA   -    MD0100PA00X+108062Y+116844X0190Y    R180 S0      
317GND              VIA   -    MD0100PA00X+107517Y+118183X0190Y         S0      
317GND              VIA   -    MD0100PA00X+107517Y+118852X0190Y         S0      
317GND              VIA   -    MD0100PA00X+108062Y+119522X0190Y    R180 S0      
317GND              VIA   -    MD0100PA00X+107077Y+120024X0190Y         S0      
317GND              VIA   -    MD0100PA00X+108062Y+120526X0190Y    R180 S0      
317GND              VIA   -    MD0100PA00X+107517Y+111490X0190Y         S0      
317GND              VIA   -    MD0100PA00X+107517Y+110821X0190Y         S0      
317GND              VIA   -    MD0100PA00X+107077Y+112662X0190Y         S0      
317GND              VIA   -    MD0100PA00X+108062Y+112160X0190Y    R180 S0      
317GND              VIA   -    MD0100PA00X+108062Y+113163X0190Y    R180 S0      
317GND              VIA   -    MD0100PA00X+107517Y+114502X0190Y         S0      
317GND              VIA   -    MD0100PA00X+107517Y+113833X0190Y         S0      
317GND              VIA   -    MD0100PA00X+107517Y+105467X0190Y         S0      
317GND              VIA   -    MD0100PA00X+107517Y+104797X0190Y         S0      
317GND              VIA   -    MD0100PA00X+107517Y+107140X0190Y         S0      
317GND              VIA   -    MD0100PA00X+107517Y+106136X0190Y         S0      
317GND              VIA   -    MD0100PA00X+108062Y+108478X0190Y    R180 S0      
317GND              VIA   -    MD0100PA00X+107077Y+108980X0190Y         S0      
317GND              VIA   -    MD0100PA00X+107517Y+107809X0190Y         S0      
317GND              VIA   -    MD0100PA00X+107517Y+110152X0190Y         S0      
317GND              VIA   -    MD0100PA00X+108062Y+109482X0190Y    R180 S0      
317GND              VIA   -    MD0100PA00X+107517Y+098104X0190Y         S0      
317GND              VIA   -    MD0100PA00X+107517Y+097435X0190Y         S0      
317GND              VIA   -    MD0100PA00X+107517Y+099443X0190Y         S0      
317GND              VIA   -    MD0100PA00X+107517Y+098774X0190Y         S0      
317GND              VIA   -    MD0100PA00X+107517Y+100447X0190Y         S0      
317GND              VIA   -    MD0100PA00X+107517Y+104128X0190Y         S0      
317GND              VIA   -    MD0100PA00X+107517Y+103459X0190Y         S0      
317GND              VIA   -    MD0100PA00X+108062Y+093754X0190Y    R180 S0      
317GND              VIA   -    MD0100PA00X+107517Y+093085X0190Y         S0      
317GND              VIA   -    MD0100PA00X+107517Y+095427X0190Y         S0      
317GND              VIA   -    MD0100PA00X+108062Y+094758X0190Y    R180 S0      
317GND              VIA   -    MD0100PA00X+107077Y+094256X0190Y         S0      
317GND              VIA   -    MD0100PA00X+107517Y+096096X0190Y         S0      
317GND              VIA   -    MD0100PA00X+107517Y+096766X0190Y         S0      
317GND              VIA   -    MD0100PA00X+107517Y+088065X0190Y         S0      
317GND              VIA   -    MD0100PA00X+108062Y+087396X0190Y    R180 S0      
317GND              VIA   -    MD0100PA00X+107077Y+086894X0190Y         S0      
317GND              VIA   -    MD0100PA00X+107517Y+089404X0190Y         S0      
317GND              VIA   -    MD0100PA00X+107517Y+088734X0190Y         S0      
317GND              VIA   -    MD0100PA00X+108062Y+090073X0190Y    R180 S0      
317GND              VIA   -    MD0100PA00X+107077Y+090575X0190Y         S0      
317GND              VIA   -    MD0100PA00X+108062Y+091077X0190Y    R180 S0      
317GND              VIA   -    MD0100PA00X+107517Y+092415X0190Y         S0      
317GND              VIA   -    MD0100PA00X+107517Y+091746X0190Y         S0      
317GND              VIA   -    MD0100PA00X+108062Y+083715X0190Y    R180 S0      
317GND              VIA   -    MD0100PA00X+108062Y+082711X0190Y    R180 S0      
317GND              VIA   -    MD0100PA00X+107077Y+083213X0190Y         S0      
317GND              VIA   -    MD0100PA00X+107517Y+084384X0190Y         S0      
317GND              VIA   -    MD0100PA00X+107517Y+085053X0190Y         S0      
317GND              VIA   -    MD0100PA00X+107517Y+085722X0190Y         S0      
317GND              VIA   -    MD0100PA00X+108062Y+086392X0190Y    R180 S0      
317GND              VIA   -    MD0100PA00X+107517Y+077691X0190Y         S0      
317GND              VIA   -    MD0100PA00X+107517Y+078360X0190Y         S0      
317GND              VIA   -    MD0100PA00X+108062Y+079030X0190Y    R180 S0      
317GND              VIA   -    MD0100PA00X+107517Y+080703X0190Y         S0      
317GND              VIA   -    MD0100PA00X+108062Y+080034X0190Y    R180 S0      
317GND              VIA   -    MD0100PA00X+107077Y+079532X0190Y         S0      
317GND              VIA   -    MD0100PA00X+107517Y+082041X0190Y         S0      
317GND              VIA   -    MD0100PA00X+107517Y+081372X0190Y         S0      
317GND              VIA   -    MD0100PA00X+106161Y+120860X0190Y         S0      
317GND              VIA   -    MD0100PA00X+105721Y+119689X0190Y         S0      
317GND              VIA   -    MD0100PA00X+105616Y+120191X0190Y         S0      
317GND              VIA   -    MD0100PA00X+106161Y+122199X0190Y         S0      
317GND              VIA   -    MD0100PA00X+106161Y+121530X0190Y         S0      
317GND              VIA   -    MD0100PA00X+105616Y+122868X0190Y         S0      
317GND              VIA   -    MD0100PA00X+105721Y+123370X0190Y         S0      
317GND              VIA   -    MD0100PA00X+105616Y+123872X0190Y         S0      
317GND              VIA   -    MD0100PA00X+106161Y+125211X0190Y         S0      
317GND              VIA   -    MD0100PA00X+106161Y+124541X0190Y         S0      
317GND              VIA   -    MD0100PA00X+106161Y+114837X0190Y         S0      
317GND              VIA   -    MD0100PA00X+106161Y+114167X0190Y         S0      
317GND              VIA   -    MD0100PA00X+105721Y+116008X0190Y         S0      
317GND              VIA   -    MD0100PA00X+105616Y+116510X0190Y         S0      
317GND              VIA   -    MD0100PA00X+105616Y+115506X0190Y         S0      
317GND              VIA   -    MD0100PA00X+106161Y+117848X0190Y         S0      
317GND              VIA   -    MD0100PA00X+106161Y+117179X0190Y         S0      
317GND              VIA   -    MD0100PA00X+106161Y+118518X0190Y         S0      
317GND              VIA   -    MD0100PA00X+105616Y+119187X0190Y         S0      
317GND              VIA   -    MD0100PA00X+105616Y+108144X0190Y         S0      
317GND              VIA   -    MD0100PA00X+105721Y+108646X0190Y         S0      
317GND              VIA   -    MD0100PA00X+106161Y+110486X0190Y         S0      
317GND              VIA   -    MD0100PA00X+106161Y+109817X0190Y         S0      
317GND              VIA   -    MD0100PA00X+105616Y+109148X0190Y         S0      
317GND              VIA   -    MD0100PA00X+106161Y+111156X0190Y         S0      
317GND              VIA   -    MD0100PA00X+105616Y+111825X0190Y         S0      
317GND              VIA   -    MD0100PA00X+105616Y+112829X0190Y         S0      
317GND              VIA   -    MD0100PA00X+105721Y+112327X0190Y         S0      
317GND              VIA   -    MD0100PA00X+106161Y+113498X0190Y         S0      
317GND              VIA   -    MD0100PA00X+106161Y+103124X0190Y         S0      
317GND              VIA   -    MD0100PA00X+106161Y+104463X0190Y         S0      
317GND              VIA   -    MD0100PA00X+106161Y+103793X0190Y         S0      
317GND              VIA   -    MD0100PA00X+106161Y+105801X0190Y         S0      
317GND              VIA   -    MD0100PA00X+106161Y+105132X0190Y         S0      
317GND              VIA   -    MD0100PA00X+106161Y+106805X0190Y         S0      
317GND              VIA   -    MD0100PA00X+106161Y+107474X0190Y         S0      
317GND              VIA   -    MD0100PA00X+105616Y+094423X0190Y         S0      
317GND              VIA   -    MD0100PA00X+106161Y+095092X0190Y         S0      
317GND              VIA   -    MD0100PA00X+106161Y+095762X0190Y         S0      
317GND              VIA   -    MD0100PA00X+106161Y+097100X0190Y         S0      
317GND              VIA   -    MD0100PA00X+106161Y+096431X0190Y         S0      
317GND              VIA   -    MD0100PA00X+106161Y+098439X0190Y         S0      
317GND              VIA   -    MD0100PA00X+106161Y+097770X0190Y         S0      
317GND              VIA   -    MD0100PA00X+106161Y+099778X0190Y         S0      
317GND              VIA   -    MD0100PA00X+106161Y+099108X0190Y         S0      
317GND              VIA   -    MD0100PA00X+106161Y+100447X0190Y         S0      
317GND              VIA   -    MD0100PA00X+105721Y+090240X0190Y         S0      
317GND              VIA   -    MD0100PA00X+105616Y+089738X0190Y         S0      
317GND              VIA   -    MD0100PA00X+105616Y+090742X0190Y         S0      
317GND              VIA   -    MD0100PA00X+106161Y+092081X0190Y         S0      
317GND              VIA   -    MD0100PA00X+106161Y+091411X0190Y         S0      
317GND              VIA   -    MD0100PA00X+105721Y+093921X0190Y         S0      
317GND              VIA   -    MD0100PA00X+105616Y+093419X0190Y         S0      
317GND              VIA   -    MD0100PA00X+106161Y+092750X0190Y         S0      
317GND              VIA   -    MD0100PA00X+106161Y+084049X0190Y         S0      
317GND              VIA   -    MD0100PA00X+106161Y+084718X0190Y         S0      
317GND              VIA   -    MD0100PA00X+105721Y+086559X0190Y         S0      
317GND              VIA   -    MD0100PA00X+105616Y+086057X0190Y         S0      
317GND              VIA   -    MD0100PA00X+106161Y+085388X0190Y         S0      
317GND              VIA   -    MD0100PA00X+106161Y+087730X0190Y         S0      
317GND              VIA   -    MD0100PA00X+105616Y+087061X0190Y         S0      
317GND              VIA   -    MD0100PA00X+106161Y+089069X0190Y         S0      
317GND              VIA   -    MD0100PA00X+106161Y+088400X0190Y         S0      
317GND              VIA   -    MD0100PA00X+106161Y+078026X0190Y         S0      
317GND              VIA   -    MD0100PA00X+105616Y+078695X0190Y         S0      
317GND              VIA   -    MD0100PA00X+105721Y+079197X0190Y         S0      
317GND              VIA   -    MD0100PA00X+105616Y+079699X0190Y         S0      
317GND              VIA   -    MD0100PA00X+106161Y+080368X0190Y         S0      
317GND              VIA   -    MD0100PA00X+106161Y+081707X0190Y         S0      
317GND              VIA   -    MD0100PA00X+106161Y+081037X0190Y         S0      
317GND              VIA   -    MD0100PA00X+105721Y+082878X0190Y         S0      
317GND              VIA   -    MD0100PA00X+105616Y+083380X0190Y         S0      
317GND              VIA   -    MD0100PA00X+105616Y+082376X0190Y         S0      
317GND              VIA   -    MD0100PA00X+105092Y+123203X0190Y    R180 S0      
317GND              VIA   -    MD0100PA00X+104546Y+122534X0190Y         S0      
317GND              VIA   -    MD0100PA00X+104106Y+123705X0190Y         S0      
317GND              VIA   -    MD0100PA00X+105092Y+124207X0190Y    R180 S0      
317GND              VIA   -    MD0100PA00X+104546Y+124876X0190Y         S0      
317GND              VIA   -    MD0100PA00X+104546Y+125545X0190Y         S0      
317GND              VIA   -    MD0100PA00X+104546Y+114502X0190Y         S0      
317GND              VIA   -    MD0100PA00X+104546Y+113833X0190Y         S0      
317GND              VIA   -    MD0100PA00X+104106Y+116343X0190Y         S0      
317GND              VIA   -    MD0100PA00X+104546Y+115171X0190Y         S0      
317GND              VIA   -    MD0100PA00X+105092Y+115841X0190Y    R180 S0      
317GND              VIA   -    MD0100PA00X+104546Y+117514X0190Y         S0      
317GND              VIA   -    MD0100PA00X+105092Y+116844X0190Y    R180 S0      
317GND              VIA   -    MD0100PA00X+104546Y+118183X0190Y         S0      
317GND              VIA   -    MD0100PA00X+104546Y+118852X0190Y         S0      
317GND              VIA   -    MD0100PA00X+105092Y+119522X0190Y    R180 S0      
317GND              VIA   -    MD0100PA00X+105092Y+120526X0190Y    R180 S0      
317GND              VIA   -    MD0100PA00X+104106Y+120024X0190Y         S0      
317GND              VIA   -    MD0100PA00X+104546Y+121864X0190Y         S0      
317GND              VIA   -    MD0100PA00X+104546Y+121195X0190Y         S0      
317GND              VIA   -    MD0100PA00X+104546Y+103459X0190Y         S0      
317GND              VIA   -    MD0100PA00X+104546Y+105467X0190Y         S0      
317GND              VIA   -    MD0100PA00X+104546Y+104797X0190Y         S0      
317GND              VIA   -    MD0100PA00X+104546Y+107140X0190Y         S0      
317GND              VIA   -    MD0100PA00X+104546Y+106136X0190Y         S0      
317GND              VIA   -    MD0100PA00X+104106Y+108980X0190Y         S0      
317GND              VIA   -    MD0100PA00X+105092Y+108478X0190Y    R180 S0      
317GND              VIA   -    MD0100PA00X+104546Y+107809X0190Y         S0      
317GND              VIA   -    MD0100PA00X+104546Y+110152X0190Y         S0      
317GND              VIA   -    MD0100PA00X+105092Y+109482X0190Y    R180 S0      
317GND              VIA   -    MD0100PA00X+104546Y+111490X0190Y         S0      
317GND              VIA   -    MD0100PA00X+104546Y+110821X0190Y         S0      
317GND              VIA   -    MD0100PA00X+104106Y+112662X0190Y         S0      
317GND              VIA   -    MD0100PA00X+105092Y+112160X0190Y    R180 S0      
317GND              VIA   -    MD0100PA00X+105092Y+113163X0190Y    R180 S0      
317GND              VIA   -    MD0100PA00X+105092Y+093754X0190Y    R180 S0      
317GND              VIA   -    MD0100PA00X+104546Y+093085X0190Y         S0      
317GND              VIA   -    MD0100PA00X+104546Y+095427X0190Y         S0      
317GND              VIA   -    MD0100PA00X+104106Y+094256X0190Y         S0      
317GND              VIA   -    MD0100PA00X+105092Y+094758X0190Y    R180 S0      
317GND              VIA   -    MD0100PA00X+104546Y+096096X0190Y         S0      
317GND              VIA   -    MD0100PA00X+104546Y+096766X0190Y         S0      
317GND              VIA   -    MD0100PA00X+104546Y+098104X0190Y         S0      
317GND              VIA   -    MD0100PA00X+104546Y+097435X0190Y         S0      
317GND              VIA   -    MD0100PA00X+104546Y+099443X0190Y         S0      
317GND              VIA   -    MD0100PA00X+104546Y+098774X0190Y         S0      
317GND              VIA   -    MD0100PA00X+104546Y+100447X0190Y         S0      
317GND              VIA   -    MD0100PA00X+104546Y+104128X0190Y         S0      
317GND              VIA   -    MD0100PA00X+104546Y+084384X0190Y         S0      
317GND              VIA   -    MD0100PA00X+104546Y+085053X0190Y         S0      
317GND              VIA   -    MD0100PA00X+104546Y+085722X0190Y         S0      
317GND              VIA   -    MD0100PA00X+105092Y+086392X0190Y    R180 S0      
317GND              VIA   -    MD0100PA00X+104546Y+088065X0190Y         S0      
317GND              VIA   -    MD0100PA00X+105092Y+087396X0190Y    R180 S0      
317GND              VIA   -    MD0100PA00X+104106Y+086894X0190Y         S0      
317GND              VIA   -    MD0100PA00X+104546Y+089404X0190Y         S0      
317GND              VIA   -    MD0100PA00X+104546Y+088734X0190Y         S0      
317GND              VIA   -    MD0100PA00X+105092Y+090073X0190Y    R180 S0      
317GND              VIA   -    MD0100PA00X+104106Y+090575X0190Y         S0      
317GND              VIA   -    MD0100PA00X+105092Y+091077X0190Y    R180 S0      
317GND              VIA   -    MD0100PA00X+104546Y+092415X0190Y         S0      
317GND              VIA   -    MD0100PA00X+104546Y+091746X0190Y         S0      
317GND              VIA   -    MD0100PA00X+104546Y+077691X0190Y         S0      
317GND              VIA   -    MD0100PA00X+104546Y+078360X0190Y         S0      
317GND              VIA   -    MD0100PA00X+105092Y+079030X0190Y    R180 S0      
317GND              VIA   -    MD0100PA00X+104546Y+080703X0190Y         S0      
317GND              VIA   -    MD0100PA00X+104106Y+079532X0190Y         S0      
317GND              VIA   -    MD0100PA00X+105092Y+080034X0190Y    R180 S0      
317GND              VIA   -    MD0100PA00X+104546Y+082041X0190Y         S0      
317GND              VIA   -    MD0100PA00X+104546Y+081372X0190Y         S0      
317GND              VIA   -    MD0100PA00X+104106Y+083213X0190Y         S0      
317GND              VIA   -    MD0100PA00X+105092Y+083715X0190Y    R180 S0      
317GND              VIA   -    MD0100PA00X+105092Y+082711X0190Y    R180 S0      
317GND              VIA   -    MD0100PA00X+106161Y+077356X0190Y         S0      
327GND              J23   -6          A01X+106161Y+077356X0205Y0590R090 S1      
317GND              VIA   -    MD0100PA00X+107972Y+076726X0190Y         S0      
327GND              R5    -2          A18X+107972Y+076726X0198Y0197R180 S2      
317GND              VIA   -    MD0100PA00X+109131Y+077356X0190Y         S0      
327GND              J21   -6          A01X+109131Y+077356X0205Y0590R090 S1      
317GND              VIA   -    MD0100PA00X+110942Y+076726X0190Y         S0      
327GND              R763  -2          A18X+110942Y+076726X0198Y0197R180 S2      
317GND              VIA   -    MD0100PA00X+112101Y+077356X0190Y         S0      
327GND              J19   -6          A01X+112101Y+077356X0205Y0590R090 S1      
317GND              VIA   -    MD0100PA00X+113912Y+076726X0190Y         S0      
327GND              R762  -2          A18X+113912Y+076726X0198Y0197R180 S2      
317GND              VIA   -    MD0100PA00X+115071Y+077356X0190Y         S0      
327GND              J17   -6          A01X+115071Y+077356X0205Y0590R090 S1      
317GND              VIA   -    MD0100PA00X+116882Y+076726X0190Y         S0      
327GND              R761  -2          A18X+116882Y+076726X0198Y0197R180 S2      
317GND              VIA   -    MD0100PA00X+116427Y+077691X0190Y         S0      
327GND              J15   -151        A01X+116427Y+077691X0205Y0590R090 S1      
317GND              VIA   -    MD0100PA00X+118041Y+077356X0190Y         S0      
327GND              J15   -6          A01X+118041Y+077356X0205Y0590R090 S1      
317GND              VIA   -    MD0100PA00X+119852Y+076726X0190Y         S0      
327GND              R7    -2          A18X+119852Y+076726X0198Y0197R180 S2      
317GND              VIA   -    MD0100PA00X+119397Y+077691X0190Y         S0      
327GND              J1    -151        A01X+119397Y+077691X0205Y0590R090 S1      
317GND              VIA   -    MD0100PA00X+121011Y+077356X0190Y         S0      
327GND              J1    -6          A01X+121011Y+077356X0205Y0590R090 S1      
317GND              VIA   -    MD0100PA00X+116972Y+079030X0190Y    R180 S0      
327GND              J15   -155        A01X+116427Y+079030X0205Y0590R090 S1      
317GND              VIA   -    MD0100PA00X+116427Y+078360X0190Y         S0      
327GND              J15   -153        A01X+116427Y+078360X0205Y0590R090 S1      
317GND              VIA   -    MD0100PA00X+117496Y+078695X0190Y         S0      
327GND              J15   -10         A01X+118041Y+078695X0205Y0590R090 S1      
317GND              VIA   -    MD0100PA00X+118041Y+078026X0190Y         S0      
327GND              J15   -8          A01X+118041Y+078026X0205Y0590R090 S1      
317GND              VIA   -    MD0100PA00X+117601Y+079197X0190Y         S0      
317GND              VIA   -    MD0100PA00X+119942Y+079030X0190Y    R180 S0      
327GND              J1    -155        A01X+119397Y+079030X0205Y0590R090 S1      
317GND              VIA   -    MD0100PA00X+119397Y+078360X0190Y         S0      
327GND              J1    -153        A01X+119397Y+078360X0205Y0590R090 S1      
317GND              VIA   -    MD0100PA00X+120466Y+078695X0190Y         S0      
327GND              J1    -10         A01X+121011Y+078695X0205Y0590R090 S1      
317GND              VIA   -    MD0100PA00X+121011Y+078026X0190Y         S0      
327GND              J1    -8          A01X+121011Y+078026X0205Y0590R090 S1      
317GND              VIA   -    MD0100PA00X+120571Y+079197X0190Y         S0      
317GND              VIA   -    MD0100PA00X+116972Y+080034X0190Y    R180 S0      
327GND              J15   -158        A01X+116427Y+080034X0205Y0590R090 S1      
317GND              VIA   -    MD0100PA00X+116427Y+080703X0190Y         S0      
327GND              J15   -160        A01X+116427Y+080703X0205Y0590R090 S1      
317GND              VIA   -    MD0100PA00X+115987Y+079532X0190Y         S0      
317GND              VIA   -    MD0100PA00X+117496Y+079699X0190Y         S0      
327GND              J15   -13         A01X+118041Y+079699X0205Y0590R090 S1      
317GND              VIA   -    MD0100PA00X+118041Y+080368X0190Y         S0      
327GND              J15   -15         A01X+118041Y+080368X0205Y0590R090 S1      
317GND              VIA   -    MD0100PA00X+119942Y+080034X0190Y    R180 S0      
327GND              J1    -158        A01X+119397Y+080034X0205Y0590R090 S1      
317GND              VIA   -    MD0100PA00X+119397Y+080703X0190Y         S0      
327GND              J1    -160        A01X+119397Y+080703X0205Y0590R090 S1      
317GND              VIA   -    MD0100PA00X+118957Y+079532X0190Y         S0      
317GND              VIA   -    MD0100PA00X+120466Y+079699X0190Y         S0      
327GND              J1    -13         A01X+121011Y+079699X0205Y0590R090 S1      
317GND              VIA   -    MD0100PA00X+121011Y+080368X0190Y         S0      
327GND              J1    -15         A01X+121011Y+080368X0205Y0590R090 S1      
317GND              VIA   -    MD0100PA00X+116427Y+081372X0190Y         S0      
327GND              J15   -162        A01X+116427Y+081372X0205Y0590R090 S1      
317GND              VIA   -    MD0100PA00X+116427Y+082041X0190Y         S0      
327GND              J15   -164        A01X+116427Y+082041X0205Y0590R090 S1      
317GND              VIA   -    MD0100PA00X+118041Y+081037X0190Y         S0      
327GND              J15   -17         A01X+118041Y+081037X0205Y0590R090 S1      
317GND              VIA   -    MD0100PA00X+118041Y+081707X0190Y         S0      
327GND              J15   -19         A01X+118041Y+081707X0205Y0590R090 S1      
317GND              VIA   -    MD0100PA00X+119397Y+081372X0190Y         S0      
327GND              J1    -162        A01X+119397Y+081372X0205Y0590R090 S1      
317GND              VIA   -    MD0100PA00X+119397Y+082041X0190Y         S0      
327GND              J1    -164        A01X+119397Y+082041X0205Y0590R090 S1      
317GND              VIA   -    MD0100PA00X+121011Y+081037X0190Y         S0      
327GND              J1    -17         A01X+121011Y+081037X0205Y0590R090 S1      
317GND              VIA   -    MD0100PA00X+121011Y+081707X0190Y         S0      
327GND              J1    -19         A01X+121011Y+081707X0205Y0590R090 S1      
317GND              VIA   -    MD0100PA00X+116972Y+082711X0190Y    R180 S0      
327GND              J15   -166        A01X+116427Y+082711X0205Y0590R090 S1      
317GND              VIA   -    MD0100PA00X+116972Y+083715X0190Y    R180 S0      
327GND              J15   -169        A01X+116427Y+083715X0205Y0590R090 S1      
317GND              VIA   -    MD0100PA00X+115987Y+083213X0190Y         S0      
317GND              VIA   -    MD0100PA00X+117496Y+082376X0190Y         S0      
327GND              J15   -21         A01X+118041Y+082376X0205Y0590R090 S1      
317GND              VIA   -    MD0100PA00X+117496Y+083380X0190Y         S0      
327GND              J15   -24         A01X+118041Y+083380X0205Y0590R090 S1      
317GND              VIA   -    MD0100PA00X+117601Y+082878X0190Y         S0      
317GND              VIA   -    MD0100PA00X+119942Y+082711X0190Y    R180 S0      
327GND              J1    -166        A01X+119397Y+082711X0205Y0590R090 S1      
317GND              VIA   -    MD0100PA00X+119942Y+083715X0190Y    R180 S0      
327GND              J1    -169        A01X+119397Y+083715X0205Y0590R090 S1      
317GND              VIA   -    MD0100PA00X+118957Y+083213X0190Y         S0      
317GND              VIA   -    MD0100PA00X+120466Y+082376X0190Y         S0      
327GND              J1    -21         A01X+121011Y+082376X0205Y0590R090 S1      
317GND              VIA   -    MD0100PA00X+120466Y+083380X0190Y         S0      
327GND              J1    -24         A01X+121011Y+083380X0205Y0590R090 S1      
317GND              VIA   -    MD0100PA00X+120571Y+082878X0190Y         S0      
317GND              VIA   -    MD0100PA00X+116427Y+084384X0190Y         S0      
327GND              J15   -171        A01X+116427Y+084384X0205Y0590R090 S1      
317GND              VIA   -    MD0100PA00X+116427Y+085053X0190Y         S0      
327GND              J15   -173        A01X+116427Y+085053X0205Y0590R090 S1      
317GND              VIA   -    MD0100PA00X+118041Y+084049X0190Y         S0      
327GND              J15   -26         A01X+118041Y+084049X0205Y0590R090 S1      
317GND              VIA   -    MD0100PA00X+118041Y+084718X0190Y         S0      
327GND              J15   -28         A01X+118041Y+084718X0205Y0590R090 S1      
317GND              VIA   -    MD0100PA00X+119397Y+084384X0190Y         S0      
327GND              J1    -171        A01X+119397Y+084384X0205Y0590R090 S1      
317GND              VIA   -    MD0100PA00X+119397Y+085053X0190Y         S0      
327GND              J1    -173        A01X+119397Y+085053X0205Y0590R090 S1      
317GND              VIA   -    MD0100PA00X+121011Y+084049X0190Y         S0      
327GND              J1    -26         A01X+121011Y+084049X0205Y0590R090 S1      
317GND              VIA   -    MD0100PA00X+121011Y+084718X0190Y         S0      
327GND              J1    -28         A01X+121011Y+084718X0205Y0590R090 S1      
317GND              VIA   -    MD0100PA00X+116972Y+086392X0190Y    R180 S0      
327GND              J15   -177        A01X+116427Y+086392X0205Y0590R090 S1      
317GND              VIA   -    MD0100PA00X+116427Y+085722X0190Y         S0      
327GND              J15   -175        A01X+116427Y+085722X0205Y0590R090 S1      
317GND              VIA   -    MD0100PA00X+117496Y+086057X0190Y         S0      
327GND              J15   -32         A01X+118041Y+086057X0205Y0590R090 S1      
317GND              VIA   -    MD0100PA00X+118041Y+085388X0190Y         S0      
327GND              J15   -30         A01X+118041Y+085388X0205Y0590R090 S1      
317GND              VIA   -    MD0100PA00X+117601Y+086559X0190Y         S0      
317GND              VIA   -    MD0100PA00X+119942Y+086392X0190Y    R180 S0      
327GND              J1    -177        A01X+119397Y+086392X0205Y0590R090 S1      
317GND              VIA   -    MD0100PA00X+119397Y+085722X0190Y         S0      
327GND              J1    -175        A01X+119397Y+085722X0205Y0590R090 S1      
317GND              VIA   -    MD0100PA00X+120466Y+086057X0190Y         S0      
327GND              J1    -32         A01X+121011Y+086057X0205Y0590R090 S1      
317GND              VIA   -    MD0100PA00X+121011Y+085388X0190Y         S0      
327GND              J1    -30         A01X+121011Y+085388X0205Y0590R090 S1      
317GND              VIA   -    MD0100PA00X+120571Y+086559X0190Y         S0      
317GND              VIA   -    MD0100PA00X+116972Y+087396X0190Y    R180 S0      
327GND              J15   -180        A01X+116427Y+087396X0205Y0590R090 S1      
317GND              VIA   -    MD0100PA00X+116427Y+088065X0190Y         S0      
327GND              J15   -182        A01X+116427Y+088065X0205Y0590R090 S1      
317GND              VIA   -    MD0100PA00X+115987Y+086894X0190Y         S0      
317GND              VIA   -    MD0100PA00X+117496Y+087061X0190Y         S0      
327GND              J15   -35         A01X+118041Y+087061X0205Y0590R090 S1      
317GND              VIA   -    MD0100PA00X+118041Y+087730X0190Y         S0      
327GND              J15   -37         A01X+118041Y+087730X0205Y0590R090 S1      
317GND              VIA   -    MD0100PA00X+119942Y+087396X0190Y    R180 S0      
327GND              J1    -180        A01X+119397Y+087396X0205Y0590R090 S1      
317GND              VIA   -    MD0100PA00X+119397Y+088065X0190Y         S0      
327GND              J1    -182        A01X+119397Y+088065X0205Y0590R090 S1      
317GND              VIA   -    MD0100PA00X+118957Y+086894X0190Y         S0      
317GND              VIA   -    MD0100PA00X+120466Y+087061X0190Y         S0      
327GND              J1    -35         A01X+121011Y+087061X0205Y0590R090 S1      
317GND              VIA   -    MD0100PA00X+121011Y+087730X0190Y         S0      
327GND              J1    -37         A01X+121011Y+087730X0205Y0590R090 S1      
317GND              VIA   -    MD0100PA00X+116427Y+088734X0190Y         S0      
327GND              J15   -184        A01X+116427Y+088734X0205Y0590R090 S1      
317GND              VIA   -    MD0100PA00X+118041Y+088400X0190Y         S0      
327GND              J15   -39         A01X+118041Y+088400X0205Y0590R090 S1      
317GND              VIA   -    MD0100PA00X+118041Y+089069X0190Y         S0      
327GND              J15   -41         A01X+118041Y+089069X0205Y0590R090 S1      
317GND              VIA   -    MD0100PA00X+119397Y+088734X0190Y         S0      
327GND              J1    -184        A01X+119397Y+088734X0205Y0590R090 S1      
317GND              VIA   -    MD0100PA00X+121011Y+088400X0190Y         S0      
327GND              J1    -39         A01X+121011Y+088400X0205Y0590R090 S1      
317GND              VIA   -    MD0100PA00X+121011Y+089069X0190Y         S0      
327GND              J1    -41         A01X+121011Y+089069X0205Y0590R090 S1      
327GND              PC113_-2          A01X+120473Y+138572X0198Y0197R090 S1      
317GND              VIA   -    MD0100PA00X+110223Y+138477X0200Y         S0      
317GND              VIA   -    MD0100PA00X+113493Y+138477X0200Y         S0      
317GND              VIA   -    MD0100PA00X+116783Y+138477X0200Y         S0      
317GND              VIA   -    MD0100PA00X+120069Y+138457X0200Y         S0      
317GND              VIA   -    MD0100PA00X+127152Y+133860X0200Y         S0      
317GND              VIA   -    MD0100PA00X+130442Y+133854X0200Y         S0      
317GND              VIA   -    MD0100PA00X+133722Y+133874X0200Y         S0      
327GND              PC175_-2          A01X+110633Y+138572X0198Y0197R090 S1      
327GND              PC177_-2          A01X+110223Y+138229X0198Y0197     S1      
327GND              PC146_-2          A01X+113903Y+138572X0198Y0197R090 S1      
327GND              PC149_-2          A01X+113493Y+138229X0198Y0197     S1      
327GND              PC145_-2          A01X+117193Y+138572X0198Y0197R090 S1      
327GND              PC148_-2          A01X+116783Y+138229X0198Y0197     S1      
327GND              PC178_-2          A01X+120069Y+138209X0198Y0197     S1      
327GND              PC83_2-2          A01X+127562Y+133955X0198Y0197R090 S1      
327GND              PC86_2-2          A01X+127152Y+133611X0198Y0197     S1      
327GND              PC84_1-2          A01X+130852Y+133949X0198Y0197R090 S1      
327GND              PC85_1-2          A01X+130442Y+133606X0198Y0197     S1      
327GND              PC132_-2          A01X+134132Y+133969X0198Y0197R090 S1      
327GND              PC134_-2          A01X+133722Y+133626X0198Y0197     S1      
317GND              VIA   -    MD0100PA00X+110389Y+138672X0200Y         S0      
317GND              VIA   -    MD0100PA00X+113659Y+138672X0200Y         S0      
317GND              VIA   -    MD0100PA00X+116949Y+138672X0200Y         S0      
317GND              VIA   -    MD0100PA00X+120229Y+138672X0200Y         S0      
317GND              VIA   -    MD0100PA00X+127318Y+134055X0200Y         S0      
317GND              VIA   -    MD0100PA00X+130608Y+134049X0200Y         S0      
317GND              VIA   -    MD0100PA00X+133888Y+134069X0200Y         S0      
327GND              PC188_-2          A18X+108876Y+138404X0400Y0500R090 S2      
327GND              PC187_-2          A18X+112136Y+138404X0400Y0500R090 S2      
327GND              PC157_-2          A18X+115406Y+138404X0400Y0500R090 S2      
327GND              PC154_-2          A18X+118696Y+138404X0400Y0500R090 S2      
327GND              PC123_-2          A18X+121976Y+138404X0400Y0500R090 S2      
327GND              PC126_-2          A18X+125775Y+133789X0400Y0500R090 S2      
327GND              PC118_-2          A18X+139731Y+133509X0400Y0500R270 S2      
327GND              PC119_-2          A18X+138893Y+133509X0400Y0500R270 S2      
327GND              PC100 -2          A18X+138679Y+132410X0950Y1110R270 S2      
327GND              PC139_-2          A18X+136472Y+131576X0400Y0500R270 S2      
327GND              PC138_-2          A18X+135635Y+131576X0400Y0500R270 S2      
327GND              PC91_1-2          A18X+133192Y+131556X0400Y0500R270 S2      
327GND              PC89_1-2          A18X+132355Y+131556X0400Y0500R270 S2      
327GND              PC96_2-2          A18X+129064Y+131562X0400Y0500R270 S2      
327GND              PC90_2-2          A18X+129902Y+131562X0400Y0500R270 S2      
327GND              PC124_-2          A18X+126612Y+131565X0400Y0500R270 S2      
327GND              PC120_-2          A18X+125775Y+131565X0400Y0500R270 S2      
327GND              PR444 -2          A18X+140569Y+130633X0198Y0197R270 S2      
327GND              PC123_-2          A18X+140050Y+130785X0400Y0500R090 S2      
327GND              PC120_-2          A18X+137230Y+130773X0400Y0500R090 S2      
327GND              PC98  -2          A18X+135210Y+130477X0950Y1110R270 S2      
327GND              PC103 -2          A18X+131770Y+130480X0950Y1110R270 S2      
327GND              PC102 -2          A18X+128311Y+130488X0950Y1110R270 S2      
327GND              PC97  -2          A18X+125369Y+130488X0950Y1110R270 S2      
327GND              PC141_-2          A18X+136583Y+129019X0400Y0500R090 S2      
327GND              PC140_-2          A18X+133833Y+128839X0400Y0500R090 S2      
327GND              PC102_-2          A18X+133144Y+128831X0400Y0500R090 S2      
327GND              PC105_-2          A18X+130396Y+128819X0400Y0500R090 S2      
327GND              PC106_-2          A18X+129708Y+128818X0400Y0500R090 S2      
327GND              PC108_-2          A18X+126935Y+128786X0400Y0500R090 S2      
327GND              PC112 -2          A01X+137001Y+135039X0198Y0197R090 S1      
327GND              PU11  -2   M      A01X+137506Y+134551X0090Y0240R090 S1      
327GND              PC115_-2          A01X+139882Y+133734X0198Y0197R270 S1      
327GND              PU11  -5          A01X+137506Y+134020X0090Y0240R090 S1      
327GND              PR155 -2          A01X+137004Y+133307X0198Y0197R090 S1      
327GND              PC113_-2          A01X+137001Y+133674X0198Y0197R270 S1      
327GND              PL9   -2          A01X+141456Y+131843X0790Y1660R090 S1      
327GND              PC135_-2          A01X+136624Y+131801X0198Y0197R270 S1      
327GND              PC131 -2          A01X+133743Y+133106X0198Y0197R090 S1      
327GND              PU16  -2   M      A01X+134248Y+132618X0090Y0240R090 S1      
327GND              PU16  -5          A01X+134248Y+132086X0090Y0240R090 S1      
327GND              PC87_1-2          A01X+133344Y+131781X0198Y0197R270 S1      
327GND              PC133_-2          A01X+133743Y+131741X0198Y0197R270 S1      
327GND              PC79  -2          A01X+130463Y+133086X0198Y0197R090 S1      
327GND              PU13  -2   M      A01X+130968Y+132598X0090Y0240R090 S1      
327GND              PU13  -5          A01X+130968Y+132066X0090Y0240R090 S1      
327GND              PC88_2-2          A01X+130069Y+131783X0198Y0197R270 S1      
327GND              PC81_C-2          A01X+130463Y+131721X0198Y0197R270 S1      
327GND              PC80  -2          A01X+127173Y+133092X0198Y0197R090 S1      
327GND              PU2   -2   M      A01X+127678Y+132604X0090Y0240R090 S1      
327GND              PU2   -5          A01X+127678Y+132072X0090Y0240R090 S1      
327GND              PC82_C-2          A01X+127173Y+131727X0198Y0197R270 S1      
327GND              PC118_-2          A01X+126764Y+131770X0198Y0197R270 S1      
327GND              PC112_-2          A01X+123883Y+131730X0198Y0197R270 S1      
327GND              PC110 -2          A01X+123883Y+133095X0198Y0197R090 S1      
327GND              PU15  -2   M      A01X+124388Y+132606X0090Y0240R090 S1      
327GND              PU15  -5          A01X+124388Y+132075X0090Y0240R090 S1      
327GND              PR158 -2          A01X+133745Y+131374X0198Y0197R090 S1      
327GND              PR506 -2          A01X+130465Y+131354X0198Y0197R090 S1      
327GND              PR507 -2          A01X+127175Y+131360X0198Y0197R090 S1      
327GND              PR510 -2          A01X+123885Y+131363X0198Y0197R090 S1      
327GND              PC93_2-2          A18X+129064Y+133786X0400Y0500R090 S2      
327GND              PC95_1-2          A18X+132355Y+133780X0400Y0500R090 S2      
327GND              PC136_-2          A18X+135635Y+133800X0400Y0500R090 S2      
327GND              PC116_-2          A18X+138893Y+135734X0400Y0500R090 S2      
317GND              VIA   -    MD0100PA00X+105168Y+135072X0193Y         S0      
317GND              VIA   -    MD0100PA00X+104868Y+135072X0193Y         S0      
317GND              VIA   -    MD0100PA00X+105468Y+135072X0193Y         S0      
317GND              VIA   -    MD0100PA00X+106793Y+133770X0200Y         S0      
317GND              VIA   -    MD0100PA00X+106072Y+131395X0200Y    R180 S0      
327GND              PC107 -2          A01X+106492Y+131106X0198Y0197R090 S1      
327GND              PR50  -2   M      A01X+106072Y+131120X0198Y0197     S1      
317GND              VIA   -    MD0100PA00X+105768Y+135072X0193Y         S0      
317GND              VIA   -    MD0100PA00X+106068Y+135072X0193Y         S0      
317GND              VIA   -    MD0100PA00X+107373Y+138820X0200Y         S0      
327GND              PC176_-2          A01X+107373Y+138572X0198Y0197R090 S1      
317GND              VIA   -    MD0100PA00X+108337Y+138527X0200Y         S0      
327GND              PR105 -2          A01X+108078Y+138554X0198Y0197     S1      
317GND              VIA   -    MD0100PA00X+108332Y+137285X0193Y         S0      
317GND              VIA   -    MD0100PA00X+108089Y+137285X0193Y         S0      
317GND              VIA   -    MD0100PA00X+107846Y+137285X0193Y         S0      
317GND              VIA   -    MD0100PA00X+107846Y+136725X0193Y         S0      
317GND              VIA   -    MD0100PA00X+107922Y+136050X0193Y         S0      
317GND              VIA   -    MD0100PA00X+107662Y+136050X0193Y         S0      
317GND              VIA   -    MD0100PA00X+108442Y+136345X0193Y         S0      
317GND              VIA   -    MD0100PA00X+108182Y+136345X0193Y         S0      
317GND              VIA   -    MD0100PA00X+108442Y+136050X0193Y         S0      
317GND              VIA   -    MD0100PA00X+108182Y+136050X0193Y         S0      
317GND              VIA   -    MD0100PA00X+108089Y+136725X0193Y         S0      
317GND              VIA   -    MD0100PA00X+108332Y+136725X0193Y         S0      
327GND              PU20  -40  M      A01X+108089Y+137004X0690Y0770     S1      
317GND              VIA   -    MD0100PA00X+108182Y+135739X0193Y         S0      
317GND              VIA   -    MD0100PA00X+107662Y+135739X0193Y         S0      
317GND              VIA   -    MD0100PA00X+107922Y+135739X0193Y         S0      
317GND              VIA   -    MD0100PA00X+108442Y+135739X0193Y         S0      
317GND              VIA   -    MD0100PA00X+107095Y+133775X0200Y         S0      
317GND              VIA   -    MD0100PA00X+109290Y+136044X0193Y         S0      
317GND              VIA   -    MD0100PA00X+109290Y+136339X0193Y         S0      
317GND              VIA   -    MD0100PA00X+109196Y+135741X0193Y         S0      
317GND              VIA   -    MD0100PA00X+108952Y+135739X0193Y         S0      
317GND              VIA   -    MD0100PA00X+109823Y+135485X0200Y         S0      
317GND              VIA   -    MD0100PA00X+109698Y+135735X0200Y         S0      
317GND              VIA   -    MD0100PA00X+109563Y+135485X0200Y         S0      
317GND              VIA   -    MD0100PA00X+109823Y+134965X0200Y         S0      
317GND              VIA   -    MD0100PA00X+109563Y+134965X0200Y         S0      
317GND              VIA   -    MD0100PA00X+109823Y+135225X0200Y         S0      
317GND              VIA   -    MD0100PA00X+109563Y+135225X0200Y         S0      
317GND              VIA   -    MD0100PA00X+108702Y+135739X0193Y         S0      
327GND              PU20  -7_9-M      A01X+108434Y+136050X0827Y2126R090 S1      
317GND              VIA   -    MD0100PA00X+109581Y+133782X0200Y         S0      
317GND              VIA   -    MD0100PA00X+109841Y+133782X0200Y         S0      
317GND              VIA   -    MD0100PA00X+111349Y+137285X0193Y         S0      
317GND              VIA   -    MD0100PA00X+111106Y+137285X0193Y         S0      
317GND              VIA   -    MD0100PA00X+111106Y+136725X0193Y         S0      
317GND              VIA   -    MD0100PA00X+111442Y+136050X0193Y         S0      
317GND              VIA   -    MD0100PA00X+111182Y+136050X0193Y         S0      
317GND              VIA   -    MD0100PA00X+110922Y+136050X0193Y         S0      
317GND              VIA   -    MD0100PA00X+111442Y+136345X0193Y         S0      
317GND              VIA   -    MD0100PA00X+111349Y+136725X0193Y         S0      
317GND              VIA   -    MD0100PA00X+111442Y+135739X0193Y         S0      
317GND              VIA   -    MD0100PA00X+110922Y+135739X0193Y         S0      
317GND              VIA   -    MD0100PA00X+111182Y+135739X0193Y         S0      
317GND              VIA   -    MD0100PA00X+110929Y+133775X0200Y         S0      
317GND              VIA   -    MD0100PA00X+110353Y+133779X0200Y         S0      
317GND              VIA   -    MD0100PA00X+111592Y+136725X0193Y         S0      
317GND              VIA   -    MD0100PA00X+112550Y+136044X0193Y         S0      
317GND              VIA   -    MD0100PA00X+112550Y+136339X0193Y         S0      
317GND              VIA   -    MD0100PA00X+111702Y+135739X0193Y         S0      
317GND              VIA   -    MD0100PA00X+112456Y+135741X0193Y         S0      
317GND              VIA   -    MD0100PA00X+112212Y+135739X0193Y         S0      
317GND              VIA   -    MD0100PA00X+111962Y+135739X0193Y         S0      
317GND              VIA   -    MD0100PA00X+112823Y+135485X0200Y         S0      
317GND              VIA   -    MD0100PA00X+112958Y+135735X0200Y         S0      
317GND              VIA   -    MD0100PA00X+112823Y+134965X0200Y         S0      
317GND              VIA   -    MD0100PA00X+112823Y+135225X0200Y         S0      
317GND              VIA   -    MD0100PA00X+111592Y+137285X0193Y         S0      
327GND              PU19  -40  M      A01X+111349Y+137004X0690Y0770     S1      
317GND              VIA   -    MD0100PA00X+111702Y+136050X0193Y         S0      
317GND              VIA   -    MD0100PA00X+111702Y+136345X0193Y         S0      
327GND              PU19  -7_9-M      A01X+111694Y+136050X0827Y2126R090 S1      
317GND              VIA   -    MD0100PA00X+111597Y+138527X0200Y         S0      
327GND              PR106 -2          A01X+111338Y+138554X0198Y0197     S1      
317GND              VIA   -    MD0100PA00X+114376Y+137285X0193Y         S0      
317GND              VIA   -    MD0100PA00X+114376Y+136725X0193Y         S0      
317GND              VIA   -    MD0100PA00X+114452Y+136050X0193Y         S0      
317GND              VIA   -    MD0100PA00X+114192Y+136050X0193Y         S0      
317GND              VIA   -    MD0100PA00X+113083Y+135485X0200Y         S0      
317GND              VIA   -    MD0100PA00X+114452Y+135739X0193Y         S0      
317GND              VIA   -    MD0100PA00X+114192Y+135739X0193Y         S0      
317GND              VIA   -    MD0100PA00X+113083Y+134965X0200Y         S0      
317GND              VIA   -    MD0100PA00X+113083Y+135225X0200Y         S0      
317GND              VIA   -    MD0100PA00X+113362Y+133779X0200Y         S0      
317GND              VIA   -    MD0100PA00X+114322Y+133783X0200Y         S0      
317GND              VIA   -    MD0100PA00X+113622Y+133779X0200Y         S0      
317GND              VIA   -    MD0100PA00X+114619Y+136725X0193Y         S0      
317GND              VIA   -    MD0100PA00X+114862Y+136725X0193Y         S0      
317GND              VIA   -    MD0100PA00X+115820Y+136044X0193Y         S0      
317GND              VIA   -    MD0100PA00X+115820Y+136339X0193Y         S0      
317GND              VIA   -    MD0100PA00X+114972Y+135739X0193Y         S0      
317GND              VIA   -    MD0100PA00X+114712Y+135739X0193Y         S0      
317GND              VIA   -    MD0100PA00X+115482Y+135739X0193Y         S0      
317GND              VIA   -    MD0100PA00X+115232Y+135739X0193Y         S0      
317GND              VIA   -    MD0100PA00X+115726Y+135741X0193Y         S0      
317GND              VIA   -    MD0100PA00X+114582Y+133783X0200Y         S0      
317GND              VIA   -    MD0100PA00X+115484Y+133783X0200Y         S0      
317GND              VIA   -    MD0100PA00X+115744Y+133783X0200Y         S0      
317GND              VIA   -    MD0100PA00X+114867Y+138527X0200Y         S0      
327GND              PR97  -2          A01X+114608Y+138554X0198Y0197     S1      
317GND              VIA   -    MD0100PA00X+114862Y+137285X0193Y         S0      
317GND              VIA   -    MD0100PA00X+114619Y+137285X0193Y         S0      
327GND              PU18  -40  M      A01X+114619Y+137004X0690Y0770     S1      
317GND              VIA   -    MD0100PA00X+114712Y+136345X0193Y         S0      
317GND              VIA   -    MD0100PA00X+114972Y+136050X0193Y         S0      
317GND              VIA   -    MD0100PA00X+114972Y+136345X0193Y         S0      
317GND              VIA   -    MD0100PA00X+114712Y+136050X0193Y         S0      
327GND              PU18  -7_9-M      A01X+114964Y+136050X0827Y2126R090 S1      
317GND              VIA   -    MD0100PA00X+115046Y+143315X0200Y         S0      
327GND              PC148 -2          A01X+115046Y+143658X0198Y0197     S1      
317GND              VIA   -    MD0100PA00X+116353Y+135485X0200Y         S0      
317GND              VIA   -    MD0100PA00X+116228Y+135735X0200Y         S0      
317GND              VIA   -    MD0100PA00X+116353Y+134965X0200Y         S0      
317GND              VIA   -    MD0100PA00X+116093Y+134965X0200Y         S0      
317GND              VIA   -    MD0100PA00X+116353Y+135225X0200Y         S0      
317GND              VIA   -    MD0100PA00X+116093Y+135225X0200Y         S0      
317GND              VIA   -    MD0100PA00X+116491Y+133788X0200Y         S0      
317GND              VIA   -    MD0100PA00X+116751Y+133788X0200Y         S0      
317GND              VIA   -    MD0100PA00X+118002Y+135739X0193Y         S0      
317GND              VIA   -    MD0100PA00X+117482Y+135739X0193Y         S0      
317GND              VIA   -    MD0100PA00X+117742Y+135739X0193Y         S0      
317GND              VIA   -    MD0100PA00X+118772Y+135739X0193Y         S0      
317GND              VIA   -    MD0100PA00X+118522Y+135739X0193Y         S0      
317GND              VIA   -    MD0100PA00X+118262Y+135739X0193Y         S0      
317GND              VIA   -    MD0100PA00X+117909Y+136725X0193Y         S0      
317GND              VIA   -    MD0100PA00X+118152Y+136725X0193Y         S0      
317GND              VIA   -    MD0100PA00X+118157Y+138527X0200Y         S0      
327GND              PR98  -2          A01X+117898Y+138554X0198Y0197     S1      
317GND              VIA   -    MD0100PA00X+118152Y+137285X0193Y         S0      
317GND              VIA   -    MD0100PA00X+117909Y+137285X0193Y         S0      
317GND              VIA   -    MD0100PA00X+117666Y+137285X0193Y         S0      
317GND              VIA   -    MD0100PA00X+117666Y+136725X0193Y         S0      
327GND              PU17  -40  M      A01X+117909Y+137004X0690Y0770     S1      
317GND              VIA   -    MD0100PA00X+118002Y+136050X0193Y         S0      
317GND              VIA   -    MD0100PA00X+117742Y+136050X0193Y         S0      
317GND              VIA   -    MD0100PA00X+117482Y+136050X0193Y         S0      
317GND              VIA   -    MD0100PA00X+118002Y+136345X0193Y         S0      
317GND              VIA   -    MD0100PA00X+118262Y+136050X0193Y         S0      
317GND              VIA   -    MD0100PA00X+118262Y+136345X0193Y         S0      
317GND              VIA   -    MD0100PA00X+119110Y+136044X0193Y         S0      
317GND              VIA   -    MD0100PA00X+119110Y+136339X0193Y         S0      
317GND              VIA   -    MD0100PA00X+119643Y+135485X0200Y         S0      
317GND              VIA   -    MD0100PA00X+119518Y+135735X0200Y         S0      
317GND              VIA   -    MD0100PA00X+119016Y+135741X0193Y         S0      
327GND              PU17  -7_9-M      A01X+118254Y+136050X0827Y2126R090 S1      
317GND              VIA   -    MD0100PA00X+119383Y+135485X0200Y         S0      
317GND              VIA   -    MD0100PA00X+119643Y+134965X0200Y         S0      
317GND              VIA   -    MD0100PA00X+119383Y+134965X0200Y         S0      
317GND              VIA   -    MD0100PA00X+119643Y+135225X0200Y         S0      
317GND              VIA   -    MD0100PA00X+119383Y+135225X0200Y         S0      
317GND              VIA   -    MD0100PA00X+120240Y+133810X0200Y         S0      
317GND              VIA   -    MD0100PA00X+119990Y+133806X0200Y         S0      
317GND              VIA   -    MD0100PA00X+119626Y+132155X0200Y         S0      
317GND              VIA   -    MD0100PA00X+119366Y+132155X0200Y         S0      
317GND              VIA   -    MD0100PA00X+119626Y+132405X0200Y         S0      
317GND              VIA   -    MD0100PA00X+119366Y+132405X0200Y         S0      
317GND              VIA   -    MD0100PA00X+120269Y+132403X0200Y         S0      
317GND              VIA   -    MD0100PA00X+120269Y+132149X0200Y         S0      
317GND              VIA   -    MD0100PA00X+119366Y+132659X0200Y         S0      
317GND              VIA   -    MD0100PA00X+119616Y+132655X0200Y         S0      
317GND              VIA   -    MD0100PA00X+121189Y+136725X0193Y         S0      
317GND              VIA   -    MD0100PA00X+121432Y+136725X0193Y         S0      
317GND              VIA   -    MD0100PA00X+120762Y+135739X0193Y         S0      
317GND              VIA   -    MD0100PA00X+121022Y+135739X0193Y         S0      
317GND              VIA   -    MD0100PA00X+121282Y+135739X0193Y         S0      
317GND              VIA   -    MD0100PA00X+121542Y+135739X0193Y         S0      
317GND              VIA   -    MD0100PA00X+121802Y+135739X0193Y         S0      
317GND              VIA   -    MD0100PA00X+121130Y+133810X0200Y         S0      
317GND              VIA   -    MD0100PA00X+120519Y+132399X0200Y         S0      
317GND              VIA   -    MD0100PA00X+120519Y+132149X0200Y         S0      
317GND              VIA   -    MD0100PA00X+121437Y+138527X0200Y         S0      
327GND              PR85  -2          A01X+121178Y+138554X0198Y0197     S1      
317GND              VIA   -    MD0100PA00X+120946Y+136725X0193Y         S0      
317GND              VIA   -    MD0100PA00X+120946Y+137285X0193Y         S0      
317GND              VIA   -    MD0100PA00X+121189Y+137285X0193Y         S0      
317GND              VIA   -    MD0100PA00X+121432Y+137285X0193Y         S0      
327GND              PU14  -40  M      A01X+121189Y+137004X0690Y0770     S1      
317GND              VIA   -    MD0100PA00X+120762Y+136050X0193Y         S0      
317GND              VIA   -    MD0100PA00X+121022Y+136050X0193Y         S0      
317GND              VIA   -    MD0100PA00X+121282Y+136050X0193Y         S0      
317GND              VIA   -    MD0100PA00X+121282Y+136345X0193Y         S0      
317GND              VIA   -    MD0100PA00X+121542Y+136050X0193Y         S0      
317GND              VIA   -    MD0100PA00X+121542Y+136345X0193Y         S0      
317GND              VIA   -    MD0100PA00X+122052Y+135739X0193Y         S0      
317GND              VIA   -    MD0100PA00X+122923Y+135485X0200Y         S0      
317GND              VIA   -    MD0100PA00X+122663Y+135485X0200Y         S0      
317GND              VIA   -    MD0100PA00X+122798Y+135735X0200Y         S0      
317GND              VIA   -    MD0100PA00X+122296Y+135741X0193Y         S0      
317GND              VIA   -    MD0100PA00X+122923Y+134965X0200Y         S0      
317GND              VIA   -    MD0100PA00X+122663Y+134965X0200Y         S0      
317GND              VIA   -    MD0100PA00X+122923Y+135225X0200Y         S0      
317GND              VIA   -    MD0100PA00X+122663Y+135225X0200Y         S0      
317GND              VIA   -    MD0100PA00X+122981Y+133810X0200Y         S0      
317GND              VIA   -    MD0100PA00X+121946Y+133812X0200Y         S0      
317GND              VIA   -    MD0100PA00X+123241Y+133810X0200Y         S0      
317GND              VIA   -    MD0100PA00X+122390Y+136044X0193Y         S0      
317GND              VIA   -    MD0100PA00X+122390Y+136339X0193Y         S0      
327GND              PU14  -7_9-M      A01X+121534Y+136050X0827Y2126R090 S1      
317GND              VIA   -    MD0100PA00X+124024Y+133958X0200Y         S0      
327GND              PC114_-2          A01X+124272Y+133958X0198Y0197R090 S1      
317GND              VIA   -    MD0100PA00X+125236Y+133912X0200Y         S0      
327GND              PR86  -2          A01X+124977Y+133940X0198Y0197     S1      
317GND              VIA   -    MD0100PA00X+124988Y+132671X0193Y         S0      
317GND              VIA   -    MD0100PA00X+124745Y+132111X0193Y         S0      
317GND              VIA   -    MD0100PA00X+124745Y+132671X0193Y         S0      
317GND              VIA   -    MD0100PA00X+125081Y+131731X0193Y         S0      
317GND              VIA   -    MD0100PA00X+125341Y+131731X0193Y         S0      
317GND              VIA   -    MD0100PA00X+125231Y+132671X0193Y         S0      
317GND              VIA   -    MD0100PA00X+124988Y+132111X0193Y         S0      
317GND              VIA   -    MD0100PA00X+125231Y+132111X0193Y         S0      
327GND              PU15  -40  M      A01X+124988Y+132390X0690Y0770     S1      
317GND              VIA   -    MD0100PA00X+124821Y+131124X0193Y         S0      
317GND              VIA   -    MD0100PA00X+124561Y+131124X0193Y         S0      
317GND              VIA   -    MD0100PA00X+124821Y+131435X0193Y         S0      
317GND              VIA   -    MD0100PA00X+124561Y+131435X0193Y         S0      
317GND              VIA   -    MD0100PA00X+125081Y+131124X0193Y         S0      
317GND              VIA   -    MD0100PA00X+125341Y+131124X0193Y         S0      
317GND              VIA   -    MD0100PA00X+125081Y+131435X0193Y         S0      
317GND              VIA   -    MD0100PA00X+125341Y+131435X0193Y         S0      
317GND              VIA   -    MD0100PA00X+124705Y+129172X0200Y         S0      
317GND              VIA   -    MD0100PA00X+124965Y+129172X0200Y         S0      
317GND              VIA   -    MD0100PA00X+126190Y+131725X0193Y         S0      
317GND              VIA   -    MD0100PA00X+126462Y+130871X0200Y         S0      
317GND              VIA   -    MD0100PA00X+126462Y+130611X0200Y         S0      
317GND              VIA   -    MD0100PA00X+126462Y+130351X0200Y         S0      
317GND              VIA   -    MD0100PA00X+126597Y+131121X0200Y         S0      
317GND              VIA   -    MD0100PA00X+126722Y+130351X0200Y         S0      
317GND              VIA   -    MD0100PA00X+126722Y+130871X0200Y         S0      
317GND              VIA   -    MD0100PA00X+126722Y+130611X0200Y         S0      
317GND              VIA   -    MD0100PA00X+125601Y+131124X0193Y         S0      
317GND              VIA   -    MD0100PA00X+125851Y+131124X0193Y         S0      
317GND              VIA   -    MD0100PA00X+126095Y+131126X0193Y         S0      
317GND              VIA   -    MD0100PA00X+126190Y+131429X0193Y         S0      
327GND              PU15  -7_9-M      A01X+125333Y+131435X0827Y2126R090 S1      
317GND              VIA   -    MD0100PA00X+126807Y+129162X0200Y         S0      
317GND              VIA   -    MD0100PA00X+126005Y+129172X0200Y         S0      
317GND              VIA   -    MD0100PA00X+125745Y+129172X0200Y         S0      
317GND              VIA   -    MD0100PA00X+125812Y+134269X0200Y    R180 S0      
327GND              PC116_-2          A01X+126052Y+134269X0198Y0197R180 S1      
317GND              VIA   -    MD0100PA00X+128035Y+132668X0193Y         S0      
317GND              VIA   -    MD0100PA00X+128035Y+132108X0193Y         S0      
317GND              VIA   -    MD0100PA00X+128278Y+132668X0193Y         S0      
317GND              VIA   -    MD0100PA00X+128278Y+132108X0193Y         S0      
317GND              VIA   -    MD0100PA00X+127850Y+131122X0193Y         S0      
317GND              VIA   -    MD0100PA00X+128110Y+131122X0193Y         S0      
317GND              VIA   -    MD0100PA00X+128110Y+131432X0193Y         S0      
317GND              VIA   -    MD0100PA00X+127850Y+131432X0193Y         S0      
317GND              VIA   -    MD0100PA00X+127067Y+129162X0200Y         S0      
317GND              VIA   -    MD0100PA00X+128521Y+132108X0193Y         S0      
317GND              VIA   -    MD0100PA00X+129479Y+131722X0193Y         S0      
317GND              VIA   -    MD0100PA00X+128370Y+131122X0193Y         S0      
317GND              VIA   -    MD0100PA00X+128630Y+131122X0193Y         S0      
317GND              VIA   -    MD0100PA00X+128370Y+131432X0193Y         S0      
317GND              VIA   -    MD0100PA00X+128630Y+131432X0193Y         S0      
317GND              VIA   -    MD0100PA00X+128890Y+131122X0193Y         S0      
317GND              VIA   -    MD0100PA00X+129385Y+131123X0193Y         S0      
317GND              VIA   -    MD0100PA00X+129140Y+131122X0193Y         S0      
317GND              VIA   -    MD0100PA00X+129752Y+130868X0200Y         S0      
317GND              VIA   -    MD0100PA00X+129752Y+130348X0200Y         S0      
317GND              VIA   -    MD0100PA00X+129752Y+130608X0200Y         S0      
317GND              VIA   -    MD0100PA00X+129479Y+131426X0193Y         S0      
317GND              VIA   -    MD0100PA00X+129575Y+129172X0200Y         S0      
317GND              VIA   -    MD0100PA00X+128526Y+133909X0200Y         S0      
327GND              PR77  -2          A01X+128266Y+133937X0198Y0197     S1      
317GND              VIA   -    MD0100PA00X+128370Y+131728X0193Y         S0      
317GND              VIA   -    MD0100PA00X+128630Y+131728X0193Y         S0      
327GND              PU2   -7_9-M      A01X+128623Y+131432X0827Y2126R090 S1      
317GND              VIA   -    MD0100PA00X+128521Y+132668X0193Y         S0      
327GND              PU2   -40  M      A01X+128278Y+132387X0690Y0770     S1      
317GND              VIA   -    MD0100PA00X+131325Y+132662X0193Y         S0      
317GND              VIA   -    MD0100PA00X+131325Y+132102X0193Y         S0      
317GND              VIA   -    MD0100PA00X+129887Y+131118X0200Y         S0      
317GND              VIA   -    MD0100PA00X+130012Y+130868X0200Y         S0      
317GND              VIA   -    MD0100PA00X+131141Y+131116X0193Y         S0      
317GND              VIA   -    MD0100PA00X+131141Y+131427X0193Y         S0      
317GND              VIA   -    MD0100PA00X+130012Y+130348X0200Y         S0      
317GND              VIA   -    MD0100PA00X+130012Y+130608X0200Y         S0      
317GND              VIA   -    MD0100PA00X+129835Y+129172X0200Y         S0      
317GND              VIA   -    MD0100PA00X+130289Y+129176X0200Y         S0      
317GND              VIA   -    MD0100PA00X+130560Y+129176X0200Y         S0      
317GND              VIA   -    MD0100PA00X+131568Y+132102X0193Y         S0      
317GND              VIA   -    MD0100PA00X+131811Y+132102X0193Y         S0      
317GND              VIA   -    MD0100PA00X+132770Y+131716X0193Y         S0      
317GND              VIA   -    MD0100PA00X+131921Y+131116X0193Y         S0      
317GND              VIA   -    MD0100PA00X+131921Y+131427X0193Y         S0      
317GND              VIA   -    MD0100PA00X+132675Y+131118X0193Y         S0      
317GND              VIA   -    MD0100PA00X+132431Y+131116X0193Y         S0      
317GND              VIA   -    MD0100PA00X+132181Y+131116X0193Y         S0      
317GND              VIA   -    MD0100PA00X+131401Y+131116X0193Y         S0      
317GND              VIA   -    MD0100PA00X+131401Y+131427X0193Y         S0      
317GND              VIA   -    MD0100PA00X+131661Y+131116X0193Y         S0      
317GND              VIA   -    MD0100PA00X+131661Y+131427X0193Y         S0      
317GND              VIA   -    MD0100PA00X+132770Y+131421X0193Y         S0      
317GND              VIA   -    MD0100PA00X+131921Y+131722X0193Y         S0      
317GND              VIA   -    MD0100PA00X+131661Y+131722X0193Y         S0      
327GND              PU13  -7_9-M      A01X+131913Y+131427X0827Y2126R090 S1      
317GND              VIA   -    MD0100PA00X+131811Y+132662X0193Y         S0      
317GND              VIA   -    MD0100PA00X+131568Y+132662X0193Y         S0      
327GND              PU13  -40  M      A01X+131568Y+132381X0690Y0770     S1      
317GND              VIA   -    MD0100PA00X+131816Y+133904X0200Y         S0      
327GND              PR78  -2          A01X+131557Y+133931X0198Y0197     S1      
317GND              VIA   -    MD0100PA00X+133042Y+130862X0200Y         S0      
317GND              VIA   -    MD0100PA00X+133042Y+130342X0200Y         S0      
317GND              VIA   -    MD0100PA00X+133042Y+130602X0200Y         S0      
317GND              VIA   -    MD0100PA00X+133302Y+130342X0200Y         S0      
317GND              VIA   -    MD0100PA00X+133302Y+130602X0200Y         S0      
317GND              VIA   -    MD0100PA00X+133177Y+131112X0200Y         S0      
317GND              VIA   -    MD0100PA00X+133302Y+130862X0200Y         S0      
317GND              VIA   -    MD0100PA00X+133008Y+129186X0200Y         S0      
317GND              VIA   -    MD0100PA00X+133268Y+129186X0200Y         S0      
317GND              VIA   -    MD0100PA00X+133567Y+129190X0200Y         S0      
317GND              VIA   -    MD0100PA00X+133844Y+129195X0200Y         S0      
317GND              VIA   -    MD0100PA00X+134848Y+132122X0193Y         S0      
317GND              VIA   -    MD0100PA00X+135091Y+132122X0193Y         S0      
317GND              VIA   -    MD0100PA00X+134421Y+131447X0193Y         S0      
317GND              VIA   -    MD0100PA00X+134421Y+131136X0193Y         S0      
317GND              VIA   -    MD0100PA00X+135201Y+131447X0193Y         S0      
317GND              VIA   -    MD0100PA00X+134941Y+131447X0193Y         S0      
317GND              VIA   -    MD0100PA00X+134681Y+131447X0193Y         S0      
317GND              VIA   -    MD0100PA00X+135461Y+131136X0193Y         S0      
317GND              VIA   -    MD0100PA00X+135711Y+131136X0193Y         S0      
317GND              VIA   -    MD0100PA00X+135201Y+131136X0193Y         S0      
317GND              VIA   -    MD0100PA00X+134941Y+131136X0193Y         S0      
317GND              VIA   -    MD0100PA00X+134681Y+131136X0193Y         S0      
317GND              VIA   -    MD0100PA00X+135096Y+133924X0200Y         S0      
327GND              PR93  -2          A01X+134837Y+133951X0198Y0197     S1      
317GND              VIA   -    MD0100PA00X+134605Y+132682X0193Y         S0      
317GND              VIA   -    MD0100PA00X+134605Y+132122X0193Y         S0      
317GND              VIA   -    MD0100PA00X+134941Y+131742X0193Y         S0      
317GND              VIA   -    MD0100PA00X+135201Y+131742X0193Y         S0      
317GND              VIA   -    MD0100PA00X+135091Y+132682X0193Y         S0      
317GND              VIA   -    MD0100PA00X+134848Y+132682X0193Y         S0      
327GND              PU16  -40  M      A01X+134848Y+132401X0690Y0770     S1      
317GND              VIA   -    MD0100PA00X+136050Y+131736X0193Y         S0      
317GND              VIA   -    MD0100PA00X+135955Y+131138X0193Y         S0      
317GND              VIA   -    MD0100PA00X+136582Y+130362X0200Y         S0      
317GND              VIA   -    MD0100PA00X+136322Y+130362X0200Y         S0      
317GND              VIA   -    MD0100PA00X+136322Y+130622X0200Y         S0      
317GND              VIA   -    MD0100PA00X+136582Y+130622X0200Y         S0      
317GND              VIA   -    MD0100PA00X+136457Y+131132X0200Y         S0      
317GND              VIA   -    MD0100PA00X+136322Y+130882X0200Y         S0      
317GND              VIA   -    MD0100PA00X+136830Y+130984X0200Y         S0      
317GND              VIA   -    MD0100PA00X+136582Y+130882X0200Y         S0      
317GND              VIA   -    MD0100PA00X+136050Y+131441X0193Y         S0      
327GND              PU16  -7_9-M      A01X+135193Y+131447X0827Y2126R090 S1      
317GND              VIA   -    MD0100PA00X+136183Y+129181X0200Y         S0      
317GND              VIA   -    MD0100PA00X+136449Y+129369X0200Y         S0      
317GND              VIA   -    MD0100PA00X+137142Y+135902X0200Y         S0      
327GND              PC111_-2          A01X+137391Y+135902X0198Y0197R090 S1      
317GND              VIA   -    MD0100PA00X+137863Y+134615X0193Y         S0      
317GND              VIA   -    MD0100PA00X+138349Y+134615X0193Y         S0      
317GND              VIA   -    MD0100PA00X+138106Y+134615X0193Y         S0      
317GND              VIA   -    MD0100PA00X+138354Y+135857X0200Y         S0      
327GND              PR7   -2          A01X+138095Y+135884X0198Y0197     S1      
317GND              VIA   -    MD0100PA00X+137679Y+133380X0193Y         S0      
317GND              VIA   -    MD0100PA00X+137679Y+133069X0193Y         S0      
317GND              VIA   -    MD0100PA00X+137863Y+134055X0193Y         S0      
317GND              VIA   -    MD0100PA00X+138459Y+133380X0193Y         S0      
317GND              VIA   -    MD0100PA00X+138459Y+133069X0193Y         S0      
317GND              VIA   -    MD0100PA00X+138199Y+133380X0193Y         S0      
317GND              VIA   -    MD0100PA00X+138199Y+133069X0193Y         S0      
317GND              VIA   -    MD0100PA00X+137939Y+133380X0193Y         S0      
317GND              VIA   -    MD0100PA00X+137939Y+133069X0193Y         S0      
317GND              VIA   -    MD0100PA00X+138719Y+133069X0193Y         S0      
317GND              VIA   -    MD0100PA00X+138459Y+133675X0193Y         S0      
317GND              VIA   -    MD0100PA00X+138199Y+133675X0193Y         S0      
317GND              VIA   -    MD0100PA00X+138106Y+134055X0193Y         S0      
317GND              VIA   -    MD0100PA00X+138349Y+134055X0193Y         S0      
327GND              PU11  -40  M      A01X+138107Y+134334X0690Y0770     S1      
317GND              VIA   -    MD0100PA00X+139308Y+133669X0193Y         S0      
317GND              VIA   -    MD0100PA00X+139308Y+133374X0193Y         S0      
317GND              VIA   -    MD0100PA00X+139890Y+132295X0200Y         S0      
317GND              VIA   -    MD0100PA00X+139630Y+132295X0200Y         S0      
317GND              VIA   -    MD0100PA00X+139890Y+132555X0200Y         S0      
317GND              VIA   -    MD0100PA00X+139890Y+132815X0200Y         S0      
317GND              VIA   -    MD0100PA00X+139630Y+132555X0200Y         S0      
317GND              VIA   -    MD0100PA00X+139630Y+132815X0200Y         S0      
317GND              VIA   -    MD0100PA00X+139924Y+131198X0200Y         S0      
317GND              VIA   -    MD0100PA00X+140174Y+131198X0200Y         S0      
317GND              VIA   -    MD0100PA00X+139213Y+133071X0193Y         S0      
317GND              VIA   -    MD0100PA00X+138969Y+133069X0193Y         S0      
327GND              PU11  -7_9-M      A01X+138451Y+133380X0827Y2126R090 S1      
317GND              VIA   -    MD0100PA00X+139765Y+133065X0200Y         S0      
317GND              VIA   -    MD0100PA00X+140141Y+133492X0200Y         S0      
317GND              VIA   -    MD0100PA00X+140572Y+131062X0200Y         S0      
317GND              VIA   -    MD0100PA00X+140661Y+128261X0200Y    R180 S0      
327GND              PC99  -2          A01X+140369Y+128619X0198Y0197R270 S1      
327GND              PR49  -2   M      A01X+140762Y+128576X0198Y0197R180 S1      
317GND              VIA   -    MD0100PA00X+140869Y+132480X0200Y         S0      
317GND              VIA   -    MD0100PA00X+141169Y+132480X0200Y         S0      
317GND              VIA   -    MD0100PA00X+141469Y+132480X0200Y         S0      
317GND              VIA   -    MD0100PA00X+141769Y+132480X0200Y         S0      
317GND              VIA   -    MD0100PA00X+142069Y+132480X0200Y         S0      
317GND              VIA   -    MD0100PA00X+137215Y+133489X0193Y         S0      
317GND              VIA   -    MD0100PA00X+133943Y+131557X0200Y         S0      
317GND              VIA   -    MD0100PA00X+130680Y+131544X0200Y         S0      
317GND              VIA   -    MD0100PA00X+127387Y+131530X0200Y         S0      
317GND              VIA   -    MD0100PA00X+124090Y+131546X0200Y         S0      
317GND              VIA   -    MD0100PA00X+120299Y+136149X0193Y         S0      
317GND              VIA   -    MD0100PA00X+117014Y+136180X0193Y         S0      
317GND              PC101 -2   MD0400PA00X+129115Y+138556X0600Y    R180 S3      
317GND              PC104 -2   MD0400PA00X+132052Y+138556X0600Y    R180 S3      
317GND              VIA   -    MD0100PA00X+110445Y+136168X0193Y         S0      
317GND              VIA   -    MD0100PA00X+107191Y+136166X0193Y         S0      
317GND              VIA   -    MD0100PA00X+113722Y+136166X0193Y         S0      
317GND              J1    -G3  MD0480PA00X+120204Y+127770X0680Y1370R090 S3      
317GND              J15   -G3  MD0480PA00X+117234Y+127770X0680Y1370R090 S3      
317GND              J19   -G3  MD0480PA00X+111294Y+127770X0680Y1370R090 S3      
317GND              J17   -G3  MD0480PA00X+114264Y+127770X0680Y1370R090 S3      
317GND              J21   -G3  MD0480PA00X+108324Y+127770X0680Y1370R090 S3      
317GND              J23   -G3  MD0480PA00X+105354Y+127770X0680Y1370R090 S3      
317GND              VIA   -    M      A01X+164834Y+145131X0200Y    R090 S2      
017GND              VIA   -    M      A18X+164834Y+145131X0260Y    R090 S2      
017GND                    -    MD0100PA00X+164834Y+145131                       
327GND              PC207_-2          A01X+168596Y+139970X0198Y0197     S1      
327GND              PC9   -2          A01X+169007Y+140314X0198Y0197R090 S1      
317GND              VIA   -    MD0100PA00X+168596Y+140219X0200Y         S0      
317GND              VIA   -    MD0100PA00X+168762Y+140414X0200Y         S0      
327GND              PU23  -2   M      A01X+169122Y+138963X0090Y0240R090 S1      
327GND              PC204 -2          A01X+168617Y+139451X0198Y0197R090 S1      
327GND              PC203 -2          A01X+165339Y+139441X0198Y0197R090 S1      
327GND              PU22  -2   M      A01X+165844Y+138953X0090Y0240R090 S1      
327GND              PC210_-2          A01X+171507Y+138122X0198Y0197R270 S1      
327GND              PC208_-2          A01X+171895Y+138122X0198Y0197R270 S1      
327GND              PR389 -2          A01X+168620Y+137719X0198Y0197R090 S1      
327GND              PU23  -5          A01X+169122Y+138431X0090Y0240R090 S1      
327GND              PC209_-2          A01X+168229Y+138112X0198Y0197R270 S1      
327GND              PC206_-2          A01X+168617Y+138086X0198Y0197R270 S1      
327GND              PR482 -2          A01X+165341Y+137709X0198Y0197R090 S1      
327GND              PU22  -5          A01X+165844Y+138421X0090Y0240R090 S1      
327GND              PC205_-2          A01X+165339Y+138076X0198Y0197R270 S1      
327GND              PU21  -31         A01X+165873Y+141845X0070Y0240R270 S1      
327GND              PU21  -32         A01X+165873Y+142003X0070Y0240R270 S1      
327GND              PU21  -18         A01X+163983Y+142160X0070Y0240R270 S1      
327GND              PU21  -17         A01X+163983Y+142318X0070Y0240R270 S1      
327GND              PU21  -20         A01X+163983Y+141845X0070Y0240R270 S1      
327GND              PC222 -2          A01X+164180Y+130799X0198Y0197R270 S1      
327GND              PR115 -2          A01X+163791Y+130687X0198Y0197     S1      
327GND              PC801 -2          A01X+172767Y+130093X0630Y1190     S1      
327GND              PC229 -2          A01X+170387Y+130093X0630Y1190     S1      
327GND              PC230 -2          A01X+167987Y+130093X0630Y1190     S1      
327GND              PC228 -2          A01X+165587Y+130093X0630Y1190     S1      
327GND              PC215_-2          A18X+167263Y+140064X0400Y0500R090 S2      
327GND              PR36  -2          A01X+166842Y+140665X0198Y0197R270 S1      
327GND              PR419 -2          A01X+166442Y+140665X0198Y0197R270 S1      
327GND              PR37  -2          A01X+164902Y+140665X0198Y0197R270 S1      
327GND              PR33  -2          A01X+165302Y+140665X0198Y0197R270 S1      
327GND              PR34  -2          A01X+165682Y+140665X0198Y0197R270 S1      
327GND              PR35  -2          A01X+166062Y+140665X0198Y0197R270 S1      
327GND              PC219_-2          A01X+167326Y+141169X0400Y0500     S1      
327GND              PC216_-2          A18X+170565Y+140074X0400Y0500R090 S2      
317GND              VIA   -    MD0100PA00X+162718Y+144802X0200Y    R270 S0      
317GND              VIA   -    MD0100PA00X+162724Y+143615X0200Y    R270 S0      
327GND              C197  -2          A01X+162965Y+143225X0198Y0197R180 S1      
327GND              C196  -2   M      A01X+162965Y+143615X0198Y0197R180 S1      
317GND              VIA   -    MD0100PA00X+162705Y+142472X0200Y         S0      
327GND              PR127 -2          A18X+162983Y+142452X0198Y0197R270 S2      
317GND              VIA   -    MD0100PA00X+164328Y+143154X0200Y    R180 S0      
317GND              VIA   -    MD0100PA00X+164318Y+141944X0200Y    R180 S0      
317GND              VIA   -    MD0100PA00X+164328Y+142554X0200Y    R090 S0      
317GND              VIA   -    MD0100PA00X+164190Y+134857X0200Y         S0      
317GND              VIA   -    MD0100PA00X+164190Y+135147X0200Y         S0      
317GND              VIA   -    MD0100PA00X+164886Y+140342X0200Y         S0      
317GND              VIA   -    MD0100PA00X+165477Y+140262X0200Y         S0      
327GND              PC201_-2          A01X+165728Y+140304X0198Y0197R090 S1      
317GND              VIA   -    MD0100PA00X+166201Y+139017X0193Y         S0      
317GND              VIA   -    MD0100PA00X+165130Y+137876X0193Y         S0      
317GND              VIA   -    MD0100PA00X+166017Y+137471X0193Y         S0      
317GND              VIA   -    MD0100PA00X+166277Y+137471X0193Y         S0      
317GND              VIA   -    MD0100PA00X+166017Y+137781X0193Y         S0      
317GND              VIA   -    MD0100PA00X+166277Y+137781X0193Y         S0      
317GND              VIA   -    MD0100PA00X+166201Y+138457X0193Y         S0      
317GND              VIA   -    MD0100PA00X+165890Y+134857X0200Y         S0      
317GND              VIA   -    MD0100PA00X+165890Y+135147X0200Y         S0      
317GND              VIA   -    MD0100PA00X+165018Y+134857X0200Y         S0      
317GND              VIA   -    MD0100PA00X+165018Y+135147X0200Y         S0      
317GND              VIA   -    MD0100PA00X+165119Y+130134X0200Y         S0      
317GND              VIA   -    MD0100PA00X+165119Y+130654X0200Y         S0      
317GND              VIA   -    MD0100PA00X+165119Y+130394X0200Y         S0      
317GND              VIA   -    MD0100PA00X+166059Y+130134X0200Y         S0      
317GND              VIA   -    MD0100PA00X+166059Y+130654X0200Y         S0      
317GND              VIA   -    MD0100PA00X+166059Y+130394X0200Y         S0      
317GND              VIA   -    MD0100PA00X+165119Y+129874X0200Y         S0      
317GND              VIA   -    MD0100PA00X+166059Y+129874X0200Y         S0      
317GND              VIA   -    MD0100PA00X+165596Y+144512X0200Y    R180 S0      
327GND              PC199 -2          A01X+165817Y+144332X0198Y0197R090 S1      
327GND              PC202_-2          A01X+165367Y+144332X0198Y0197R090 S1      
317GND              VIA   -    MD0100PA00X+166246Y+144436X0200Y         S0      
317GND              VIA   -    MD0100PA00X+165538Y+141944X0200Y    R180 S0      
317GND              VIA   -    MD0100PA00X+165538Y+143154X0200Y    R180 S0      
317GND              VIA   -    MD0100PA00X+164928Y+143154X0200Y    R180 S0      
317GND              VIA   -    MD0100PA00X+164928Y+141944X0200Y    R180 S0      
317GND              VIA   -    MD0100PA00X+165538Y+142554X0200Y    R090 S0      
327GND              PU21  -TH  M      A01X+164928Y+142554X1440Y1440R270 S1      
317GND              VIA   -    MD0100PA00X+167519Y+130134X0200Y         S0      
317GND              VIA   -    MD0100PA00X+167519Y+130654X0200Y         S0      
317GND              VIA   -    MD0100PA00X+167519Y+130394X0200Y         S0      
317GND              VIA   -    MD0100PA00X+167519Y+129874X0200Y         S0      
317GND              VIA   -    MD0100PA00X+167307Y+137471X0193Y         S0      
317GND              VIA   -    MD0100PA00X+166797Y+138077X0193Y         S0      
317GND              VIA   -    MD0100PA00X+166797Y+137781X0193Y         S0      
317GND              VIA   -    MD0100PA00X+166537Y+137471X0193Y         S0      
317GND              VIA   -    MD0100PA00X+166537Y+138077X0193Y         S0      
317GND              VIA   -    MD0100PA00X+166537Y+137781X0193Y         S0      
317GND              VIA   -    MD0100PA00X+167057Y+137471X0193Y         S0      
317GND              VIA   -    MD0100PA00X+166797Y+137471X0193Y         S0      
317GND              VIA   -    MD0100PA00X+167551Y+137472X0193Y         S0      
317GND              VIA   -    MD0100PA00X+166444Y+138457X0193Y         S0      
317GND              VIA   -    MD0100PA00X+166687Y+138457X0193Y         S0      
317GND              VIA   -    MD0100PA00X+167590Y+138055X0193Y         S0      
317GND              VIA   -    MD0100PA00X+167590Y+137759X0193Y         S0      
327GND              PU22  -7_9-M      A01X+166789Y+137781X0827Y2126R090 S1      
317GND              VIA   -    MD0100PA00X+167483Y+134837X0200Y         S0      
317GND              VIA   -    MD0100PA00X+167483Y+135127X0200Y         S0      
317GND              VIA   -    MD0100PA00X+166629Y+144439X0200Y         S0      
327GND              PC4   -2          A01X+166629Y+144178X0198Y0197R090 S1      
317GND              VIA   -    MD0100PA00X+167227Y+142057X0200Y         S0      
327GND              PC198 -2          A01X+166940Y+142448X0198Y0197     S1      
327GND              PR126 -2   M      A01X+166942Y+142057X0198Y0197     S1      
327GND              PC5   -2          A01X+166933Y+143222X0198Y0197     S1      
327GND              PC193 -2   M      A01X+166936Y+142834X0198Y0197     S1      
317GND              VIA   -    MD0100PA00X+167291Y+142993X0200Y         S0      
317GND              VIA   -    MD0100PA00X+167478Y+140769X0200Y         S0      
317GND              VIA   -    MD0100PA00X+167228Y+140769X0200Y         S0      
317GND              VIA   -    MD0100PA00X+167107Y+140542X0200Y         S0      
317GND              VIA   -    MD0100PA00X+166692Y+140258X0200Y         S0      
327GND              PR133 -1          A01X+166433Y+140286X0198Y0197R180 S1      
317GND              VIA   -    MD0100PA00X+166444Y+139017X0193Y         S0      
317GND              VIA   -    MD0100PA00X+166687Y+139017X0193Y         S0      
327GND              PU22  -40  M      A01X+166444Y+138736X0690Y0770     S1      
317GND              VIA   -    MD0100PA00X+168471Y+130104X0200Y         S0      
317GND              VIA   -    MD0100PA00X+168471Y+130624X0200Y         S0      
317GND              VIA   -    MD0100PA00X+168471Y+130364X0200Y         S0      
317GND              VIA   -    MD0100PA00X+168471Y+129844X0200Y         S0      
317GND              VIA   -    MD0100PA00X+168053Y+137467X0200Y         S0      
317GND              VIA   -    MD0100PA00X+169295Y+137481X0193Y         S0      
317GND              VIA   -    MD0100PA00X+169295Y+137791X0193Y         S0      
317GND              VIA   -    MD0100PA00X+168390Y+137876X0193Y         S0      
317GND              VIA   -    MD0100PA00X+167918Y+136957X0200Y         S0      
317GND              VIA   -    MD0100PA00X+168178Y+136957X0200Y         S0      
317GND              VIA   -    MD0100PA00X+168178Y+136697X0200Y         S0      
317GND              VIA   -    MD0100PA00X+167918Y+136697X0200Y         S0      
317GND              VIA   -    MD0100PA00X+168178Y+137217X0200Y         S0      
317GND              VIA   -    MD0100PA00X+167918Y+137217X0200Y         S0      
317GND              VIA   -    MD0100PA00X+167913Y+134852X0200Y         S0      
317GND              VIA   -    MD0100PA00X+168723Y+134842X0200Y         S0      
317GND              VIA   -    MD0100PA00X+167913Y+135142X0200Y         S0      
317GND              VIA   -    MD0100PA00X+168723Y+135132X0200Y         S0      
317GND              VIA   -    MD0100PA00X+168736Y+144027X0200Y    R180 S0      
317GND              VIA   -    MD0100PA00X+168468Y+144026X0200Y    R180 S0      
317GND              VIA   -    MD0100PA00X+169722Y+138467X0193Y         S0      
317GND              VIA   -    MD0100PA00X+169965Y+138467X0193Y         S0      
317GND              VIA   -    MD0100PA00X+169553Y+134842X0200Y         S0      
317GND              VIA   -    MD0100PA00X+169553Y+135132X0200Y         S0      
317GND              VIA   -    MD0100PA00X+169909Y+130104X0200Y         S0      
317GND              VIA   -    MD0100PA00X+169909Y+130624X0200Y         S0      
317GND              VIA   -    MD0100PA00X+169909Y+130364X0200Y         S0      
317GND              VIA   -    MD0100PA00X+169909Y+129844X0200Y         S0      
317GND              VIA   -    MD0100PA00X+169970Y+140268X0200Y         S0      
327GND              PR134 -1          A01X+169711Y+140296X0198Y0197R180 S1      
317GND              VIA   -    MD0100PA00X+169722Y+139027X0193Y         S0      
317GND              VIA   -    MD0100PA00X+169479Y+139027X0193Y         S0      
317GND              VIA   -    MD0100PA00X+169965Y+139027X0193Y         S0      
317GND              VIA   -    MD0100PA00X+169815Y+137481X0193Y         S0      
317GND              VIA   -    MD0100PA00X+169555Y+137481X0193Y         S0      
317GND              VIA   -    MD0100PA00X+169815Y+138087X0193Y         S0      
317GND              VIA   -    MD0100PA00X+169555Y+137791X0193Y         S0      
317GND              VIA   -    MD0100PA00X+169815Y+137791X0193Y         S0      
317GND              VIA   -    MD0100PA00X+170585Y+137481X0193Y         S0      
317GND              VIA   -    MD0100PA00X+170335Y+137481X0193Y         S0      
317GND              VIA   -    MD0100PA00X+170075Y+137481X0193Y         S0      
317GND              VIA   -    MD0100PA00X+170075Y+138087X0193Y         S0      
317GND              VIA   -    MD0100PA00X+170075Y+137791X0193Y         S0      
317GND              VIA   -    MD0100PA00X+169479Y+138467X0193Y         S0      
327GND              PU23  -40  M      A01X+169723Y+138746X0690Y0770     S1      
317GND              VIA   -    MD0100PA00X+170875Y+130619X0200Y         S0      
317GND              VIA   -    MD0100PA00X+170875Y+130359X0200Y         S0      
317GND              VIA   -    MD0100PA00X+170875Y+129839X0200Y         S0      
317GND              VIA   -    MD0100PA00X+170829Y+137482X0193Y         S0      
317GND              VIA   -    MD0100PA00X+171331Y+137477X0200Y         S0      
317GND              VIA   -    MD0100PA00X+171627Y+137518X0200Y         S0      
317GND              VIA   -    MD0100PA00X+170868Y+137766X0193Y         S0      
317GND              VIA   -    MD0100PA00X+170868Y+138062X0193Y         S0      
327GND              PU23  -7_9-M      A01X+170067Y+137791X0827Y2126R090 S1      
317GND              VIA   -    MD0100PA00X+171990Y+136341X0200Y         S0      
317GND              VIA   -    MD0100PA00X+171990Y+136591X0200Y         S0      
317GND              VIA   -    MD0100PA00X+171990Y+136851X0200Y         S0      
317GND              VIA   -    MD0100PA00X+171456Y+136967X0200Y         S0      
317GND              VIA   -    MD0100PA00X+171196Y+136967X0200Y         S0      
317GND              VIA   -    MD0100PA00X+171456Y+136707X0200Y         S0      
317GND              VIA   -    MD0100PA00X+171196Y+136707X0200Y         S0      
317GND              VIA   -    MD0100PA00X+170953Y+134862X0200Y         S0      
317GND              VIA   -    MD0100PA00X+170953Y+135152X0200Y         S0      
317GND              VIA   -    MD0100PA00X+172175Y+130209X0200Y         S0      
317GND              VIA   -    MD0100PA00X+170875Y+130099X0200Y         S0      
317GND              VIA   -    MD0100PA00X+172175Y+130469X0200Y         S0      
317GND              VIA   -    MD0100PA00X+172392Y+137718X0200Y         S0      
317GND              VIA   -    MD0100PA00X+172392Y+138052X0200Y         S0      
317GND              VIA   -    MD0100PA00X+173520Y+136318X0200Y         S0      
317GND              VIA   -    MD0100PA00X+173520Y+136568X0200Y         S0      
317GND              VIA   -    MD0100PA00X+173520Y+136828X0200Y         S0      
317GND              VIA   -    MD0100PA00X+174307Y+143221X0200Y         S0      
327GND              PC6003-2          A01X+174307Y+143500X0198Y0197     S1      
317GND              H33   -1   MD1470PA00X+162973Y+138352X2440Y         S3      
317GND              H34   -1   MD1470PA00X+173997Y+138353X2440Y         S3      
327GND              PC200 -2          A01X+166246Y+144175X0198Y0197R090 S1      
327GND              C5009 -2          A01X+162959Y+144802X0198Y0197R180 S1      
317GND              VIA   -    MD0100PA00X+159914Y+140046X0200Y         S0      
327GND              R6125 -2   M      A18X+159767Y+139701X0198Y0197R270 S2      
327GND              R6126 -2   M      A18X+158810Y+139701X0198Y0197R270 S2      
327GND              R6127 -2   M      A18X+159279Y+139701X0198Y0197R270 S2      
327GND              R6129 -2          A18X+157860Y+139701X0198Y0197R270 S2      
327GND              R6128 -2   M      A18X+158341Y+139701X0198Y0197R270 S2      
317GND              VIA   -    MD0100PA00X+136830Y+130734X0200Y         S0      
317GND              VIA   -    MD0100PA00X+171881Y+135135X0200Y         S0      
317GND              VIA   -    MD0100PA00X+171881Y+134845X0200Y         S0      
317GND              VIA   -    MD0100PA00X+172185Y+130730X0200Y         S0      
317GND              VIA   -    MD0100PA00X+172175Y+129949X0200Y         S0      
317GND              VIA   -    MD0100PA00X+173262Y+130492X0200Y         S0      
317GND              VIA   -    MD0100PA00X+173262Y+130232X0200Y         S0      
317GND              VIA   -    MD0100PA00X+173272Y+130753X0200Y         S0      
317GND              VIA   -    MD0100PA00X+173262Y+129972X0200Y         S0      
327GND              VIA   -           A18X+141363Y+139358X0260Y    R270 S2      
327GND              VIA   -           A18X+141199Y+137114X0260Y    R270 S2      
327GND              VIA   -           A18X+141633Y+136228X0260Y    R270 S2      
327GND              VIA   -           A18X+142699Y+139114X0260Y    R270 S2      
327GND              VIA   -           A18X+141653Y+131310X0260Y         S2      
317GND              PC164 -2   MD0400PA00X+116654Y+142232X0600Y    R180 S3      
317GND              PC220 -2   MD0400PA00X+170084Y+143436X0600Y    R180 S3      
317GND              VIA   -    MD0100PA00X+103564Y+077358X0200Y         S0      
317GND              VIA   -    MD0100PA00X+102549Y+076872X0200Y         S0      
317GND              VIA   -    MD0100PA00X+100759Y+076998X0200Y    R180 S0      
317GND              VIA   -    MD0100PA00X+100759Y+076748X0200Y    R180 S0      
317GND              VIA   -    MD0100PA00X+080041Y+076727X0190Y         S0      
327GND              R778  -2          A18X+080041Y+076727X0198Y0197R180 S2      
317GND              VIA   -    MD0100PA00X+080745Y+076376X0190Y    R180 S0      
327GND              C180  -2          A18X+081032Y+076376X0198Y0197     S2      
317GND              VIA   -    MD0100PA00X+077790Y+076377X0190Y         S0      
327GND              C176  -2          A18X+077790Y+076377X0198Y0197     S2      
317GND              VIA   -    MD0100PA00X+077071Y+076727X0190Y         S0      
327GND              R777  -2          A18X+077071Y+076727X0198Y0197R180 S2      
317GND              VIA   -    MD0100PA00X+074805Y+076377X0190Y         S0      
327GND              C172  -2          A18X+074805Y+076377X0198Y0197     S2      
317GND              VIA   -    MD0100PA00X+074101Y+076727X0190Y         S0      
327GND              R776  -2          A18X+074101Y+076727X0198Y0197R180 S2      
317GND              VIA   -    MD0100PA00X+071131Y+076727X0190Y         S0      
327GND              R775  -2          A18X+071131Y+076727X0198Y0197R180 S2      
317GND              VIA   -    MD0100PA00X+071835Y+076377X0190Y         S0      
327GND              C168  -2          A18X+071835Y+076377X0198Y0197     S2      
317GND              VIA   -    MD0100PA00X+068160Y+076727X0190Y         S0      
327GND              R774  -2          A18X+068160Y+076727X0198Y0197R180 S2      
317GND              VIA   -    MD0100PA00X+068865Y+076377X0190Y         S0      
327GND              C164  -2          A18X+068865Y+076377X0198Y0197     S2      
317GND              VIA   -    MD0100PA00X+065190Y+076727X0190Y         S0      
327GND              R37   -2          A18X+065190Y+076727X0198Y0197R180 S2      
317GND              VIA   -    MD0100PA00X+065895Y+076377X0190Y         S0      
327GND              C160  -2          A18X+065895Y+076377X0198Y0197     S2      
327GND              PC136_-2          A01X+039778Y+135904X0198Y0197R090 S1      
317GND              J32   -G3  MD0480PA00X+010710Y+127770X0680Y1370R090 S3      
317GND              J30   -G3  MD0480PA00X+013680Y+127770X0680Y1370R090 S3      
317GND              J28   -G3  MD0480PA00X+016650Y+127770X0680Y1370R090 S3      
317GND              J26   -G3  MD0480PA00X+019620Y+127770X0680Y1370R090 S3      
317GND              J24   -G3  MD0480PA00X+022590Y+127770X0680Y1370R090 S3      
317GND              J33   -G3  MD0480PA00X+007739Y+127770X0680Y1370R090 S3      
317GND              VIA   -    MD0100PA00X+039291Y+131788X0200Y         S0      
317GND              VIA   -    MD0100PA00X+039295Y+131528X0200Y         S0      
317GND              H21   -1   MD1470PA00X+044376Y+133982X2440Y         S3      
317GND              H13   -1   MD1470PA00X+027644Y+135754X2440Y         S3      
327GND              PL39  -2   M      A01X+043870Y+131903X0790Y1660R090 S1      
317GND              VIA   -    MD0100PA00X+044456Y+132162X0200Y         S0      
317GND              VIA   -    MD0100PA00X+044156Y+132162X0200Y         S0      
327GND              PC392 -2   M      A01X+042725Y+128927X0198Y0197R090 S1      
327GND              PR226 -2          A01X+043118Y+128969X0198Y0197R180 S1      
317GND              VIA   -    MD0100PA00X+042725Y+129175X0200Y    R180 S0      
317GND              VIA   -    MD0100PA00X+043183Y+131124X0200Y         S0      
317GND              VIA   -    MD0100PA00X+043556Y+132162X0200Y         S0      
317GND              VIA   -    MD0100PA00X+043256Y+132162X0200Y         S0      
317GND              VIA   -    MD0100PA00X+043856Y+132162X0200Y         S0      
317GND              VIA   -    MD0100PA00X+042102Y+133067X0200Y         S0      
327GND              PU33  -7_9-M      A01X+040838Y+133382X0827Y2126R090 S1      
317GND              VIA   -    MD0100PA00X+041356Y+133071X0193Y         S0      
317GND              VIA   -    MD0100PA00X+041600Y+133072X0193Y         S0      
317GND              VIA   -    MD0100PA00X+041106Y+133071X0193Y         S0      
317GND              VIA   -    MD0100PA00X+042433Y+133145X0200Y         S0      
317GND              VIA   -    MD0100PA00X+042109Y+131122X0200Y         S0      
317GND              VIA   -    MD0100PA00X+042352Y+131197X0200Y         S0      
317GND              VIA   -    MD0100PA00X+042227Y+132817X0200Y         S0      
317GND              VIA   -    MD0100PA00X+042227Y+132557X0200Y         S0      
317GND              VIA   -    MD0100PA00X+042227Y+132297X0200Y         S0      
317GND              VIA   -    MD0100PA00X+041967Y+132817X0200Y         S0      
317GND              VIA   -    MD0100PA00X+041967Y+132297X0200Y         S0      
317GND              VIA   -    MD0100PA00X+041967Y+132557X0200Y         S0      
317GND              VIA   -    MD0100PA00X+041695Y+133376X0193Y         S0      
317GND              VIA   -    MD0100PA00X+041695Y+133671X0193Y         S0      
327GND              PU33  -40  M      A01X+040494Y+134336X0690Y0770     S1      
317GND              VIA   -    MD0100PA00X+040493Y+134057X0193Y         S0      
317GND              VIA   -    MD0100PA00X+040736Y+134057X0193Y         S0      
317GND              VIA   -    MD0100PA00X+040250Y+134057X0193Y         S0      
317GND              VIA   -    MD0100PA00X+040586Y+133677X0193Y         S0      
317GND              VIA   -    MD0100PA00X+040846Y+133677X0193Y         S0      
317GND              VIA   -    MD0100PA00X+040066Y+133382X0193Y         S0      
317GND              VIA   -    MD0100PA00X+040326Y+133382X0193Y         S0      
317GND              VIA   -    MD0100PA00X+040586Y+133382X0193Y         S0      
317GND              VIA   -    MD0100PA00X+040846Y+133382X0193Y         S0      
317GND              VIA   -    MD0100PA00X+040326Y+133071X0193Y         S0      
317GND              VIA   -    MD0100PA00X+040066Y+133071X0193Y         S0      
317GND              VIA   -    MD0100PA00X+040586Y+133071X0193Y         S0      
317GND              VIA   -    MD0100PA00X+040846Y+133071X0193Y         S0      
317GND              VIA   -    MD0100PA00X+039613Y+133472X0193Y         S0      
317GND              VIA   -    MD0100PA00X+040250Y+134617X0193Y         S0      
317GND              VIA   -    MD0100PA00X+040493Y+134617X0193Y         S0      
317GND              VIA   -    MD0100PA00X+040736Y+134617X0193Y         S0      
327GND              PR426 -2          A01X+040482Y+135886X0198Y0197     S1      
317GND              VIA   -    MD0100PA00X+040741Y+135859X0200Y         S0      
317GND              VIA   -    M      A01X+039527Y+135862X0200Y         S2      
017GND              VIA   -    M      A18X+039527Y+135862X0260Y         S2      
017GND                    -    MD0100PA00X+039527Y+135862                       
317GND              VIA   -    MD0100PA00X+038570Y+129183X0200Y         S0      
317GND              VIA   -    MD0100PA00X+038836Y+129371X0200Y         S0      
327GND              PU38  -7_9-M      A01X+037580Y+131448X0827Y2126R090 S1      
317GND              VIA   -    MD0100PA00X+038437Y+131442X0193Y         S0      
317GND              VIA   -    MD0100PA00X+038844Y+131134X0200Y         S0      
317GND              VIA   -    MD0100PA00X+038342Y+131139X0193Y         S0      
317GND              VIA   -    MD0100PA00X+038709Y+130364X0200Y         S0      
317GND              VIA   -    MD0100PA00X+038969Y+130364X0200Y         S0      
317GND              VIA   -    MD0100PA00X+038709Y+130884X0200Y         S0      
317GND              VIA   -    MD0100PA00X+038709Y+130624X0200Y         S0      
317GND              VIA   -    MD0100PA00X+038969Y+130884X0200Y         S0      
317GND              VIA   -    MD0100PA00X+038969Y+130624X0200Y         S0      
317GND              VIA   -    MD0100PA00X+039495Y+131126X0200Y         S0      
317GND              VIA   -    MD0100PA00X+039218Y+130986X0200Y         S0      
317GND              VIA   -    MD0100PA00X+038437Y+131738X0193Y         S0      
317GND              VIA   -    MD0100PA00X+037328Y+131138X0193Y         S0      
317GND              VIA   -    MD0100PA00X+037068Y+131138X0193Y         S0      
317GND              VIA   -    MD0100PA00X+036808Y+131138X0193Y         S0      
317GND              VIA   -    MD0100PA00X+037328Y+131448X0193Y         S0      
317GND              VIA   -    MD0100PA00X+036808Y+131448X0193Y         S0      
317GND              VIA   -    MD0100PA00X+037068Y+131448X0193Y         S0      
317GND              VIA   -    MD0100PA00X+037588Y+131138X0193Y         S0      
317GND              VIA   -    MD0100PA00X+037848Y+131138X0193Y         S0      
317GND              VIA   -    MD0100PA00X+037588Y+131448X0193Y         S0      
317GND              VIA   -    MD0100PA00X+038098Y+131138X0193Y         S0      
327GND              PU38  -40  M      A01X+037236Y+132403X0690Y0770     S1      
317GND              VIA   -    MD0100PA00X+037235Y+132124X0193Y         S0      
317GND              VIA   -    MD0100PA00X+037478Y+132124X0193Y         S0      
317GND              VIA   -    MD0100PA00X+037328Y+131744X0193Y         S0      
317GND              VIA   -    MD0100PA00X+037478Y+132684X0193Y         S0      
317GND              VIA   -    MD0100PA00X+036992Y+132124X0193Y         S0      
317GND              VIA   -    MD0100PA00X+036992Y+132684X0193Y         S0      
317GND              VIA   -    MD0100PA00X+037235Y+132684X0193Y         S0      
317GND              VIA   -    MD0100PA00X+037588Y+131744X0193Y         S0      
327GND              PR270 -2          A01X+037224Y+133953X0198Y0197     S1      
317GND              VIA   -    MD0100PA00X+037483Y+133926X0200Y         S0      
317GND              VIA   -    MD0100PA00X+036355Y+131539X0193Y         S0      
317GND              VIA   -    MD0100PA00X+035395Y+129188X0200Y         S0      
317GND              VIA   -    MD0100PA00X+035655Y+129188X0200Y         S0      
317GND              VIA   -    MD0100PA00X+036231Y+129197X0200Y         S0      
317GND              VIA   -    MD0100PA00X+035954Y+129192X0200Y         S0      
327GND              PU35  -7_9-M      A01X+034300Y+131428X0827Y2126R090 S1      
317GND              VIA   -    MD0100PA00X+035157Y+131422X0193Y         S0      
317GND              VIA   -    MD0100PA00X+035564Y+131114X0200Y         S0      
317GND              VIA   -    MD0100PA00X+035429Y+130344X0200Y         S0      
317GND              VIA   -    MD0100PA00X+035429Y+130864X0200Y         S0      
317GND              VIA   -    MD0100PA00X+035429Y+130604X0200Y         S0      
317GND              VIA   -    MD0100PA00X+035689Y+130344X0200Y         S0      
317GND              VIA   -    MD0100PA00X+035689Y+130864X0200Y         S0      
317GND              VIA   -    MD0100PA00X+035689Y+130604X0200Y         S0      
317GND              VIA   -    MD0100PA00X+035157Y+131718X0193Y         S0      
317GND              VIA   -    MD0100PA00X+034308Y+131724X0193Y         S0      
317GND              VIA   -    MD0100PA00X+034048Y+131724X0193Y         S0      
327GND              PU35  -40  M      A01X+033956Y+132383X0690Y0770     S1      
317GND              VIA   -    MD0100PA00X+033712Y+132664X0193Y         S0      
317GND              VIA   -    MD0100PA00X+033955Y+132664X0193Y         S0      
317GND              VIA   -    MD0100PA00X+033712Y+132104X0193Y         S0      
317GND              VIA   -    MD0100PA00X+034198Y+132664X0193Y         S0      
327GND              PR255 -2          A01X+033944Y+133933X0198Y0197     S1      
317GND              VIA   -    MD0100PA00X+034203Y+133906X0200Y         S0      
317GND              VIA   -    MD0100PA00X+034308Y+131118X0193Y         S0      
317GND              VIA   -    MD0100PA00X+034568Y+131118X0193Y         S0      
317GND              VIA   -    MD0100PA00X+034308Y+131428X0193Y         S0      
317GND              VIA   -    MD0100PA00X+034818Y+131118X0193Y         S0      
317GND              VIA   -    MD0100PA00X+035062Y+131119X0193Y         S0      
317GND              VIA   -    MD0100PA00X+034048Y+131118X0193Y         S0      
317GND              VIA   -    MD0100PA00X+033788Y+131118X0193Y         S0      
317GND              VIA   -    MD0100PA00X+033788Y+131428X0193Y         S0      
317GND              VIA   -    MD0100PA00X+034048Y+131428X0193Y         S0      
317GND              VIA   -    MD0100PA00X+033955Y+132104X0193Y         S0      
317GND              VIA   -    MD0100PA00X+034198Y+132104X0193Y         S0      
317GND              VIA   -    MD0100PA00X+032676Y+129178X0200Y         S0      
317GND              VIA   -    MD0100PA00X+032222Y+129174X0200Y         S0      
317GND              VIA   -    MD0100PA00X+032947Y+129178X0200Y         S0      
317GND              VIA   -    MD0100PA00X+032274Y+131120X0200Y         S0      
317GND              VIA   -    MD0100PA00X+032399Y+130870X0200Y         S0      
317GND              VIA   -    MD0100PA00X+032399Y+130610X0200Y         S0      
317GND              VIA   -    MD0100PA00X+032399Y+130350X0200Y         S0      
317GND              VIA   -    MD0100PA00X+033528Y+131118X0193Y         S0      
317GND              VIA   -    MD0100PA00X+033528Y+131428X0193Y         S0      
317GND              VIA   -    MD0100PA00X+033075Y+131519X0193Y         S0      
327GND              PU5   -7_9-M      A01X+031010Y+131434X0827Y2126R090 S1      
317GND              VIA   -    MD0100PA00X+031017Y+131730X0193Y         S0      
317GND              VIA   -    MD0100PA00X+030757Y+131730X0193Y         S0      
327GND              PU5   -40  M      A01X+030665Y+132389X0690Y0770     S1      
317GND              VIA   -    MD0100PA00X+030665Y+132670X0193Y         S0      
317GND              VIA   -    MD0100PA00X+030908Y+132670X0193Y         S0      
327GND              PR254 -2          A01X+030654Y+133939X0198Y0197     S1      
317GND              VIA   -    MD0100PA00X+030913Y+133911X0200Y         S0      
317GND              VIA   -    MD0100PA00X+031962Y+129174X0200Y         S0      
317GND              VIA   -    MD0100PA00X+031866Y+131428X0193Y         S0      
317GND              VIA   -    MD0100PA00X+031017Y+131124X0193Y         S0      
317GND              VIA   -    MD0100PA00X+031017Y+131434X0193Y         S0      
317GND              VIA   -    MD0100PA00X+030757Y+131124X0193Y         S0      
317GND              VIA   -    MD0100PA00X+030757Y+131434X0193Y         S0      
317GND              VIA   -    MD0100PA00X+031277Y+131124X0193Y         S0      
317GND              VIA   -    MD0100PA00X+031527Y+131124X0193Y         S0      
317GND              VIA   -    MD0100PA00X+031772Y+131125X0193Y         S0      
317GND              VIA   -    MD0100PA00X+032139Y+130350X0200Y         S0      
317GND              VIA   -    MD0100PA00X+032139Y+130870X0200Y         S0      
317GND              VIA   -    MD0100PA00X+032139Y+130610X0200Y         S0      
317GND              VIA   -    MD0100PA00X+031866Y+131724X0193Y         S0      
317GND              VIA   -    MD0100PA00X+030665Y+132110X0193Y         S0      
317GND              VIA   -    MD0100PA00X+030908Y+132110X0193Y         S0      
317GND              VIA   -    MD0100PA00X+029194Y+129138X0200Y         S0      
317GND              VIA   -    MD0100PA00X+030497Y+131124X0193Y         S0      
317GND              VIA   -    MD0100PA00X+030237Y+131124X0193Y         S0      
317GND              VIA   -    MD0100PA00X+030497Y+131434X0193Y         S0      
317GND              VIA   -    MD0100PA00X+030237Y+131434X0193Y         S0      
317GND              VIA   -    MD0100PA00X+029784Y+131524X0193Y         S0      
317GND              VIA   -    MD0100PA00X+030422Y+132110X0193Y         S0      
317GND              VIA   -    MD0100PA00X+030422Y+132670X0193Y         S0      
317GND              VIA   -    MD0100PA00X+029454Y+129138X0200Y         S0      
327GND              PC408_-2          A01X+028439Y+134270X0198Y0197R180 S1      
317GND              VIA   -    MD0100PA00X+028199Y+134270X0200Y    R180 S0      
327GND              PU37  -7_9-M      A01X+027720Y+131437X0827Y2126R090 S1      
317GND              VIA   -    MD0100PA00X+027728Y+131733X0193Y         S0      
317GND              VIA   -    MD0100PA00X+028132Y+129174X0200Y         S0      
317GND              VIA   -    MD0100PA00X+028392Y+129174X0200Y         S0      
317GND              VIA   -    MD0100PA00X+028577Y+131431X0193Y         S0      
317GND              VIA   -    MD0100PA00X+028984Y+131122X0200Y         S0      
317GND              VIA   -    MD0100PA00X+029109Y+130352X0200Y         S0      
317GND              VIA   -    MD0100PA00X+028849Y+130352X0200Y         S0      
317GND              VIA   -    MD0100PA00X+029109Y+130872X0200Y         S0      
317GND              VIA   -    MD0100PA00X+029109Y+130612X0200Y         S0      
317GND              VIA   -    MD0100PA00X+028849Y+130872X0200Y         S0      
317GND              VIA   -    MD0100PA00X+028849Y+130612X0200Y         S0      
317GND              VIA   -    MD0100PA00X+027728Y+131126X0193Y         S0      
317GND              VIA   -    MD0100PA00X+027728Y+131437X0193Y         S0      
317GND              VIA   -    MD0100PA00X+027988Y+131126X0193Y         S0      
317GND              VIA   -    MD0100PA00X+028238Y+131126X0193Y         S0      
317GND              VIA   -    MD0100PA00X+028482Y+131128X0193Y         S0      
317GND              VIA   -    MD0100PA00X+028577Y+131727X0193Y         S0      
317GND              VIA   -    MD0100PA00X+027409Y+129174X0200Y         S0      
317GND              VIA   -    MD0100PA00X+027149Y+129174X0200Y         S0      
317GND              VIA   -    MD0100PA00X+027468Y+131126X0193Y         S0      
317GND              VIA   -    MD0100PA00X+026948Y+131126X0193Y         S0      
317GND              VIA   -    MD0100PA00X+027208Y+131126X0193Y         S0      
317GND              VIA   -    MD0100PA00X+027468Y+131437X0193Y         S0      
317GND              VIA   -    MD0100PA00X+026948Y+131437X0193Y         S0      
317GND              VIA   -    MD0100PA00X+027208Y+131437X0193Y         S0      
327GND              PU37  -40  M      A01X+027376Y+132392X0690Y0770     S1      
317GND              VIA   -    MD0100PA00X+027375Y+132113X0193Y         S0      
317GND              VIA   -    MD0100PA00X+027618Y+132113X0193Y         S0      
317GND              VIA   -    MD0100PA00X+026495Y+131527X0193Y         S0      
317GND              VIA   -    MD0100PA00X+027468Y+131733X0193Y         S0      
317GND              VIA   -    MD0100PA00X+027375Y+132673X0193Y         S0      
317GND              VIA   -    MD0100PA00X+027618Y+132673X0193Y         S0      
317GND              VIA   -    MD0100PA00X+027132Y+132113X0193Y         S0      
317GND              VIA   -    MD0100PA00X+027132Y+132673X0193Y         S0      
327GND              PC404_-2          A01X+026660Y+133960X0198Y0197R090 S1      
317GND              VIA   -    M      A01X+026408Y+133918X0200Y         S2      
017GND              VIA   -    M      A18X+026408Y+133918X0260Y         S2      
017GND                    -    MD0100PA00X+026408Y+133918                       
327GND              PR263 -2          A01X+027364Y+133942X0198Y0197     S1      
317GND              VIA   -    MD0100PA00X+027623Y+133914X0200Y         S0      
317GND              VIA   -    MD0100PA00X+024772Y+133814X0200Y         S0      
317GND              VIA   -    MD0100PA00X+025807Y+133812X0200Y         S0      
317GND              VIA   -    MD0100PA00X+026067Y+133812X0200Y         S0      
317GND              VIA   -    MD0100PA00X+025489Y+134967X0200Y         S0      
317GND              VIA   -    MD0100PA00X+025749Y+134967X0200Y         S0      
327GND              PU36  -7_9-M      A01X+024360Y+136052X0827Y2126R090 S1      
317GND              VIA   -    MD0100PA00X+024878Y+135741X0193Y         S0      
317GND              VIA   -    MD0100PA00X+025122Y+135742X0193Y         S0      
317GND              VIA   -    MD0100PA00X+025489Y+135487X0200Y         S0      
317GND              VIA   -    MD0100PA00X+025489Y+135227X0200Y         S0      
317GND              VIA   -    MD0100PA00X+025749Y+135487X0200Y         S0      
317GND              VIA   -    MD0100PA00X+025624Y+135737X0200Y         S0      
317GND              VIA   -    MD0100PA00X+025749Y+135227X0200Y         S0      
317GND              VIA   -    MD0100PA00X+025217Y+136046X0193Y         S0      
317GND              VIA   -    MD0100PA00X+025217Y+136341X0193Y         S0      
317GND              VIA   -    MD0100PA00X+023588Y+136052X0193Y         S0      
317GND              VIA   -    MD0100PA00X+023848Y+136052X0193Y         S0      
327GND              PU36  -40  M      A01X+024016Y+137006X0690Y0770     S1      
317GND              VIA   -    MD0100PA00X+023772Y+136727X0193Y         S0      
317GND              VIA   -    MD0100PA00X+023772Y+137287X0193Y         S0      
317GND              VIA   -    MD0100PA00X+024015Y+137287X0193Y         S0      
317GND              VIA   -    MD0100PA00X+024258Y+137287X0193Y         S0      
327GND              PR262 -2          A01X+024004Y+138556X0198Y0197     S1      
317GND              VIA   -    MD0100PA00X+024263Y+138529X0200Y         S0      
317GND              VIA   -    MD0100PA00X+023296Y+132140X0200Y         S0      
317GND              VIA   -    MD0100PA00X+023296Y+132390X0200Y         S0      
317GND              VIA   -    MD0100PA00X+023956Y+133812X0200Y         S0      
317GND              VIA   -    MD0100PA00X+024628Y+135741X0193Y         S0      
317GND              VIA   -    MD0100PA00X+023588Y+135741X0193Y         S0      
317GND              VIA   -    MD0100PA00X+023848Y+135741X0193Y         S0      
317GND              VIA   -    MD0100PA00X+024108Y+135741X0193Y         S0      
317GND              VIA   -    MD0100PA00X+024368Y+135741X0193Y         S0      
317GND              VIA   -    MD0100PA00X+024368Y+136052X0193Y         S0      
317GND              VIA   -    MD0100PA00X+024108Y+136052X0193Y         S0      
317GND              VIA   -    MD0100PA00X+024108Y+136347X0193Y         S0      
317GND              VIA   -    MD0100PA00X+024368Y+136347X0193Y         S0      
317GND              VIA   -    MD0100PA00X+024015Y+136727X0193Y         S0      
317GND              VIA   -    MD0100PA00X+024258Y+136727X0193Y         S0      
317GND              VIA   -    MD0100PA00X+023135Y+136142X0193Y         S0      
317GND              VIA   -    MD0100PA00X+023017Y+132140X0200Y         S0      
317GND              VIA   -    MD0100PA00X+023017Y+132390X0200Y         S0      
317GND              VIA   -    MD0100PA00X+022188Y+132392X0200Y         S0      
317GND              VIA   -    MD0100PA00X+022448Y+132142X0200Y         S0      
317GND              VIA   -    MD0100PA00X+022188Y+132142X0200Y         S0      
317GND              VIA   -    MD0100PA00X+022448Y+132392X0200Y         S0      
317GND              VIA   -    MD0100PA00X+022188Y+132642X0200Y         S0      
317GND              VIA   -    MD0100PA00X+022448Y+132642X0200Y         S0      
317GND              VIA   -    MD0100PA00X+023066Y+133812X0200Y         S0      
317GND              VIA   -    MD0100PA00X+022134Y+133807X0200Y         S0      
317GND              VIA   -    MD0100PA00X+022394Y+133807X0200Y         S0      
317GND              VIA   -    MD0100PA00X+022787Y+133812X0200Y         S0      
317GND              VIA   -    MD0100PA00X+022209Y+134967X0200Y         S0      
317GND              VIA   -    MD0100PA00X+022469Y+134967X0200Y         S0      
327GND              PU39  -7_9-M      A01X+021080Y+136052X0827Y2126R090 S1      
317GND              VIA   -    MD0100PA00X+021842Y+135742X0193Y         S0      
317GND              VIA   -    MD0100PA00X+022209Y+135227X0200Y         S0      
317GND              VIA   -    MD0100PA00X+022209Y+135487X0200Y         S0      
317GND              VIA   -    MD0100PA00X+022344Y+135737X0200Y         S0      
317GND              VIA   -    MD0100PA00X+022469Y+135227X0200Y         S0      
317GND              VIA   -    MD0100PA00X+022469Y+135487X0200Y         S0      
317GND              VIA   -    MD0100PA00X+021937Y+136341X0193Y         S0      
317GND              VIA   -    MD0100PA00X+021937Y+136046X0193Y         S0      
327GND              PU39  -40  M      A01X+020736Y+137006X0690Y0770     S1      
317GND              VIA   -    MD0100PA00X+020978Y+136727X0193Y         S0      
317GND              VIA   -    MD0100PA00X+020308Y+136052X0193Y         S0      
317GND              VIA   -    MD0100PA00X+020568Y+136052X0193Y         S0      
317GND              VIA   -    MD0100PA00X+021088Y+136052X0193Y         S0      
317GND              VIA   -    MD0100PA00X+020828Y+136052X0193Y         S0      
317GND              VIA   -    MD0100PA00X+020828Y+136347X0193Y         S0      
317GND              VIA   -    MD0100PA00X+021088Y+136347X0193Y         S0      
317GND              VIA   -    MD0100PA00X+020735Y+137287X0193Y         S0      
317GND              VIA   -    MD0100PA00X+020492Y+137287X0193Y         S0      
317GND              VIA   -    MD0100PA00X+020492Y+136727X0193Y         S0      
317GND              VIA   -    MD0100PA00X+020978Y+137287X0193Y         S0      
327GND              PR275 -2          A01X+020724Y+138556X0198Y0197     S1      
317GND              VIA   -    MD0100PA00X+020983Y+138529X0200Y         S0      
317GND              VIA   -    MD0100PA00X+020308Y+135741X0193Y         S0      
317GND              VIA   -    MD0100PA00X+020568Y+135741X0193Y         S0      
317GND              VIA   -    MD0100PA00X+021348Y+135741X0193Y         S0      
317GND              VIA   -    MD0100PA00X+020828Y+135741X0193Y         S0      
317GND              VIA   -    MD0100PA00X+021088Y+135741X0193Y         S0      
317GND              VIA   -    MD0100PA00X+021598Y+135741X0193Y         S0      
317GND              VIA   -    MD0100PA00X+020735Y+136727X0193Y         S0      
317GND              VIA   -    MD0100PA00X+019317Y+133790X0200Y         S0      
317GND              VIA   -    MD0100PA00X+019577Y+133790X0200Y         S0      
317GND              VIA   -    MD0100PA00X+019179Y+134967X0200Y         S0      
317GND              VIA   -    MD0100PA00X+018919Y+134967X0200Y         S0      
317GND              VIA   -    MD0100PA00X+019179Y+135227X0200Y         S0      
317GND              VIA   -    MD0100PA00X+019179Y+135487X0200Y         S0      
317GND              VIA   -    MD0100PA00X+018919Y+135227X0200Y         S0      
317GND              VIA   -    MD0100PA00X+018919Y+135487X0200Y         S0      
317GND              VIA   -    MD0100PA00X+019054Y+135737X0200Y         S0      
317GND              VIA   -    MD0100PA00X+019855Y+136142X0193Y         S0      
327GND              PU40  -7_9-M      A01X+017790Y+136052X0827Y2126R090 S1      
317GND              VIA   -    MD0100PA00X+017798Y+136052X0193Y         S0      
317GND              VIA   -    MD0100PA00X+017538Y+136052X0193Y         S0      
317GND              VIA   -    MD0100PA00X+017538Y+136347X0193Y         S0      
317GND              VIA   -    MD0100PA00X+017798Y+136347X0193Y         S0      
327GND              PU40  -40  M      A01X+017446Y+137006X0690Y0770     S1      
317GND              VIA   -    MD0100PA00X+017445Y+137287X0193Y         S0      
317GND              VIA   -    MD0100PA00X+017688Y+137287X0193Y         S0      
317GND              VIA   -    MD0100PA00X+017278Y+136052X0193Y         S0      
327GND              PR274 -2          A01X+017434Y+138556X0198Y0197     S1      
317GND              VIA   -    MD0100PA00X+017693Y+138529X0200Y         S0      
317GND              VIA   -    MD0100PA00X+017408Y+133785X0200Y         S0      
317GND              VIA   -    MD0100PA00X+018310Y+133785X0200Y         S0      
317GND              VIA   -    MD0100PA00X+018570Y+133785X0200Y         S0      
317GND              VIA   -    MD0100PA00X+018058Y+135741X0193Y         S0      
317GND              VIA   -    MD0100PA00X+017798Y+135741X0193Y         S0      
317GND              VIA   -    MD0100PA00X+017538Y+135741X0193Y         S0      
317GND              VIA   -    MD0100PA00X+018552Y+135742X0193Y         S0      
317GND              VIA   -    MD0100PA00X+018308Y+135741X0193Y         S0      
317GND              VIA   -    MD0100PA00X+017278Y+135741X0193Y         S0      
317GND              VIA   -    MD0100PA00X+018647Y+136341X0193Y         S0      
317GND              VIA   -    MD0100PA00X+018647Y+136046X0193Y         S0      
317GND              VIA   -    MD0100PA00X+017445Y+136727X0193Y         S0      
317GND              VIA   -    MD0100PA00X+017688Y+136727X0193Y         S0      
317GND              VIA   -    MD0100PA00X+016565Y+136142X0193Y         S0      
317GND              VIA   -    MD0100PA00X+017018Y+136052X0193Y         S0      
317GND              VIA   -    MD0100PA00X+017202Y+137287X0193Y         S0      
317GND              VIA   -    MD0100PA00X+017202Y+136727X0193Y         S0      
317GND              VIA   -    MD0100PA00X+016188Y+133781X0200Y         S0      
317GND              VIA   -    MD0100PA00X+016448Y+133781X0200Y         S0      
317GND              VIA   -    MD0100PA00X+017148Y+133785X0200Y         S0      
317GND              VIA   -    MD0100PA00X+015909Y+134967X0200Y         S0      
317GND              VIA   -    MD0100PA00X+015909Y+135227X0200Y         S0      
317GND              VIA   -    MD0100PA00X+015784Y+135737X0200Y         S0      
317GND              VIA   -    MD0100PA00X+015909Y+135487X0200Y         S0      
317GND              VIA   -    MD0100PA00X+017018Y+135741X0193Y         S0      
327GND              PR369 -2          A01X+014164Y+138556X0198Y0197     S1      
317GND              VIA   -    MD0100PA00X+014423Y+138529X0200Y         S0      
327GND              PU52  -7_9-M      A01X+014520Y+136052X0827Y2126R090 S1      
317GND              VIA   -    MD0100PA00X+014528Y+136052X0193Y         S0      
317GND              VIA   -    MD0100PA00X+014268Y+136347X0193Y         S0      
317GND              VIA   -    MD0100PA00X+014528Y+136347X0193Y         S0      
317GND              VIA   -    MD0100PA00X+014268Y+136052X0193Y         S0      
327GND              PU52  -40  M      A01X+014176Y+137006X0690Y0770     S1      
317GND              VIA   -    MD0100PA00X+014418Y+137287X0193Y         S0      
317GND              VIA   -    MD0100PA00X+015038Y+135741X0193Y         S0      
317GND              VIA   -    MD0100PA00X+014268Y+135741X0193Y         S0      
317GND              VIA   -    MD0100PA00X+014788Y+135741X0193Y         S0      
317GND              VIA   -    MD0100PA00X+014528Y+135741X0193Y         S0      
317GND              VIA   -    MD0100PA00X+015649Y+134967X0200Y         S0      
317GND              VIA   -    MD0100PA00X+015282Y+135742X0193Y         S0      
317GND              VIA   -    MD0100PA00X+015649Y+135227X0200Y         S0      
317GND              VIA   -    MD0100PA00X+015649Y+135487X0200Y         S0      
317GND              VIA   -    MD0100PA00X+015377Y+136341X0193Y         S0      
317GND              VIA   -    MD0100PA00X+015377Y+136046X0193Y         S0      
317GND              VIA   -    MD0100PA00X+014418Y+136727X0193Y         S0      
317GND              VIA   -    MD0100PA00X+013179Y+133781X0200Y         S0      
317GND              VIA   -    MD0100PA00X+013755Y+133777X0200Y         S0      
317GND              VIA   -    MD0100PA00X+013748Y+135741X0193Y         S0      
317GND              VIA   -    MD0100PA00X+014008Y+135741X0193Y         S0      
317GND              VIA   -    MD0100PA00X+014175Y+136727X0193Y         S0      
317GND              VIA   -    MD0100PA00X+013295Y+136142X0193Y         S0      
317GND              VIA   -    MD0100PA00X+013748Y+136052X0193Y         S0      
317GND              VIA   -    MD0100PA00X+014008Y+136052X0193Y         S0      
317GND              VIA   -    MD0100PA00X+014175Y+137287X0193Y         S0      
317GND              VIA   -    MD0100PA00X+013932Y+137287X0193Y         S0      
317GND              VIA   -    MD0100PA00X+013932Y+136727X0193Y         S0      
327GND              PU53  -7_9-M      A01X+011260Y+136052X0827Y2126R090 S1      
317GND              VIA   -    MD0100PA00X+012121Y+136069X0193Y         S0      
317GND              VIA   -    MD0100PA00X+012121Y+136364X0193Y         S0      
317GND              VIA   -    MD0100PA00X+012667Y+133784X0200Y         S0      
317GND              VIA   -    MD0100PA00X+012407Y+133784X0200Y         S0      
317GND              VIA   -    MD0100PA00X+011778Y+135741X0193Y         S0      
317GND              VIA   -    MD0100PA00X+012389Y+134967X0200Y         S0      
317GND              VIA   -    MD0100PA00X+012649Y+134967X0200Y         S0      
317GND              VIA   -    MD0100PA00X+012022Y+135742X0193Y         S0      
317GND              VIA   -    MD0100PA00X+012389Y+135227X0200Y         S0      
317GND              VIA   -    MD0100PA00X+012389Y+135487X0200Y         S0      
317GND              VIA   -    MD0100PA00X+012649Y+135227X0200Y         S0      
317GND              VIA   -    MD0100PA00X+012524Y+135737X0200Y         S0      
317GND              VIA   -    MD0100PA00X+012649Y+135487X0200Y         S0      
317GND              VIA   -    MD0100PA00X+011528Y+135741X0193Y         S0      
317GND              VIA   -    MD0100PA00X+009921Y+133777X0200Y         S0      
317GND              VIA   -    MD0100PA00X+010488Y+135741X0193Y         S0      
317GND              VIA   -    MD0100PA00X+010748Y+135741X0193Y         S0      
317GND              VIA   -    MD0100PA00X+011008Y+135741X0193Y         S0      
317GND              VIA   -    MD0100PA00X+011268Y+135741X0193Y         S0      
327GND              PU53  -40  M      A01X+010916Y+137006X0690Y0770     S1      
317GND              VIA   -    MD0100PA00X+011158Y+136727X0193Y         S0      
317GND              VIA   -    MD0100PA00X+010915Y+136727X0193Y         S0      
317GND              VIA   -    MD0100PA00X+010035Y+136142X0193Y         S0      
317GND              VIA   -    MD0100PA00X+010488Y+136052X0193Y         S0      
317GND              VIA   -    MD0100PA00X+010748Y+136052X0193Y         S0      
317GND              VIA   -    MD0100PA00X+011008Y+136052X0193Y         S0      
317GND              VIA   -    MD0100PA00X+011268Y+136052X0193Y         S0      
317GND              VIA   -    MD0100PA00X+011008Y+136347X0193Y         S0      
317GND              VIA   -    MD0100PA00X+011268Y+136347X0193Y         S0      
317GND              VIA   -    MD0100PA00X+010915Y+137287X0193Y         S0      
317GND              VIA   -    MD0100PA00X+010672Y+137287X0193Y         S0      
317GND              VIA   -    MD0100PA00X+010672Y+136727X0193Y         S0      
317GND              VIA   -    MD0100PA00X+011158Y+137287X0193Y         S0      
327GND              PC621_-2          A01X+010200Y+138574X0198Y0197R090 S1      
317GND              VIA   -    M      A01X+010200Y+138825X0200Y         S2      
017GND              VIA   -    M      A18X+010200Y+138825X0260Y         S2      
017GND                    -    MD0100PA00X+010200Y+138825                       
327GND              PR368 -2          A01X+010904Y+138556X0198Y0197     S1      
317GND              VIA   -    MD0100PA00X+011163Y+138529X0200Y         S0      
327GND              PR460 -2   M      A01X+009015Y+131162X0198Y0197     S1      
327GND              PC451 -2          A01X+009416Y+131118X0198Y0197R090 S1      
317GND              VIA   -    M      A01X+009015Y+131456X0200Y    R180 S2      
017GND              VIA   -    M      A18X+009015Y+131456X0260Y    R180 S2      
017GND                    -    MD0100PA00X+009015Y+131456                       
317GND              VIA   -    MD0100PA00X+009619Y+133772X0200Y         S0      
317GND              VIA   -    MD0100PA00X+008850Y+135030X0193Y         S0      
317GND              VIA   -    MD0100PA00X+009100Y+135030X0193Y         S0      
317GND              VIA   -    MD0100PA00X+009279Y+134130X0200Y         S0      
317GND              VIA   -    MD0100PA00X+009294Y+134617X0200Y         S0      
317GND              VIA   -    MD0100PA00X+009050Y+133895X0200Y         S0      
327GND              PC147_-2          A18X+041280Y+135735X0400Y0500R090 S2      
327GND              PC429_-2          A18X+038022Y+133802X0400Y0500R090 S2      
327GND              PC379_-2          A18X+034742Y+133782X0400Y0500R090 S2      
327GND              PC385_-2          A18X+031451Y+133788X0400Y0500R090 S2      
327GND              PR516 -2          A01X+026272Y+131364X0198Y0197R090 S1      
327GND              PR513 -2          A01X+029562Y+131362X0198Y0197R090 S1      
327GND              PR512 -2          A01X+032852Y+131356X0198Y0197R090 S1      
327GND              PR517 -2          A01X+036132Y+131376X0198Y0197R090 S1      
327GND              PC402_-2          A01X+026270Y+131732X0198Y0197R270 S1      
327GND              PU37  -5          A01X+026775Y+132077X0090Y0240R090 S1      
327GND              PU37  -2   M      A01X+026775Y+132608X0090Y0240R090 S1      
327GND              PC400 -2          A01X+026270Y+133097X0198Y0197R090 S1      
327GND              PC370 -2          A01X+029560Y+133094X0198Y0197R090 S1      
327GND              PU5   -2   M      A01X+030065Y+132606X0090Y0240R090 S1      
327GND              PC406_-2          A01X+029151Y+131771X0198Y0197R270 S1      
327GND              PC372_-2          A01X+029560Y+131729X0198Y0197R270 S1      
327GND              PU5   -5          A01X+030065Y+132074X0090Y0240R090 S1      
327GND              PC371_-2          A01X+032850Y+131723X0198Y0197R270 S1      
327GND              PC378_-2          A01X+032456Y+131785X0198Y0197R270 S1      
327GND              PU35  -5          A01X+033355Y+132068X0090Y0240R090 S1      
327GND              PU35  -2   M      A01X+033355Y+132600X0090Y0240R090 S1      
327GND              PC369 -2          A01X+032850Y+133088X0198Y0197R090 S1      
327GND              PC423_-2          A01X+036130Y+131743X0198Y0197R270 S1      
327GND              PC377_-2          A01X+035731Y+131783X0198Y0197R270 S1      
327GND              PU38  -5          A01X+036635Y+132088X0090Y0240R090 S1      
327GND              PU38  -2   M      A01X+036635Y+132620X0090Y0240R090 S1      
327GND              PC421 -2          A01X+036130Y+133108X0198Y0197R090 S1      
327GND              PC424_-2          A01X+039011Y+131803X0198Y0197R270 S1      
327GND              PC139_-2          A01X+039388Y+133676X0198Y0197R270 S1      
327GND              PR518 -2          A01X+039391Y+133309X0198Y0197R090 S1      
327GND              PU33  -5          A01X+039893Y+134021X0090Y0240R090 S1      
327GND              PC140_-2          A01X+042269Y+133736X0198Y0197R270 S1      
327GND              PC141_-2          A01X+042656Y+133734X0198Y0197R270 S1      
327GND              PU33  -2   M      A01X+039893Y+134553X0090Y0240R090 S1      
327GND              PC138 -2          A01X+039388Y+135041X0198Y0197R090 S1      
327GND              PC442_-2          A18X+021522Y+138405X0400Y0500R090 S2      
327GND              PC446_-2          A18X+018232Y+138405X0400Y0500R090 S2      
327GND              PC628_-2          A18X+014962Y+138405X0400Y0500R090 S2      
327GND              PR378 -2          A18X+009283Y+133263X0198Y0197R270 S2      
327GND              PC634_-2          A18X+009799Y+133415X0400Y0500R090 S2      
327GND              PC636_-2          A18X+012556Y+133417X0400Y0500R090 S2      
327GND              PC635_-2          A18X+013399Y+133425X0400Y0500R090 S2      
327GND              PC637_-2          A18X+016206Y+133417X0400Y0500R090 S2      
327GND              PC458_-2          A18X+017027Y+133417X0400Y0500R090 S2      
327GND              PC460_-2          A18X+017847Y+133417X0400Y0500R090 S2      
327GND              PC459_-2          A18X+018668Y+133417X0400Y0500R090 S2      
327GND              PC456_-2          A18X+019449Y+133415X0400Y0500R090 S2      
327GND              PC419_-2          A18X+022999Y+133455X0400Y0500R090 S2      
327GND              PC420_-2          A18X+024706Y+133457X0400Y0500R090 S2      
327GND              PC417_-2          A18X+023889Y+133455X0400Y0500R090 S2      
327GND              PC418_-2          A18X+025556Y+133455X0400Y0500R090 S2      
327GND              PC410_-2          A18X+028162Y+133791X0400Y0500R090 S2      
327GND              PC455 -2          A18X+011179Y+135065X0950Y1110R270 S2      
327GND              PC452 -2          A18X+014789Y+135085X0950Y1110R270 S2      
327GND              PC450 -2          A18X+020899Y+135075X0950Y1110R270 S2      
327GND              PC627_-2          A18X+012540Y+136181X0400Y0500R270 S2      
327GND              PC633_-2          A18X+011702Y+136181X0400Y0500R270 S2      
327GND              PC626_-2          A18X+014962Y+136181X0400Y0500R270 S2      
327GND              PC632_-2          A18X+015800Y+136181X0400Y0500R270 S2      
327GND              PC443_-2          A18X+018232Y+136181X0400Y0500R270 S2      
327GND              PC449_-2          A18X+019070Y+136181X0400Y0500R270 S2      
327GND              PC448_-2          A18X+021522Y+136181X0400Y0500R270 S2      
327GND              PC444_-2          A18X+022360Y+136181X0400Y0500R270 S2      
327GND              PC409_-2          A18X+024802Y+136181X0400Y0500R270 S2      
327GND              PC411_-2          A18X+025640Y+136181X0400Y0500R270 S2      
327GND              PL47  -3          A01X+021076Y+132374X0540Y1780R270 S1      
327GND              PL43  -3          A01X+024336Y+132374X0540Y1780R270 S1      
327GND              PL46  -2          A01X+008297Y+134458X0790Y1660R090 S1      
327GND              PU53  -5          A01X+010315Y+136691X0090Y0240R090 S1      
327GND              PU53  -2   M      A01X+010315Y+137223X0090Y0240R090 S1      
327GND              PC616 -2          A01X+009810Y+137711X0198Y0197R090 S1      
327GND              PC618_-2          A01X+009810Y+136346X0198Y0197R270 S1      
327GND              PR491 -2          A01X+009812Y+135979X0198Y0197R090 S1      
327GND              PC625_-2          A01X+012691Y+136406X0198Y0197R270 S1      
327GND              PC619_-2          A01X+013070Y+136346X0198Y0197R270 S1      
327GND              PU52  -5          A01X+013575Y+136691X0090Y0240R090 S1      
327GND              PU52  -2   M      A01X+013575Y+137223X0090Y0240R090 S1      
327GND              PC617 -2          A01X+013070Y+137711X0198Y0197R090 S1      
327GND              PR492 -2          A01X+013072Y+135979X0198Y0197R090 S1      
327GND              PC434_-2          A01X+016340Y+136346X0198Y0197R270 S1      
327GND              PC624_-2          A01X+015951Y+136383X0198Y0197R270 S1      
327GND              PU40  -5          A01X+016845Y+136691X0090Y0240R090 S1      
327GND              PU40  -2   M      A01X+016845Y+137223X0090Y0240R090 S1      
327GND              PC432 -2          A01X+016340Y+137711X0198Y0197R090 S1      
327GND              PR489 -2          A01X+016342Y+135979X0198Y0197R090 S1      
327GND              PC437_-2          A01X+019630Y+136346X0198Y0197R270 S1      
327GND              PC441_-2          A01X+019221Y+136406X0198Y0197R270 S1      
327GND              PU39  -5          A01X+020135Y+136691X0090Y0240R090 S1      
327GND              PU39  -2   M      A01X+020135Y+137223X0090Y0240R090 S1      
327GND              PC433 -2          A01X+019630Y+137711X0198Y0197R090 S1      
327GND              PR488 -2          A01X+019632Y+135979X0198Y0197R090 S1      
327GND              PC401_-2          A01X+022910Y+136346X0198Y0197R270 S1      
327GND              PC440_-2          A01X+022511Y+136406X0198Y0197R270 S1      
327GND              PR515 -2          A01X+022912Y+135979X0198Y0197R090 S1      
327GND              PU36  -5          A01X+023415Y+136691X0090Y0240R090 S1      
327GND              PU36  -2   M      A01X+023415Y+137223X0090Y0240R090 S1      
327GND              PC399 -2          A01X+022910Y+137711X0198Y0197R090 S1      
327GND              PC407_-2          A01X+025791Y+136406X0198Y0197R270 S1      
327GND              PC405_-2          A01X+026178Y+136405X0198Y0197R270 S1      
327GND              PC622_-2          A01X+013049Y+138230X0198Y0197     S1      
317GND              VIA   -    MD0100PA00X+013215Y+138674X0200Y         S0      
327GND              PC620_-2          A01X+013460Y+138574X0198Y0197R090 S1      
317GND              VIA   -    MD0100PA00X+036275Y+134071X0200Y         S0      
317GND              VIA   -    MD0100PA00X+032995Y+134051X0200Y         S0      
317GND              VIA   -    MD0100PA00X+029705Y+134057X0200Y         S0      
317GND              VIA   -    MD0100PA00X+023055Y+138674X0200Y         S0      
317GND              VIA   -    MD0100PA00X+019775Y+138674X0200Y         S0      
317GND              VIA   -    MD0100PA00X+016485Y+138674X0200Y         S0      
327GND              PC422_-2          A01X+036520Y+133971X0198Y0197R090 S1      
327GND              PC425_-2          A01X+036109Y+133627X0198Y0197     S1      
327GND              PC374_-2          A01X+033240Y+133951X0198Y0197R090 S1      
327GND              PC375_-2          A01X+032829Y+133607X0198Y0197     S1      
327GND              PC373_-2          A01X+029949Y+133957X0198Y0197R090 S1      
327GND              PC376_-2          A01X+029539Y+133613X0198Y0197     S1      
327GND              PC403_-2          A01X+023300Y+138574X0198Y0197R090 S1      
327GND              PC623_-2          A01X+022889Y+138230X0198Y0197     S1      
327GND              PC435_-2          A01X+020020Y+138574X0198Y0197R090 S1      
327GND              PC438_-2          A01X+019609Y+138230X0198Y0197     S1      
327GND              PC436_-2          A01X+016730Y+138574X0198Y0197R090 S1      
327GND              PC439_-2          A01X+016319Y+138230X0198Y0197     S1      
317GND              VIA   -    MD0100PA00X+022889Y+138479X0200Y         S0      
317GND              VIA   -    MD0100PA00X+019609Y+138479X0200Y         S0      
317GND              VIA   -    MD0100PA00X+016319Y+138479X0200Y         S0      
317GND              VIA   -    MD0100PA00X+013049Y+138479X0200Y         S0      
317GND              VIA   -    MD0100PA00X+029539Y+133862X0200Y         S0      
317GND              VIA   -    MD0100PA00X+032829Y+133856X0200Y         S0      
317GND              VIA   -    MD0100PA00X+036109Y+133876X0200Y         S0      
317GND              H11   -1   MD1470PA00X+007959Y+136935X2440Y         S3      
327GND              VIA   -           A18X+017027Y+134459X0260Y    R090 S2      
327GND              VIA   -           A18X+018668Y+134459X0260Y    R090 S2      
327GND              VIA   -           A18X+022999Y+134497X0260Y    R090 S2      
327GND              VIA   -           A18X+024706Y+134499X0260Y    R090 S2      
317GND              VIA   -    MD0100PA00X+066350Y+077356X0190Y         S0      
327GND              J102  -6          A01X+066350Y+077356X0205Y0590R090 S1      
317GND              VIA   -    MD0100PA00X+067706Y+077691X0190Y         S0      
327GND              J27   -151        A01X+067706Y+077691X0205Y0590R090 S1      
317GND              VIA   -    MD0100PA00X+069320Y+077356X0190Y         S0      
327GND              J27   -6          A01X+069320Y+077356X0205Y0590R090 S1      
327GND              C5010 -2          A01X+061920Y+139073X0198Y0197R180 S1      
327GND              PR13  -2          A01X+064624Y+135336X0198Y0197R270 S1      
317GND              J29   -G2  MD0480PA00X+074453Y+102140X0680Y1370R090 S3      
317GND              J100  -G2  MD0480PA00X+071483Y+102140X0680Y1370R090 S3      
317GND              J37   -G2  MD0480PA00X+080393Y+102140X0680Y1370R090 S3      
317GND              J99   -G2  MD0480PA00X+077423Y+102140X0680Y1370R090 S3      
317GND              J29   -G3  MD0480PA00X+074453Y+127770X0680Y1370R090 S3      
317GND              J100  -G3  MD0480PA00X+071483Y+127770X0680Y1370R090 S3      
317GND              J37   -G3  MD0480PA00X+080393Y+127770X0680Y1370R090 S3      
317GND              J99   -G3  MD0480PA00X+077423Y+127770X0680Y1370R090 S3      
327GND              J37   -286        A01X+079586Y+124876X0205Y0590R090 S1      
327GND              J37   -288        A01X+079586Y+125545X0205Y0590R090 S1      
327GND              J37   -143        A01X+081200Y+125211X0205Y0590R090 S1      
327GND              J37   -141        A01X+081200Y+124542X0205Y0590R090 S1      
327GND              J37   -268        A01X+079586Y+118852X0205Y0590R090 S1      
327GND              J37   -275        A01X+079586Y+121195X0205Y0590R090 S1      
327GND              J37   -277        A01X+079586Y+121864X0205Y0590R090 S1      
327GND              J37   -279        A01X+079586Y+122534X0205Y0590R090 S1      
327GND              J37   -130        A01X+081200Y+120860X0205Y0590R090 S1      
327GND              J37   -132        A01X+081200Y+121530X0205Y0590R090 S1      
327GND              J37   -134        A01X+081200Y+122199X0205Y0590R090 S1      
327GND              J37   -253        A01X+079586Y+113833X0205Y0590R090 S1      
327GND              J37   -255        A01X+079586Y+114502X0205Y0590R090 S1      
327GND              J37   -257        A01X+079586Y+115171X0205Y0590R090 S1      
327GND              J37   -264        A01X+079586Y+117514X0205Y0590R090 S1      
327GND              J37   -266        A01X+079586Y+118183X0205Y0590R090 S1      
327GND              J37   -110        A01X+081200Y+114168X0205Y0590R090 S1      
327GND              J37   -108        A01X+081200Y+113498X0205Y0590R090 S1      
327GND              J37   -112        A01X+081200Y+114837X0205Y0590R090 S1      
327GND              J37   -119        A01X+081200Y+117179X0205Y0590R090 S1      
327GND              J37   -121        A01X+081200Y+117849X0205Y0590R090 S1      
327GND              J37   -123        A01X+081200Y+118518X0205Y0590R090 S1      
327GND              J37   -235        A01X+079586Y+107809X0205Y0590R090 S1      
327GND              J37   -242        A01X+079586Y+110152X0205Y0590R090 S1      
327GND              J37   -244        A01X+079586Y+110821X0205Y0590R090 S1      
327GND              J37   -246        A01X+079586Y+111490X0205Y0590R090 S1      
327GND              J37   -90         A01X+081200Y+107474X0205Y0590R090 S1      
327GND              J37   -99         A01X+081200Y+110486X0205Y0590R090 S1      
327GND              J37   -97         A01X+081200Y+109817X0205Y0590R090 S1      
327GND              J37   -101        A01X+081200Y+111156X0205Y0590R090 S1      
327GND              J37   -222        A01X+079586Y+103459X0205Y0590R090 S1      
327GND              J37   -224        A01X+079586Y+104128X0205Y0590R090 S1      
327GND              J37   -226        A01X+079586Y+104797X0205Y0590R090 S1      
327GND              J37   -228        A01X+079586Y+105467X0205Y0590R090 S1      
327GND              J37   -230        A01X+079586Y+106136X0205Y0590R090 S1      
327GND              J37   -233        A01X+079586Y+107140X0205Y0590R090 S1      
327GND              J37   -77         A01X+081200Y+103124X0205Y0590R090 S1      
327GND              J37   -79         A01X+081200Y+103793X0205Y0590R090 S1      
327GND              J37   -81         A01X+081200Y+104463X0205Y0590R090 S1      
327GND              J37   -83         A01X+081200Y+105132X0205Y0590R090 S1      
327GND              J37   -85         A01X+081200Y+105801X0205Y0590R090 S1      
327GND              J37   -88         A01X+081200Y+106805X0205Y0590R090 S1      
327GND              J37   -208        A01X+079586Y+096766X0205Y0590R090 S1      
327GND              J37   -210        A01X+079586Y+097435X0205Y0590R090 S1      
327GND              J37   -212        A01X+079586Y+098104X0205Y0590R090 S1      
327GND              J37   -214        A01X+079586Y+098774X0205Y0590R090 S1      
327GND              J37   -216        A01X+079586Y+099443X0205Y0590R090 S1      
327GND              J37   -219        A01X+079586Y+100447X0205Y0590R090 S1      
327GND              J37   -63         A01X+081200Y+096431X0205Y0590R090 S1      
327GND              J37   -65         A01X+081200Y+097100X0205Y0590R090 S1      
327GND              J37   -67         A01X+081200Y+097770X0205Y0590R090 S1      
327GND              J37   -69         A01X+081200Y+098439X0205Y0590R090 S1      
327GND              J37   -71         A01X+081200Y+099108X0205Y0590R090 S1      
327GND              J37   -73         A01X+081200Y+099778X0205Y0590R090 S1      
327GND              J37   -75         A01X+081200Y+100447X0205Y0590R090 S1      
327GND              J37   -193        A01X+079586Y+091746X0205Y0590R090 S1      
327GND              J37   -195        A01X+079586Y+092416X0205Y0590R090 S1      
327GND              J37   -197        A01X+079586Y+093085X0205Y0590R090 S1      
327GND              J37   -204        A01X+079586Y+095427X0205Y0590R090 S1      
327GND              J37   -206        A01X+079586Y+096097X0205Y0590R090 S1      
327GND              J37   -48         A01X+081200Y+091412X0205Y0590R090 S1      
327GND              J37   -50         A01X+081200Y+092081X0205Y0590R090 S1      
327GND              J37   -52         A01X+081200Y+092750X0205Y0590R090 S1      
327GND              J37   -59         A01X+081200Y+095093X0205Y0590R090 S1      
327GND              J37   -61         A01X+081200Y+095762X0205Y0590R090 S1      
327GND              J37   -173        A01X+079586Y+085053X0205Y0590R090 S1      
327GND              J37   -175        A01X+079586Y+085723X0205Y0590R090 S1      
327GND              J37   -182        A01X+079586Y+088065X0205Y0590R090 S1      
327GND              J37   -184        A01X+079586Y+088734X0205Y0590R090 S1      
327GND              J37   -186        A01X+079586Y+089404X0205Y0590R090 S1      
327GND              J37   -30         A01X+081200Y+085388X0205Y0590R090 S1      
327GND              J37   -37         A01X+081200Y+087730X0205Y0590R090 S1      
327GND              J37   -39         A01X+081200Y+088400X0205Y0590R090 S1      
327GND              J37   -41         A01X+081200Y+089069X0205Y0590R090 S1      
327GND              J37   -160        A01X+079586Y+080703X0205Y0590R090 S1      
327GND              J37   -162        A01X+079586Y+081372X0205Y0590R090 S1      
327GND              J37   -164        A01X+079586Y+082042X0205Y0590R090 S1      
327GND              J37   -171        A01X+079586Y+084384X0205Y0590R090 S1      
327GND              J37   -15         A01X+081200Y+080368X0205Y0590R090 S1      
327GND              J37   -17         A01X+081200Y+081038X0205Y0590R090 S1      
327GND              J37   -19         A01X+081200Y+081707X0205Y0590R090 S1      
327GND              J37   -26         A01X+081200Y+084049X0205Y0590R090 S1      
327GND              J37   -28         A01X+081200Y+084719X0205Y0590R090 S1      
327GND              J37   -151        A01X+079586Y+077691X0205Y0590R090 S1      
327GND              J37   -153        A01X+079586Y+078360X0205Y0590R090 S1      
327GND              J37   -8          A01X+081200Y+078026X0205Y0590R090 S1      
327GND              J29   -286        A01X+073646Y+124876X0205Y0590R090 S1      
327GND              J29   -288        A01X+073646Y+125545X0205Y0590R090 S1      
327GND              J29   -141        A01X+075260Y+124542X0205Y0590R090 S1      
327GND              J99   -286        A01X+076616Y+124876X0205Y0590R090 S1      
327GND              J29   -143        A01X+075260Y+125211X0205Y0590R090 S1      
327GND              J99   -288        A01X+076616Y+125545X0205Y0590R090 S1      
327GND              J99   -141        A01X+078230Y+124542X0205Y0590R090 S1      
327GND              J99   -143        A01X+078230Y+125211X0205Y0590R090 S1      
327GND              J29   -268        A01X+073646Y+118852X0205Y0590R090 S1      
327GND              J29   -277        A01X+073646Y+121864X0205Y0590R090 S1      
327GND              J29   -275        A01X+073646Y+121195X0205Y0590R090 S1      
327GND              J29   -279        A01X+073646Y+122534X0205Y0590R090 S1      
327GND              J99   -268        A01X+076616Y+118852X0205Y0590R090 S1      
327GND              J99   -277        A01X+076616Y+121864X0205Y0590R090 S1      
327GND              J99   -275        A01X+076616Y+121195X0205Y0590R090 S1      
327GND              J29   -130        A01X+075260Y+120860X0205Y0590R090 S1      
327GND              J29   -134        A01X+075260Y+122199X0205Y0590R090 S1      
327GND              J29   -132        A01X+075260Y+121530X0205Y0590R090 S1      
327GND              J99   -279        A01X+076616Y+122534X0205Y0590R090 S1      
327GND              J99   -130        A01X+078230Y+120860X0205Y0590R090 S1      
327GND              J99   -134        A01X+078230Y+122199X0205Y0590R090 S1      
327GND              J99   -132        A01X+078230Y+121530X0205Y0590R090 S1      
327GND              J29   -253        A01X+073646Y+113833X0205Y0590R090 S1      
327GND              J29   -257        A01X+073646Y+115171X0205Y0590R090 S1      
327GND              J29   -255        A01X+073646Y+114502X0205Y0590R090 S1      
327GND              J29   -266        A01X+073646Y+118183X0205Y0590R090 S1      
327GND              J29   -264        A01X+073646Y+117514X0205Y0590R090 S1      
327GND              J29   -110        A01X+075260Y+114168X0205Y0590R090 S1      
327GND              J99   -253        A01X+076616Y+113833X0205Y0590R090 S1      
327GND              J29   -108        A01X+075260Y+113498X0205Y0590R090 S1      
327GND              J99   -257        A01X+076616Y+115171X0205Y0590R090 S1      
327GND              J99   -255        A01X+076616Y+114502X0205Y0590R090 S1      
327GND              J29   -112        A01X+075260Y+114837X0205Y0590R090 S1      
327GND              J29   -119        A01X+075260Y+117179X0205Y0590R090 S1      
327GND              J99   -266        A01X+076616Y+118183X0205Y0590R090 S1      
327GND              J99   -264        A01X+076616Y+117514X0205Y0590R090 S1      
327GND              J29   -123        A01X+075260Y+118518X0205Y0590R090 S1      
327GND              J29   -121        A01X+075260Y+117849X0205Y0590R090 S1      
327GND              J99   -110        A01X+078230Y+114168X0205Y0590R090 S1      
327GND              J99   -108        A01X+078230Y+113498X0205Y0590R090 S1      
327GND              J99   -112        A01X+078230Y+114837X0205Y0590R090 S1      
327GND              J99   -119        A01X+078230Y+117179X0205Y0590R090 S1      
327GND              J99   -123        A01X+078230Y+118518X0205Y0590R090 S1      
327GND              J99   -121        A01X+078230Y+117849X0205Y0590R090 S1      
327GND              J29   -235        A01X+073646Y+107809X0205Y0590R090 S1      
327GND              J29   -244        A01X+073646Y+110821X0205Y0590R090 S1      
327GND              J29   -242        A01X+073646Y+110152X0205Y0590R090 S1      
327GND              J29   -246        A01X+073646Y+111490X0205Y0590R090 S1      
327GND              J99   -235        A01X+076616Y+107809X0205Y0590R090 S1      
327GND              J29   -90         A01X+075260Y+107474X0205Y0590R090 S1      
327GND              J99   -244        A01X+076616Y+110821X0205Y0590R090 S1      
327GND              J99   -242        A01X+076616Y+110152X0205Y0590R090 S1      
327GND              J29   -99         A01X+075260Y+110486X0205Y0590R090 S1      
327GND              J29   -97         A01X+075260Y+109817X0205Y0590R090 S1      
327GND              J99   -246        A01X+076616Y+111490X0205Y0590R090 S1      
327GND              J29   -101        A01X+075260Y+111156X0205Y0590R090 S1      
327GND              J99   -90         A01X+078230Y+107474X0205Y0590R090 S1      
327GND              J99   -99         A01X+078230Y+110486X0205Y0590R090 S1      
327GND              J99   -97         A01X+078230Y+109817X0205Y0590R090 S1      
327GND              J99   -101        A01X+078230Y+111156X0205Y0590R090 S1      
327GND              J29   -224        A01X+073646Y+104128X0205Y0590R090 S1      
327GND              J29   -222        A01X+073646Y+103459X0205Y0590R090 S1      
327GND              J29   -230        A01X+073646Y+106136X0205Y0590R090 S1      
327GND              J29   -228        A01X+073646Y+105467X0205Y0590R090 S1      
327GND              J29   -226        A01X+073646Y+104797X0205Y0590R090 S1      
327GND              J29   -233        A01X+073646Y+107140X0205Y0590R090 S1      
327GND              J99   -222        A01X+076616Y+103459X0205Y0590R090 S1      
327GND              J29   -81         A01X+075260Y+104463X0205Y0590R090 S1      
327GND              J29   -79         A01X+075260Y+103793X0205Y0590R090 S1      
327GND              J29   -77         A01X+075260Y+103124X0205Y0590R090 S1      
327GND              J99   -224        A01X+076616Y+104128X0205Y0590R090 S1      
327GND              J99   -230        A01X+076616Y+106136X0205Y0590R090 S1      
327GND              J99   -228        A01X+076616Y+105467X0205Y0590R090 S1      
327GND              J99   -226        A01X+076616Y+104797X0205Y0590R090 S1      
327GND              J29   -85         A01X+075260Y+105801X0205Y0590R090 S1      
327GND              J29   -83         A01X+075260Y+105132X0205Y0590R090 S1      
327GND              J99   -233        A01X+076616Y+107140X0205Y0590R090 S1      
327GND              J29   -88         A01X+075260Y+106805X0205Y0590R090 S1      
327GND              J99   -81         A01X+078230Y+104463X0205Y0590R090 S1      
327GND              J99   -79         A01X+078230Y+103793X0205Y0590R090 S1      
327GND              J99   -77         A01X+078230Y+103124X0205Y0590R090 S1      
327GND              J99   -85         A01X+078230Y+105801X0205Y0590R090 S1      
327GND              J99   -83         A01X+078230Y+105132X0205Y0590R090 S1      
327GND              J99   -88         A01X+078230Y+106805X0205Y0590R090 S1      
327GND              J29   -212        A01X+073646Y+098104X0205Y0590R090 S1      
327GND              J29   -210        A01X+073646Y+097435X0205Y0590R090 S1      
327GND              J29   -208        A01X+073646Y+096766X0205Y0590R090 S1      
327GND              J29   -216        A01X+073646Y+099443X0205Y0590R090 S1      
327GND              J29   -214        A01X+073646Y+098774X0205Y0590R090 S1      
327GND              J29   -219        A01X+073646Y+100447X0205Y0590R090 S1      
327GND              J29   -63         A01X+075260Y+096431X0205Y0590R090 S1      
327GND              J99   -212        A01X+076616Y+098104X0205Y0590R090 S1      
327GND              J99   -210        A01X+076616Y+097435X0205Y0590R090 S1      
327GND              J29   -67         A01X+075260Y+097770X0205Y0590R090 S1      
327GND              J29   -65         A01X+075260Y+097100X0205Y0590R090 S1      
327GND              J99   -208        A01X+076616Y+096766X0205Y0590R090 S1      
327GND              J99   -216        A01X+076616Y+099443X0205Y0590R090 S1      
327GND              J99   -214        A01X+076616Y+098774X0205Y0590R090 S1      
327GND              J29   -73         A01X+075260Y+099778X0205Y0590R090 S1      
327GND              J29   -71         A01X+075260Y+099108X0205Y0590R090 S1      
327GND              J29   -69         A01X+075260Y+098439X0205Y0590R090 S1      
327GND              J99   -219        A01X+076616Y+100447X0205Y0590R090 S1      
327GND              J29   -75         A01X+075260Y+100447X0205Y0590R090 S1      
327GND              J99   -63         A01X+078230Y+096431X0205Y0590R090 S1      
327GND              J99   -67         A01X+078230Y+097770X0205Y0590R090 S1      
327GND              J99   -65         A01X+078230Y+097100X0205Y0590R090 S1      
327GND              J99   -73         A01X+078230Y+099778X0205Y0590R090 S1      
327GND              J99   -71         A01X+078230Y+099108X0205Y0590R090 S1      
327GND              J99   -69         A01X+078230Y+098439X0205Y0590R090 S1      
327GND              J99   -75         A01X+078230Y+100447X0205Y0590R090 S1      
327GND              J29   -193        A01X+073646Y+091746X0205Y0590R090 S1      
327GND              J29   -197        A01X+073646Y+093085X0205Y0590R090 S1      
327GND              J29   -195        A01X+073646Y+092416X0205Y0590R090 S1      
327GND              J29   -206        A01X+073646Y+096097X0205Y0590R090 S1      
327GND              J29   -204        A01X+073646Y+095427X0205Y0590R090 S1      
327GND              J99   -193        A01X+076616Y+091746X0205Y0590R090 S1      
327GND              J29   -48         A01X+075260Y+091412X0205Y0590R090 S1      
327GND              J99   -197        A01X+076616Y+093085X0205Y0590R090 S1      
327GND              J99   -195        A01X+076616Y+092416X0205Y0590R090 S1      
327GND              J29   -52         A01X+075260Y+092750X0205Y0590R090 S1      
327GND              J29   -50         A01X+075260Y+092081X0205Y0590R090 S1      
327GND              J29   -59         A01X+075260Y+095093X0205Y0590R090 S1      
327GND              J99   -206        A01X+076616Y+096097X0205Y0590R090 S1      
327GND              J99   -204        A01X+076616Y+095427X0205Y0590R090 S1      
327GND              J29   -61         A01X+075260Y+095762X0205Y0590R090 S1      
327GND              J99   -48         A01X+078230Y+091412X0205Y0590R090 S1      
327GND              J99   -52         A01X+078230Y+092750X0205Y0590R090 S1      
327GND              J99   -50         A01X+078230Y+092081X0205Y0590R090 S1      
327GND              J99   -59         A01X+078230Y+095093X0205Y0590R090 S1      
327GND              J99   -61         A01X+078230Y+095762X0205Y0590R090 S1      
327GND              J29   -173        A01X+073646Y+085053X0205Y0590R090 S1      
327GND              J29   -175        A01X+073646Y+085723X0205Y0590R090 S1      
327GND              J29   -182        A01X+073646Y+088065X0205Y0590R090 S1      
327GND              J29   -186        A01X+073646Y+089404X0205Y0590R090 S1      
327GND              J29   -184        A01X+073646Y+088734X0205Y0590R090 S1      
327GND              J99   -173        A01X+076616Y+085053X0205Y0590R090 S1      
327GND              J29   -30         A01X+075260Y+085388X0205Y0590R090 S1      
327GND              J99   -175        A01X+076616Y+085723X0205Y0590R090 S1      
327GND              J99   -182        A01X+076616Y+088065X0205Y0590R090 S1      
327GND              J29   -39         A01X+075260Y+088400X0205Y0590R090 S1      
327GND              J29   -37         A01X+075260Y+087730X0205Y0590R090 S1      
327GND              J99   -186        A01X+076616Y+089404X0205Y0590R090 S1      
327GND              J99   -184        A01X+076616Y+088734X0205Y0590R090 S1      
327GND              J29   -41         A01X+075260Y+089069X0205Y0590R090 S1      
327GND              J99   -30         A01X+078230Y+085388X0205Y0590R090 S1      
327GND              J99   -39         A01X+078230Y+088400X0205Y0590R090 S1      
327GND              J99   -37         A01X+078230Y+087730X0205Y0590R090 S1      
327GND              J99   -41         A01X+078230Y+089069X0205Y0590R090 S1      
327GND              J29   -160        A01X+073646Y+080703X0205Y0590R090 S1      
327GND              J29   -164        A01X+073646Y+082042X0205Y0590R090 S1      
327GND              J29   -162        A01X+073646Y+081372X0205Y0590R090 S1      
327GND              J29   -171        A01X+073646Y+084384X0205Y0590R090 S1      
327GND              J29   -15         A01X+075260Y+080368X0205Y0590R090 S1      
327GND              J99   -160        A01X+076616Y+080703X0205Y0590R090 S1      
327GND              J99   -164        A01X+076616Y+082042X0205Y0590R090 S1      
327GND              J99   -162        A01X+076616Y+081372X0205Y0590R090 S1      
327GND              J29   -19         A01X+075260Y+081707X0205Y0590R090 S1      
327GND              J29   -17         A01X+075260Y+081038X0205Y0590R090 S1      
327GND              J29   -28         A01X+075260Y+084719X0205Y0590R090 S1      
327GND              J29   -26         A01X+075260Y+084049X0205Y0590R090 S1      
327GND              J99   -171        A01X+076616Y+084384X0205Y0590R090 S1      
327GND              J99   -15         A01X+078230Y+080368X0205Y0590R090 S1      
327GND              J99   -19         A01X+078230Y+081707X0205Y0590R090 S1      
327GND              J99   -17         A01X+078230Y+081038X0205Y0590R090 S1      
327GND              J99   -28         A01X+078230Y+084719X0205Y0590R090 S1      
327GND              J99   -26         A01X+078230Y+084049X0205Y0590R090 S1      
327GND              J29   -153        A01X+073646Y+078360X0205Y0590R090 S1      
327GND              J29   -151        A01X+073646Y+077691X0205Y0590R090 S1      
327GND              J99   -153        A01X+076616Y+078360X0205Y0590R090 S1      
327GND              J99   -151        A01X+076616Y+077691X0205Y0590R090 S1      
327GND              J29   -8          A01X+075260Y+078026X0205Y0590R090 S1      
327GND              J99   -8          A01X+078230Y+078026X0205Y0590R090 S1      
327GND              J100  -286        A01X+070676Y+124876X0205Y0590R090 S1      
327GND              J100  -288        A01X+070676Y+125545X0205Y0590R090 S1      
327GND              J100  -141        A01X+072290Y+124542X0205Y0590R090 S1      
327GND              J100  -143        A01X+072290Y+125211X0205Y0590R090 S1      
327GND              J100  -268        A01X+070676Y+118852X0205Y0590R090 S1      
327GND              J100  -277        A01X+070676Y+121864X0205Y0590R090 S1      
327GND              J100  -275        A01X+070676Y+121195X0205Y0590R090 S1      
327GND              J100  -279        A01X+070676Y+122534X0205Y0590R090 S1      
327GND              J100  -130        A01X+072290Y+120860X0205Y0590R090 S1      
327GND              J100  -134        A01X+072290Y+122199X0205Y0590R090 S1      
327GND              J100  -132        A01X+072290Y+121530X0205Y0590R090 S1      
327GND              J100  -253        A01X+070676Y+113833X0205Y0590R090 S1      
327GND              J100  -257        A01X+070676Y+115171X0205Y0590R090 S1      
327GND              J100  -255        A01X+070676Y+114502X0205Y0590R090 S1      
327GND              J100  -266        A01X+070676Y+118183X0205Y0590R090 S1      
327GND              J100  -264        A01X+070676Y+117514X0205Y0590R090 S1      
327GND              J100  -110        A01X+072290Y+114168X0205Y0590R090 S1      
327GND              J100  -108        A01X+072290Y+113498X0205Y0590R090 S1      
327GND              J100  -112        A01X+072290Y+114837X0205Y0590R090 S1      
327GND              J100  -119        A01X+072290Y+117179X0205Y0590R090 S1      
327GND              J100  -123        A01X+072290Y+118518X0205Y0590R090 S1      
327GND              J100  -121        A01X+072290Y+117849X0205Y0590R090 S1      
327GND              J100  -235        A01X+070676Y+107809X0205Y0590R090 S1      
327GND              J100  -244        A01X+070676Y+110821X0205Y0590R090 S1      
327GND              J100  -242        A01X+070676Y+110152X0205Y0590R090 S1      
327GND              J100  -246        A01X+070676Y+111490X0205Y0590R090 S1      
327GND              J100  -90         A01X+072290Y+107474X0205Y0590R090 S1      
327GND              J100  -99         A01X+072290Y+110486X0205Y0590R090 S1      
327GND              J100  -97         A01X+072290Y+109817X0205Y0590R090 S1      
327GND              J100  -101        A01X+072290Y+111156X0205Y0590R090 S1      
327GND              J100  -224        A01X+070676Y+104128X0205Y0590R090 S1      
327GND              J100  -222        A01X+070676Y+103459X0205Y0590R090 S1      
327GND              J100  -230        A01X+070676Y+106136X0205Y0590R090 S1      
327GND              J100  -228        A01X+070676Y+105467X0205Y0590R090 S1      
327GND              J100  -226        A01X+070676Y+104797X0205Y0590R090 S1      
327GND              J100  -233        A01X+070676Y+107140X0205Y0590R090 S1      
327GND              J100  -81         A01X+072290Y+104463X0205Y0590R090 S1      
327GND              J100  -79         A01X+072290Y+103793X0205Y0590R090 S1      
327GND              J100  -77         A01X+072290Y+103124X0205Y0590R090 S1      
327GND              J100  -85         A01X+072290Y+105801X0205Y0590R090 S1      
327GND              J100  -83         A01X+072290Y+105132X0205Y0590R090 S1      
327GND              J100  -88         A01X+072290Y+106805X0205Y0590R090 S1      
327GND              J100  -212        A01X+070676Y+098104X0205Y0590R090 S1      
327GND              J100  -210        A01X+070676Y+097435X0205Y0590R090 S1      
327GND              J100  -208        A01X+070676Y+096766X0205Y0590R090 S1      
327GND              J100  -216        A01X+070676Y+099443X0205Y0590R090 S1      
327GND              J100  -214        A01X+070676Y+098774X0205Y0590R090 S1      
327GND              J100  -219        A01X+070676Y+100447X0205Y0590R090 S1      
327GND              J100  -63         A01X+072290Y+096431X0205Y0590R090 S1      
327GND              J100  -67         A01X+072290Y+097770X0205Y0590R090 S1      
327GND              J100  -65         A01X+072290Y+097100X0205Y0590R090 S1      
327GND              J100  -73         A01X+072290Y+099778X0205Y0590R090 S1      
327GND              J100  -71         A01X+072290Y+099108X0205Y0590R090 S1      
327GND              J100  -69         A01X+072290Y+098439X0205Y0590R090 S1      
327GND              J100  -75         A01X+072290Y+100447X0205Y0590R090 S1      
327GND              J100  -193        A01X+070676Y+091746X0205Y0590R090 S1      
327GND              J100  -197        A01X+070676Y+093085X0205Y0590R090 S1      
327GND              J100  -195        A01X+070676Y+092416X0205Y0590R090 S1      
327GND              J100  -206        A01X+070676Y+096097X0205Y0590R090 S1      
327GND              J100  -204        A01X+070676Y+095427X0205Y0590R090 S1      
327GND              J100  -48         A01X+072290Y+091412X0205Y0590R090 S1      
327GND              J100  -52         A01X+072290Y+092750X0205Y0590R090 S1      
327GND              J100  -50         A01X+072290Y+092081X0205Y0590R090 S1      
327GND              J100  -59         A01X+072290Y+095093X0205Y0590R090 S1      
327GND              J100  -61         A01X+072290Y+095762X0205Y0590R090 S1      
327GND              J100  -173        A01X+070676Y+085053X0205Y0590R090 S1      
327GND              J100  -175        A01X+070676Y+085723X0205Y0590R090 S1      
327GND              J100  -182        A01X+070676Y+088065X0205Y0590R090 S1      
327GND              J100  -186        A01X+070676Y+089404X0205Y0590R090 S1      
327GND              J100  -184        A01X+070676Y+088734X0205Y0590R090 S1      
327GND              J100  -30         A01X+072290Y+085388X0205Y0590R090 S1      
327GND              J100  -39         A01X+072290Y+088400X0205Y0590R090 S1      
327GND              J100  -37         A01X+072290Y+087730X0205Y0590R090 S1      
327GND              J100  -41         A01X+072290Y+089069X0205Y0590R090 S1      
327GND              J100  -160        A01X+070676Y+080703X0205Y0590R090 S1      
327GND              J100  -164        A01X+070676Y+082042X0205Y0590R090 S1      
327GND              J100  -162        A01X+070676Y+081372X0205Y0590R090 S1      
327GND              J100  -171        A01X+070676Y+084384X0205Y0590R090 S1      
327GND              J100  -15         A01X+072290Y+080368X0205Y0590R090 S1      
327GND              J100  -19         A01X+072290Y+081707X0205Y0590R090 S1      
327GND              J100  -17         A01X+072290Y+081038X0205Y0590R090 S1      
327GND              J100  -26         A01X+072290Y+084049X0205Y0590R090 S1      
327GND              J100  -28         A01X+072290Y+084719X0205Y0590R090 S1      
327GND              J100  -153        A01X+070676Y+078360X0205Y0590R090 S1      
327GND              J100  -151        A01X+070676Y+077691X0205Y0590R090 S1      
327GND              J100  -8          A01X+072290Y+078026X0205Y0590R090 S1      
327GND              J37   -273        A01X+079586Y+120526X0205Y0590R090 S1      
327GND              J37   -128        A01X+081200Y+120191X0205Y0590R090 S1      
327GND              J37   -270        A01X+079586Y+119522X0205Y0590R090 S1      
327GND              J37   -125        A01X+081200Y+119187X0205Y0590R090 S1      
327GND              J37   -139        A01X+081200Y+123872X0205Y0590R090 S1      
327GND              J37   -281        A01X+079586Y+123203X0205Y0590R090 S1      
327GND              J37   -136        A01X+081200Y+122868X0205Y0590R090 S1      
327GND              J37   -284        A01X+079586Y+124207X0205Y0590R090 S1      
327GND              J37   -251        A01X+079586Y+113164X0205Y0590R090 S1      
327GND              J37   -259        A01X+079586Y+115841X0205Y0590R090 S1      
327GND              J37   -114        A01X+081200Y+115506X0205Y0590R090 S1      
327GND              J37   -262        A01X+079586Y+116845X0205Y0590R090 S1      
327GND              J37   -117        A01X+081200Y+116510X0205Y0590R090 S1      
327GND              J37   -237        A01X+079586Y+108478X0205Y0590R090 S1      
327GND              J37   -240        A01X+079586Y+109482X0205Y0590R090 S1      
327GND              J37   -95         A01X+081200Y+109148X0205Y0590R090 S1      
327GND              J37   -92         A01X+081200Y+108144X0205Y0590R090 S1      
327GND              J37   -248        A01X+079586Y+112160X0205Y0590R090 S1      
327GND              J37   -103        A01X+081200Y+111825X0205Y0590R090 S1      
327GND              J37   -106        A01X+081200Y+112829X0205Y0590R090 S1      
327GND              J37   -191        A01X+079586Y+091077X0205Y0590R090 S1      
327GND              J37   -46         A01X+081200Y+090742X0205Y0590R090 S1      
327GND              J37   -54         A01X+081200Y+093419X0205Y0590R090 S1      
327GND              J37   -199        A01X+079586Y+093754X0205Y0590R090 S1      
327GND              J37   -202        A01X+079586Y+094758X0205Y0590R090 S1      
327GND              J37   -57         A01X+081200Y+094423X0205Y0590R090 S1      
327GND              J37   -177        A01X+079586Y+086392X0205Y0590R090 S1      
327GND              J37   -32         A01X+081200Y+086057X0205Y0590R090 S1      
327GND              J37   -35         A01X+081200Y+087061X0205Y0590R090 S1      
327GND              J37   -180        A01X+079586Y+087396X0205Y0590R090 S1      
327GND              J37   -188        A01X+079586Y+090073X0205Y0590R090 S1      
327GND              J37   -43         A01X+081200Y+089738X0205Y0590R090 S1      
327GND              J37   -158        A01X+079586Y+080034X0205Y0590R090 S1      
327GND              J37   -13         A01X+081200Y+079699X0205Y0590R090 S1      
327GND              J37   -166        A01X+079586Y+082711X0205Y0590R090 S1      
327GND              J37   -169        A01X+079586Y+083715X0205Y0590R090 S1      
327GND              J37   -21         A01X+081200Y+082376X0205Y0590R090 S1      
327GND              J37   -24         A01X+081200Y+083380X0205Y0590R090 S1      
327GND              J37   -155        A01X+079586Y+079030X0205Y0590R090 S1      
327GND              J37   -10         A01X+081200Y+078695X0205Y0590R090 S1      
327GND              J29   -273        A01X+073646Y+120526X0205Y0590R090 S1      
327GND              J29   -270        A01X+073646Y+119522X0205Y0590R090 S1      
327GND              J29   -281        A01X+073646Y+123203X0205Y0590R090 S1      
327GND              J29   -284        A01X+073646Y+124207X0205Y0590R090 S1      
327GND              J29   -128        A01X+075260Y+120191X0205Y0590R090 S1      
327GND              J29   -125        A01X+075260Y+119187X0205Y0590R090 S1      
327GND              J29   -139        A01X+075260Y+123872X0205Y0590R090 S1      
327GND              J29   -136        A01X+075260Y+122868X0205Y0590R090 S1      
327GND              J99   -273        A01X+076616Y+120526X0205Y0590R090 S1      
327GND              J99   -128        A01X+078230Y+120191X0205Y0590R090 S1      
327GND              J99   -270        A01X+076616Y+119522X0205Y0590R090 S1      
327GND              J99   -125        A01X+078230Y+119187X0205Y0590R090 S1      
327GND              J99   -139        A01X+078230Y+123872X0205Y0590R090 S1      
327GND              J99   -281        A01X+076616Y+123203X0205Y0590R090 S1      
327GND              J99   -136        A01X+078230Y+122868X0205Y0590R090 S1      
327GND              J99   -284        A01X+076616Y+124207X0205Y0590R090 S1      
327GND              J29   -251        A01X+073646Y+113164X0205Y0590R090 S1      
327GND              J29   -259        A01X+073646Y+115841X0205Y0590R090 S1      
327GND              J29   -262        A01X+073646Y+116845X0205Y0590R090 S1      
327GND              J29   -114        A01X+075260Y+115506X0205Y0590R090 S1      
327GND              J29   -117        A01X+075260Y+116510X0205Y0590R090 S1      
327GND              J99   -251        A01X+076616Y+113164X0205Y0590R090 S1      
327GND              J99   -259        A01X+076616Y+115841X0205Y0590R090 S1      
327GND              J99   -114        A01X+078230Y+115506X0205Y0590R090 S1      
327GND              J99   -262        A01X+076616Y+116845X0205Y0590R090 S1      
327GND              J99   -117        A01X+078230Y+116510X0205Y0590R090 S1      
327GND              J29   -240        A01X+073646Y+109482X0205Y0590R090 S1      
327GND              J29   -237        A01X+073646Y+108478X0205Y0590R090 S1      
327GND              J29   -248        A01X+073646Y+112160X0205Y0590R090 S1      
327GND              J29   -95         A01X+075260Y+109148X0205Y0590R090 S1      
327GND              J29   -92         A01X+075260Y+108144X0205Y0590R090 S1      
327GND              J29   -103        A01X+075260Y+111825X0205Y0590R090 S1      
327GND              J29   -106        A01X+075260Y+112829X0205Y0590R090 S1      
327GND              J99   -240        A01X+076616Y+109482X0205Y0590R090 S1      
327GND              J99   -95         A01X+078230Y+109148X0205Y0590R090 S1      
327GND              J99   -237        A01X+076616Y+108478X0205Y0590R090 S1      
327GND              J99   -92         A01X+078230Y+108144X0205Y0590R090 S1      
327GND              J99   -248        A01X+076616Y+112160X0205Y0590R090 S1      
327GND              J99   -103        A01X+078230Y+111825X0205Y0590R090 S1      
327GND              J99   -106        A01X+078230Y+112829X0205Y0590R090 S1      
327GND              J29   -191        A01X+073646Y+091077X0205Y0590R090 S1      
327GND              J29   -202        A01X+073646Y+094758X0205Y0590R090 S1      
327GND              J29   -199        A01X+073646Y+093754X0205Y0590R090 S1      
327GND              J29   -46         A01X+075260Y+090742X0205Y0590R090 S1      
327GND              J29   -54         A01X+075260Y+093419X0205Y0590R090 S1      
327GND              J29   -57         A01X+075260Y+094423X0205Y0590R090 S1      
327GND              J99   -191        A01X+076616Y+091077X0205Y0590R090 S1      
327GND              J99   -46         A01X+078230Y+090742X0205Y0590R090 S1      
327GND              J99   -54         A01X+078230Y+093419X0205Y0590R090 S1      
327GND              J99   -202        A01X+076616Y+094758X0205Y0590R090 S1      
327GND              J99   -199        A01X+076616Y+093754X0205Y0590R090 S1      
327GND              J99   -57         A01X+078230Y+094423X0205Y0590R090 S1      
327GND              J29   -177        A01X+073646Y+086392X0205Y0590R090 S1      
327GND              J29   -180        A01X+073646Y+087396X0205Y0590R090 S1      
327GND              J29   -188        A01X+073646Y+090073X0205Y0590R090 S1      
327GND              J29   -35         A01X+075260Y+087061X0205Y0590R090 S1      
327GND              J29   -32         A01X+075260Y+086057X0205Y0590R090 S1      
327GND              J29   -43         A01X+075260Y+089738X0205Y0590R090 S1      
327GND              J99   -32         A01X+078230Y+086057X0205Y0590R090 S1      
327GND              J99   -177        A01X+076616Y+086392X0205Y0590R090 S1      
327GND              J99   -35         A01X+078230Y+087061X0205Y0590R090 S1      
327GND              J99   -180        A01X+076616Y+087396X0205Y0590R090 S1      
327GND              J99   -188        A01X+076616Y+090073X0205Y0590R090 S1      
327GND              J99   -43         A01X+078230Y+089738X0205Y0590R090 S1      
327GND              J29   -158        A01X+073646Y+080034X0205Y0590R090 S1      
327GND              J29   -169        A01X+073646Y+083715X0205Y0590R090 S1      
327GND              J29   -166        A01X+073646Y+082711X0205Y0590R090 S1      
327GND              J29   -13         A01X+075260Y+079699X0205Y0590R090 S1      
327GND              J29   -24         A01X+075260Y+083380X0205Y0590R090 S1      
327GND              J29   -21         A01X+075260Y+082376X0205Y0590R090 S1      
327GND              J99   -158        A01X+076616Y+080034X0205Y0590R090 S1      
327GND              J99   -13         A01X+078230Y+079699X0205Y0590R090 S1      
327GND              J99   -169        A01X+076616Y+083715X0205Y0590R090 S1      
327GND              J99   -166        A01X+076616Y+082711X0205Y0590R090 S1      
327GND              J99   -24         A01X+078230Y+083380X0205Y0590R090 S1      
327GND              J99   -21         A01X+078230Y+082376X0205Y0590R090 S1      
327GND              J29   -155        A01X+073646Y+079030X0205Y0590R090 S1      
327GND              J29   -10         A01X+075260Y+078695X0205Y0590R090 S1      
327GND              J99   -155        A01X+076616Y+079030X0205Y0590R090 S1      
327GND              J99   -10         A01X+078230Y+078695X0205Y0590R090 S1      
327GND              J100  -273        A01X+070676Y+120526X0205Y0590R090 S1      
327GND              J100  -270        A01X+070676Y+119522X0205Y0590R090 S1      
327GND              J100  -281        A01X+070676Y+123203X0205Y0590R090 S1      
327GND              J100  -284        A01X+070676Y+124207X0205Y0590R090 S1      
327GND              J100  -128        A01X+072290Y+120191X0205Y0590R090 S1      
327GND              J100  -125        A01X+072290Y+119187X0205Y0590R090 S1      
327GND              J100  -139        A01X+072290Y+123872X0205Y0590R090 S1      
327GND              J100  -136        A01X+072290Y+122868X0205Y0590R090 S1      
327GND              J100  -251        A01X+070676Y+113164X0205Y0590R090 S1      
327GND              J100  -259        A01X+070676Y+115841X0205Y0590R090 S1      
327GND              J100  -262        A01X+070676Y+116845X0205Y0590R090 S1      
327GND              J100  -114        A01X+072290Y+115506X0205Y0590R090 S1      
327GND              J100  -117        A01X+072290Y+116510X0205Y0590R090 S1      
327GND              J100  -240        A01X+070676Y+109482X0205Y0590R090 S1      
327GND              J100  -237        A01X+070676Y+108478X0205Y0590R090 S1      
327GND              J100  -248        A01X+070676Y+112160X0205Y0590R090 S1      
327GND              J100  -95         A01X+072290Y+109148X0205Y0590R090 S1      
327GND              J100  -92         A01X+072290Y+108144X0205Y0590R090 S1      
327GND              J100  -103        A01X+072290Y+111825X0205Y0590R090 S1      
327GND              J100  -106        A01X+072290Y+112829X0205Y0590R090 S1      
327GND              J100  -191        A01X+070676Y+091077X0205Y0590R090 S1      
327GND              J100  -202        A01X+070676Y+094758X0205Y0590R090 S1      
327GND              J100  -199        A01X+070676Y+093754X0205Y0590R090 S1      
327GND              J100  -46         A01X+072290Y+090742X0205Y0590R090 S1      
327GND              J100  -54         A01X+072290Y+093419X0205Y0590R090 S1      
327GND              J100  -57         A01X+072290Y+094423X0205Y0590R090 S1      
327GND              J100  -177        A01X+070676Y+086392X0205Y0590R090 S1      
327GND              J100  -180        A01X+070676Y+087396X0205Y0590R090 S1      
327GND              J100  -188        A01X+070676Y+090073X0205Y0590R090 S1      
327GND              J100  -35         A01X+072290Y+087061X0205Y0590R090 S1      
327GND              J100  -32         A01X+072290Y+086057X0205Y0590R090 S1      
327GND              J100  -43         A01X+072290Y+089738X0205Y0590R090 S1      
327GND              J100  -158        A01X+070676Y+080034X0205Y0590R090 S1      
327GND              J100  -166        A01X+070676Y+082711X0205Y0590R090 S1      
327GND              J100  -169        A01X+070676Y+083715X0205Y0590R090 S1      
327GND              J100  -13         A01X+072290Y+079699X0205Y0590R090 S1      
327GND              J100  -24         A01X+072290Y+083380X0205Y0590R090 S1      
327GND              J100  -21         A01X+072290Y+082376X0205Y0590R090 S1      
327GND              J100  -155        A01X+070676Y+079030X0205Y0590R090 S1      
327GND              J100  -10         A01X+072290Y+078695X0205Y0590R090 S1      
317GND              J102  -G3  MD0480PA00X+065542Y+127770X0680Y1370R090 S3      
317GND              J27   -G3  MD0480PA00X+068513Y+127770X0680Y1370R090 S3      
317GND              VIA   -    MD0100PA00X+077601Y+138075X0200Y         S0      
317GND              H49   -1   MD1470PA00X+079168Y+138514X2440Y         S3      
317GND              PC522 -2   MD0400PA00X+075464Y+143674X0600Y    R180 S3      
317GND              H22   -1   MD1470PA00X+068144Y+138514X2440Y         S3      
317GND              VIA   -    MD0100PA00X+081640Y+123370X0190Y         S0      
317GND              VIA   -    MD0100PA00X+081640Y+082878X0190Y         S0      
317GND              VIA   -    MD0100PA00X+081640Y+086559X0190Y         S0      
317GND              VIA   -    MD0100PA00X+081640Y+090240X0190Y         S0      
317GND              VIA   -    MD0100PA00X+081640Y+093921X0190Y         S0      
317GND              VIA   -    MD0100PA00X+081640Y+108646X0190Y         S0      
317GND              VIA   -    MD0100PA00X+081640Y+112327X0190Y         S0      
317GND              VIA   -    MD0100PA00X+081640Y+116008X0190Y         S0      
317GND              VIA   -    MD0100PA00X+081640Y+119689X0190Y         S0      
317GND              VIA   -    MD0100PA00X+080131Y+124207X0190Y    R180 S0      
317GND              VIA   -    MD0100PA00X+080131Y+116845X0190Y    R180 S0      
317GND              VIA   -    MD0100PA00X+081200Y+117179X0190Y         S0      
317GND              VIA   -    MD0100PA00X+081200Y+117849X0190Y         S0      
317GND              VIA   -    MD0100PA00X+080655Y+119187X0190Y         S0      
317GND              VIA   -    MD0100PA00X+081200Y+118518X0190Y         S0      
317GND              VIA   -    MD0100PA00X+080026Y+120024X0190Y         S0      
317GND              VIA   -    MD0100PA00X+080131Y+120526X0190Y    R180 S0      
317GND              VIA   -    MD0100PA00X+080655Y+120191X0190Y         S0      
317GND              VIA   -    MD0100PA00X+080131Y+119522X0190Y    R180 S0      
317GND              VIA   -    MD0100PA00X+081200Y+120860X0190Y         S0      
317GND              VIA   -    MD0100PA00X+081200Y+121530X0190Y         S0      
317GND              VIA   -    MD0100PA00X+081200Y+122199X0190Y         S0      
317GND              VIA   -    MD0100PA00X+080026Y+123705X0190Y         S0      
317GND              VIA   -    MD0100PA00X+080655Y+123872X0190Y         S0      
317GND              VIA   -    MD0100PA00X+080131Y+123203X0190Y    R180 S0      
317GND              VIA   -    MD0100PA00X+080655Y+122868X0190Y         S0      
317GND              VIA   -    MD0100PA00X+081200Y+125211X0190Y         S0      
317GND              VIA   -    MD0100PA00X+081200Y+124542X0190Y         S0      
317GND              VIA   -    MD0100PA00X+080131Y+108478X0190Y    R180 S0      
317GND              VIA   -    MD0100PA00X+080026Y+108980X0190Y         S0      
317GND              VIA   -    MD0100PA00X+080655Y+108144X0190Y         S0      
317GND              VIA   -    MD0100PA00X+080131Y+109482X0190Y    R180 S0      
317GND              VIA   -    MD0100PA00X+080655Y+109148X0190Y         S0      
317GND              VIA   -    MD0100PA00X+081200Y+110486X0190Y         S0      
317GND              VIA   -    MD0100PA00X+081200Y+109817X0190Y         S0      
317GND              VIA   -    MD0100PA00X+080655Y+111825X0190Y         S0      
317GND              VIA   -    MD0100PA00X+081200Y+111156X0190Y         S0      
317GND              VIA   -    MD0100PA00X+080131Y+113164X0190Y    R180 S0      
317GND              VIA   -    MD0100PA00X+081200Y+113498X0190Y         S0      
317GND              VIA   -    MD0100PA00X+080131Y+112160X0190Y    R180 S0      
317GND              VIA   -    MD0100PA00X+080026Y+112662X0190Y         S0      
317GND              VIA   -    MD0100PA00X+080655Y+112829X0190Y         S0      
317GND              VIA   -    MD0100PA00X+081200Y+114168X0190Y         S0      
317GND              VIA   -    MD0100PA00X+081200Y+114837X0190Y         S0      
317GND              VIA   -    MD0100PA00X+080131Y+115841X0190Y    R180 S0      
317GND              VIA   -    MD0100PA00X+080655Y+115506X0190Y         S0      
317GND              VIA   -    MD0100PA00X+080026Y+116343X0190Y         S0      
317GND              VIA   -    MD0100PA00X+080655Y+116510X0190Y         S0      
317GND              VIA   -    MD0100PA00X+081200Y+097770X0190Y         S0      
317GND              VIA   -    MD0100PA00X+081200Y+098439X0190Y         S0      
317GND              VIA   -    MD0100PA00X+081200Y+099108X0190Y         S0      
317GND              VIA   -    MD0100PA00X+081200Y+099778X0190Y         S0      
317GND              VIA   -    MD0100PA00X+081200Y+100447X0190Y         S0      
317GND              VIA   -    MD0100PA00X+081200Y+103124X0190Y         S0      
317GND              VIA   -    MD0100PA00X+081200Y+103793X0190Y         S0      
317GND              VIA   -    MD0100PA00X+081200Y+104463X0190Y         S0      
317GND              VIA   -    MD0100PA00X+081200Y+105132X0190Y         S0      
317GND              VIA   -    MD0100PA00X+081200Y+105801X0190Y         S0      
317GND              VIA   -    MD0100PA00X+081200Y+107474X0190Y         S0      
317GND              VIA   -    MD0100PA00X+081200Y+106805X0190Y         S0      
317GND              VIA   -    MD0100PA00X+081200Y+088400X0190Y         S0      
317GND              VIA   -    MD0100PA00X+081200Y+089069X0190Y         S0      
317GND              VIA   -    MD0100PA00X+080131Y+091077X0190Y    R180 S0      
317GND              VIA   -    MD0100PA00X+080026Y+090575X0190Y         S0      
317GND              VIA   -    MD0100PA00X+080655Y+090742X0190Y         S0      
317GND              VIA   -    MD0100PA00X+080131Y+090073X0190Y    R180 S0      
317GND              VIA   -    MD0100PA00X+080655Y+089738X0190Y         S0      
317GND              VIA   -    MD0100PA00X+081200Y+091412X0190Y         S0      
317GND              VIA   -    MD0100PA00X+081200Y+092081X0190Y         S0      
317GND              VIA   -    MD0100PA00X+080655Y+093419X0190Y         S0      
317GND              VIA   -    MD0100PA00X+081200Y+092750X0190Y         S0      
317GND              VIA   -    MD0100PA00X+080131Y+093754X0190Y    R180 S0      
317GND              VIA   -    MD0100PA00X+080655Y+094423X0190Y         S0      
317GND              VIA   -    MD0100PA00X+080131Y+094758X0190Y    R180 S0      
317GND              VIA   -    MD0100PA00X+080026Y+094256X0190Y         S0      
317GND              VIA   -    MD0100PA00X+081200Y+095093X0190Y         S0      
317GND              VIA   -    MD0100PA00X+081200Y+096431X0190Y         S0      
317GND              VIA   -    MD0100PA00X+081200Y+097100X0190Y         S0      
317GND              VIA   -    MD0100PA00X+081200Y+095762X0190Y         S0      
317GND              VIA   -    MD0100PA00X+080131Y+080034X0190Y    R180 S0      
317GND              VIA   -    MD0100PA00X+080026Y+079532X0190Y         S0      
317GND              VIA   -    MD0100PA00X+080655Y+079699X0190Y         S0      
317GND              VIA   -    MD0100PA00X+081200Y+080368X0190Y         S0      
317GND              VIA   -    MD0100PA00X+081200Y+081038X0190Y         S0      
317GND              VIA   -    MD0100PA00X+081200Y+081707X0190Y         S0      
317GND              VIA   -    MD0100PA00X+080655Y+082376X0190Y         S0      
317GND              VIA   -    MD0100PA00X+080655Y+083380X0190Y         S0      
317GND              VIA   -    MD0100PA00X+080131Y+082711X0190Y    R180 S0      
317GND              VIA   -    MD0100PA00X+080131Y+083715X0190Y    R180 S0      
317GND              VIA   -    MD0100PA00X+080026Y+083213X0190Y         S0      
317GND              VIA   -    MD0100PA00X+081200Y+084049X0190Y         S0      
317GND              VIA   -    MD0100PA00X+081200Y+084719X0190Y         S0      
317GND              VIA   -    MD0100PA00X+081200Y+085388X0190Y         S0      
317GND              VIA   -    MD0100PA00X+080131Y+086392X0190Y    R180 S0      
317GND              VIA   -    MD0100PA00X+080655Y+086057X0190Y         S0      
317GND              VIA   -    MD0100PA00X+080026Y+086894X0190Y         S0      
317GND              VIA   -    MD0100PA00X+080655Y+087061X0190Y         S0      
317GND              VIA   -    MD0100PA00X+080131Y+087396X0190Y    R180 S0      
317GND              VIA   -    MD0100PA00X+081200Y+087730X0190Y         S0      
317GND              VIA   -    MD0100PA00X+080131Y+079030X0190Y    R180 S0      
317GND              VIA   -    MD0100PA00X+080655Y+078695X0190Y         S0      
317GND              VIA   -    MD0100PA00X+081200Y+078026X0190Y         S0      
317GND              VIA   -    MD0100PA00X+078670Y+119689X0190Y         S0      
317GND              VIA   -    MD0100PA00X+079586Y+121195X0190Y         S0      
317GND              VIA   -    MD0100PA00X+079586Y+121864X0190Y         S0      
317GND              VIA   -    MD0100PA00X+079586Y+122534X0190Y         S0      
317GND              VIA   -    MD0100PA00X+078670Y+123370X0190Y         S0      
317GND              VIA   -    MD0100PA00X+079586Y+124876X0190Y         S0      
317GND              VIA   -    MD0100PA00X+079586Y+125545X0190Y         S0      
317GND              VIA   -    MD0100PA00X+079586Y+113833X0190Y         S0      
317GND              VIA   -    MD0100PA00X+079586Y+114502X0190Y         S0      
317GND              VIA   -    MD0100PA00X+079586Y+115171X0190Y         S0      
317GND              VIA   -    MD0100PA00X+078670Y+116008X0190Y         S0      
317GND              VIA   -    MD0100PA00X+079586Y+117514X0190Y         S0      
317GND              VIA   -    MD0100PA00X+079586Y+118852X0190Y         S0      
317GND              VIA   -    MD0100PA00X+079586Y+118183X0190Y         S0      
317GND              VIA   -    MD0100PA00X+079586Y+107809X0190Y         S0      
317GND              VIA   -    MD0100PA00X+078670Y+108646X0190Y         S0      
317GND              VIA   -    MD0100PA00X+079586Y+110152X0190Y         S0      
317GND              VIA   -    MD0100PA00X+079586Y+110821X0190Y         S0      
317GND              VIA   -    MD0100PA00X+079586Y+111490X0190Y         S0      
317GND              VIA   -    MD0100PA00X+078670Y+112327X0190Y         S0      
317GND              VIA   -    MD0100PA00X+079586Y+098774X0190Y         S0      
317GND              VIA   -    MD0100PA00X+079586Y+099443X0190Y         S0      
317GND              VIA   -    MD0100PA00X+079586Y+100447X0190Y         S0      
317GND              VIA   -    MD0100PA00X+079586Y+103459X0190Y         S0      
317GND              VIA   -    MD0100PA00X+079586Y+104128X0190Y         S0      
317GND              VIA   -    MD0100PA00X+079586Y+104797X0190Y         S0      
317GND              VIA   -    MD0100PA00X+079586Y+105467X0190Y         S0      
317GND              VIA   -    MD0100PA00X+079586Y+106136X0190Y         S0      
317GND              VIA   -    MD0100PA00X+079586Y+107140X0190Y         S0      
317GND              VIA   -    MD0100PA00X+079586Y+095427X0190Y         S0      
317GND              VIA   -    MD0100PA00X+079586Y+096766X0190Y         S0      
317GND              VIA   -    MD0100PA00X+079586Y+096097X0190Y         S0      
317GND              VIA   -    MD0100PA00X+079586Y+097435X0190Y         S0      
317GND              VIA   -    MD0100PA00X+079586Y+098104X0190Y         S0      
317GND              VIA   -    MD0100PA00X+079586Y+088734X0190Y         S0      
317GND              VIA   -    MD0100PA00X+079586Y+089404X0190Y         S0      
317GND              VIA   -    MD0100PA00X+078670Y+090240X0190Y         S0      
317GND              VIA   -    MD0100PA00X+079586Y+091746X0190Y         S0      
317GND              VIA   -    MD0100PA00X+079586Y+092416X0190Y         S0      
317GND              VIA   -    MD0100PA00X+079586Y+093085X0190Y         S0      
317GND              VIA   -    MD0100PA00X+078670Y+093921X0190Y         S0      
317GND              VIA   -    MD0100PA00X+078670Y+082878X0190Y         S0      
317GND              VIA   -    MD0100PA00X+079586Y+085053X0190Y         S0      
317GND              VIA   -    MD0100PA00X+079586Y+084384X0190Y         S0      
317GND              VIA   -    MD0100PA00X+079586Y+085723X0190Y         S0      
317GND              VIA   -    MD0100PA00X+078670Y+086559X0190Y         S0      
317GND              VIA   -    MD0100PA00X+079586Y+088065X0190Y         S0      
317GND              VIA   -    MD0100PA00X+079586Y+077691X0190Y         S0      
317GND              VIA   -    MD0100PA00X+078670Y+079197X0190Y         S0      
317GND              VIA   -    MD0100PA00X+079586Y+078360X0190Y         S0      
317GND              VIA   -    MD0100PA00X+079586Y+080703X0190Y         S0      
317GND              VIA   -    MD0100PA00X+079586Y+081372X0190Y         S0      
317GND              VIA   -    MD0100PA00X+079586Y+082042X0190Y         S0      
317GND              VIA   -    MD0100PA00X+077056Y+123705X0190Y         S0      
317GND              VIA   -    MD0100PA00X+077685Y+123872X0190Y         S0      
317GND              VIA   -    MD0100PA00X+077161Y+123203X0190Y    R180 S0      
317GND              VIA   -    MD0100PA00X+077685Y+122868X0190Y         S0      
317GND              VIA   -    MD0100PA00X+078230Y+124542X0190Y         S0      
317GND              VIA   -    MD0100PA00X+078230Y+125211X0190Y         S0      
317GND              VIA   -    MD0100PA00X+077161Y+124207X0190Y    R180 S0      
317GND              VIA   -    MD0100PA00X+076952Y+129720X0200Y         S0      
317GND              VIA   -    MD0100PA00X+076952Y+130230X0200Y         S0      
317GND              VIA   -    MD0100PA00X+076952Y+129970X0200Y         S0      
317GND              VIA   -    MD0100PA00X+076952Y+130490X0200Y         S0      
317GND              VIA   -    MD0100PA00X+077047Y+137550X0200Y         S0      
317GND              VIA   -    MD0100PA00X+077307Y+137550X0200Y         S0      
317GND              VIA   -    MD0100PA00X+078230Y+117179X0190Y         S0      
317GND              VIA   -    MD0100PA00X+077161Y+116845X0190Y    R180 S0      
317GND              VIA   -    MD0100PA00X+078230Y+117849X0190Y         S0      
317GND              VIA   -    MD0100PA00X+077685Y+119187X0190Y         S0      
317GND              VIA   -    MD0100PA00X+078230Y+118518X0190Y         S0      
317GND              VIA   -    MD0100PA00X+077161Y+120526X0190Y    R180 S0      
317GND              VIA   -    MD0100PA00X+077685Y+120191X0190Y         S0      
317GND              VIA   -    MD0100PA00X+077056Y+120024X0190Y         S0      
317GND              VIA   -    MD0100PA00X+077161Y+119522X0190Y    R180 S0      
317GND              VIA   -    MD0100PA00X+078230Y+120860X0190Y         S0      
317GND              VIA   -    MD0100PA00X+078230Y+122199X0190Y         S0      
317GND              VIA   -    MD0100PA00X+078230Y+121530X0190Y         S0      
317GND              VIA   -    MD0100PA00X+078230Y+113498X0190Y         S0      
317GND              VIA   -    MD0100PA00X+077161Y+113164X0190Y    R180 S0      
317GND              VIA   -    MD0100PA00X+077161Y+112160X0190Y    R180 S0      
317GND              VIA   -    MD0100PA00X+077056Y+112662X0190Y         S0      
317GND              VIA   -    MD0100PA00X+077685Y+112829X0190Y         S0      
317GND              VIA   -    MD0100PA00X+078230Y+114168X0190Y         S0      
317GND              VIA   -    MD0100PA00X+078230Y+114837X0190Y         S0      
317GND              VIA   -    MD0100PA00X+077161Y+115841X0190Y    R180 S0      
317GND              VIA   -    MD0100PA00X+077685Y+115506X0190Y         S0      
317GND              VIA   -    MD0100PA00X+077056Y+116343X0190Y         S0      
317GND              VIA   -    MD0100PA00X+077685Y+116510X0190Y         S0      
317GND              VIA   -    MD0100PA00X+077056Y+108980X0190Y         S0      
317GND              VIA   -    MD0100PA00X+077161Y+108478X0190Y    R180 S0      
317GND              VIA   -    MD0100PA00X+077685Y+108144X0190Y         S0      
317GND              VIA   -    MD0100PA00X+077161Y+109482X0190Y    R180 S0      
317GND              VIA   -    MD0100PA00X+077685Y+109148X0190Y         S0      
317GND              VIA   -    MD0100PA00X+078230Y+110486X0190Y         S0      
317GND              VIA   -    MD0100PA00X+078230Y+109817X0190Y         S0      
317GND              VIA   -    MD0100PA00X+078230Y+111156X0190Y         S0      
317GND              VIA   -    MD0100PA00X+077685Y+111825X0190Y         S0      
317GND              VIA   -    MD0100PA00X+078230Y+100447X0190Y         S0      
317GND              VIA   -    MD0100PA00X+078230Y+104463X0190Y         S0      
317GND              VIA   -    MD0100PA00X+078230Y+103793X0190Y         S0      
317GND              VIA   -    MD0100PA00X+078230Y+103124X0190Y         S0      
317GND              VIA   -    MD0100PA00X+078230Y+105801X0190Y         S0      
317GND              VIA   -    MD0100PA00X+078230Y+105132X0190Y         S0      
317GND              VIA   -    MD0100PA00X+078230Y+107474X0190Y         S0      
317GND              VIA   -    MD0100PA00X+078230Y+106805X0190Y         S0      
317GND              VIA   -    MD0100PA00X+078230Y+095093X0190Y         S0      
317GND              VIA   -    MD0100PA00X+077056Y+094256X0190Y         S0      
317GND              VIA   -    MD0100PA00X+077161Y+094758X0190Y    R180 S0      
317GND              VIA   -    MD0100PA00X+077685Y+094423X0190Y         S0      
317GND              VIA   -    MD0100PA00X+078230Y+096431X0190Y         S0      
317GND              VIA   -    MD0100PA00X+078230Y+097100X0190Y         S0      
317GND              VIA   -    MD0100PA00X+078230Y+095762X0190Y         S0      
317GND              VIA   -    MD0100PA00X+078230Y+097770X0190Y         S0      
317GND              VIA   -    MD0100PA00X+078230Y+098439X0190Y         S0      
317GND              VIA   -    MD0100PA00X+078230Y+099778X0190Y         S0      
317GND              VIA   -    MD0100PA00X+078230Y+099108X0190Y         S0      
317GND              VIA   -    MD0100PA00X+077056Y+090575X0190Y         S0      
317GND              VIA   -    MD0100PA00X+077161Y+091077X0190Y    R180 S0      
317GND              VIA   -    MD0100PA00X+077685Y+090742X0190Y         S0      
317GND              VIA   -    MD0100PA00X+077161Y+090073X0190Y    R180 S0      
317GND              VIA   -    MD0100PA00X+077685Y+089738X0190Y         S0      
317GND              VIA   -    MD0100PA00X+078230Y+091412X0190Y         S0      
317GND              VIA   -    MD0100PA00X+078230Y+092081X0190Y         S0      
317GND              VIA   -    MD0100PA00X+078230Y+092750X0190Y         S0      
317GND              VIA   -    MD0100PA00X+077685Y+093419X0190Y         S0      
317GND              VIA   -    MD0100PA00X+077161Y+093754X0190Y    R180 S0      
317GND              VIA   -    MD0100PA00X+078230Y+084049X0190Y         S0      
317GND              VIA   -    MD0100PA00X+078230Y+085388X0190Y         S0      
317GND              VIA   -    MD0100PA00X+077161Y+086392X0190Y    R180 S0      
317GND              VIA   -    MD0100PA00X+077685Y+086057X0190Y         S0      
317GND              VIA   -    MD0100PA00X+077056Y+086894X0190Y         S0      
317GND              VIA   -    MD0100PA00X+077685Y+087061X0190Y         S0      
317GND              VIA   -    MD0100PA00X+078230Y+087730X0190Y         S0      
317GND              VIA   -    MD0100PA00X+077161Y+087396X0190Y    R180 S0      
317GND              VIA   -    MD0100PA00X+078230Y+088400X0190Y         S0      
317GND              VIA   -    MD0100PA00X+078230Y+089069X0190Y         S0      
317GND              VIA   -    MD0100PA00X+078230Y+080368X0190Y         S0      
317GND              VIA   -    MD0100PA00X+077056Y+079532X0190Y         S0      
317GND              VIA   -    MD0100PA00X+077161Y+080034X0190Y    R180 S0      
317GND              VIA   -    MD0100PA00X+077685Y+079699X0190Y         S0      
317GND              VIA   -    MD0100PA00X+078230Y+081707X0190Y         S0      
317GND              VIA   -    MD0100PA00X+078230Y+081038X0190Y         S0      
317GND              VIA   -    MD0100PA00X+077161Y+082711X0190Y    R180 S0      
317GND              VIA   -    MD0100PA00X+077685Y+083380X0190Y         S0      
317GND              VIA   -    MD0100PA00X+077685Y+082376X0190Y         S0      
317GND              VIA   -    MD0100PA00X+077056Y+083213X0190Y         S0      
317GND              VIA   -    MD0100PA00X+077161Y+083715X0190Y    R180 S0      
317GND              VIA   -    MD0100PA00X+078230Y+084719X0190Y         S0      
317GND              VIA   -    MD0100PA00X+078230Y+078026X0190Y         S0      
317GND              VIA   -    MD0100PA00X+077161Y+079030X0190Y    R180 S0      
317GND              VIA   -    MD0100PA00X+077685Y+078695X0190Y         S0      
317GND              VIA   -    MD0100PA00X+076558Y+137548X0200Y         S0      
327GND              PU45  -7_9-M      A01X+075294Y+137862X0827Y2126R090 S1      
317GND              VIA   -    MD0100PA00X+076056Y+137553X0193Y         S0      
317GND              VIA   -    MD0100PA00X+075812Y+137552X0193Y         S0      
317GND              VIA   -    MD0100PA00X+075562Y+137552X0193Y         S0      
317GND              VIA   -    MD0100PA00X+076180Y+134913X0200Y         S0      
317GND              VIA   -    MD0100PA00X+076180Y+135203X0200Y         S0      
317GND              VIA   -    MD0100PA00X+076423Y+137038X0200Y         S0      
317GND              VIA   -    MD0100PA00X+076423Y+136778X0200Y         S0      
317GND              VIA   -    MD0100PA00X+076683Y+136778X0200Y         S0      
317GND              VIA   -    MD0100PA00X+076683Y+137038X0200Y         S0      
317GND              VIA   -    MD0100PA00X+076683Y+137288X0200Y         S0      
317GND              VIA   -    MD0100PA00X+076423Y+137288X0200Y         S0      
317GND              VIA   -    MD0100PA00X+076113Y+137798X0193Y         S0      
317GND              VIA   -    MD0100PA00X+076113Y+138093X0193Y         S0      
317GND              VIA   -    MD0100PA00X+075700Y+119689X0190Y         S0      
317GND              VIA   -    MD0100PA00X+076616Y+121864X0190Y         S0      
317GND              VIA   -    MD0100PA00X+076616Y+121195X0190Y         S0      
317GND              VIA   -    MD0100PA00X+075700Y+123370X0190Y         S0      
317GND              VIA   -    MD0100PA00X+076616Y+122534X0190Y         S0      
317GND              VIA   -    MD0100PA00X+076616Y+124876X0190Y         S0      
317GND              VIA   -    MD0100PA00X+076616Y+125545X0190Y         S0      
317GND              VIA   -    MD0100PA00X+075985Y+129725X0200Y         S0      
317GND              VIA   -    MD0100PA00X+075985Y+129975X0200Y         S0      
317GND              VIA   -    MD0100PA00X+075985Y+130235X0200Y         S0      
317GND              VIA   -    MD0100PA00X+075985Y+130495X0200Y         S0      
317GND              VIA   -    MD0100PA00X+076616Y+115171X0190Y         S0      
317GND              VIA   -    MD0100PA00X+075700Y+116008X0190Y         S0      
317GND              VIA   -    MD0100PA00X+076616Y+117514X0190Y         S0      
317GND              VIA   -    MD0100PA00X+076616Y+118852X0190Y         S0      
317GND              VIA   -    MD0100PA00X+076616Y+118183X0190Y         S0      
317GND              VIA   -    MD0100PA00X+076616Y+110152X0190Y         S0      
317GND              VIA   -    MD0100PA00X+076616Y+110821X0190Y         S0      
317GND              VIA   -    MD0100PA00X+076616Y+111490X0190Y         S0      
317GND              VIA   -    MD0100PA00X+075700Y+112327X0190Y         S0      
317GND              VIA   -    MD0100PA00X+076616Y+113833X0190Y         S0      
317GND              VIA   -    MD0100PA00X+076616Y+114502X0190Y         S0      
317GND              VIA   -    MD0100PA00X+076616Y+103459X0190Y         S0      
317GND              VIA   -    MD0100PA00X+076616Y+104128X0190Y         S0      
317GND              VIA   -    MD0100PA00X+076616Y+105467X0190Y         S0      
317GND              VIA   -    MD0100PA00X+076616Y+104797X0190Y         S0      
317GND              VIA   -    MD0100PA00X+076616Y+106136X0190Y         S0      
317GND              VIA   -    MD0100PA00X+076616Y+107140X0190Y         S0      
317GND              VIA   -    MD0100PA00X+076616Y+107809X0190Y         S0      
317GND              VIA   -    MD0100PA00X+075700Y+108646X0190Y         S0      
317GND              VIA   -    MD0100PA00X+076616Y+096766X0190Y         S0      
317GND              VIA   -    MD0100PA00X+076616Y+096097X0190Y         S0      
317GND              VIA   -    MD0100PA00X+076616Y+098104X0190Y         S0      
317GND              VIA   -    MD0100PA00X+076616Y+097435X0190Y         S0      
317GND              VIA   -    MD0100PA00X+076616Y+099443X0190Y         S0      
317GND              VIA   -    MD0100PA00X+076616Y+098774X0190Y         S0      
317GND              VIA   -    MD0100PA00X+076616Y+100447X0190Y         S0      
317GND              VIA   -    MD0100PA00X+076616Y+091746X0190Y         S0      
317GND              VIA   -    MD0100PA00X+076616Y+092416X0190Y         S0      
317GND              VIA   -    MD0100PA00X+076616Y+093085X0190Y         S0      
317GND              VIA   -    MD0100PA00X+075700Y+093921X0190Y         S0      
317GND              VIA   -    MD0100PA00X+076616Y+095427X0190Y         S0      
317GND              VIA   -    MD0100PA00X+075700Y+086559X0190Y         S0      
317GND              VIA   -    MD0100PA00X+076616Y+085723X0190Y         S0      
317GND              VIA   -    MD0100PA00X+076616Y+088065X0190Y         S0      
317GND              VIA   -    MD0100PA00X+076616Y+089404X0190Y         S0      
317GND              VIA   -    MD0100PA00X+076616Y+088734X0190Y         S0      
317GND              VIA   -    MD0100PA00X+075700Y+090240X0190Y         S0      
317GND              VIA   -    MD0100PA00X+076616Y+082042X0190Y         S0      
317GND              VIA   -    MD0100PA00X+076616Y+081372X0190Y         S0      
317GND              VIA   -    MD0100PA00X+075700Y+082878X0190Y         S0      
317GND              VIA   -    MD0100PA00X+076616Y+085053X0190Y         S0      
317GND              VIA   -    MD0100PA00X+076616Y+084384X0190Y         S0      
317GND              VIA   -    MD0100PA00X+076616Y+077691X0190Y         S0      
317GND              VIA   -    MD0100PA00X+075700Y+079197X0190Y         S0      
317GND              VIA   -    MD0100PA00X+076616Y+078360X0190Y         S0      
317GND              VIA   -    MD0100PA00X+076616Y+080703X0190Y         S0      
327GND              PU45  -40  M      A01X+074949Y+138817X0690Y0770     S1      
317GND              VIA   -    MD0100PA00X+074949Y+139098X0193Y         S0      
317GND              VIA   -    MD0100PA00X+074706Y+139098X0193Y         S0      
317GND              VIA   -    MD0100PA00X+075192Y+139098X0193Y         S0      
327GND              PR329 -1          A01X+074938Y+140367X0198Y0197R180 S1      
317GND              VIA   -    MD0100PA00X+075197Y+140340X0200Y         S0      
317GND              VIA   -    MD0100PA00X+075260Y+124542X0190Y         S0      
317GND              VIA   -    MD0100PA00X+075260Y+125211X0190Y         S0      
317GND              VIA   -    MD0100PA00X+074191Y+124207X0190Y    R180 S0      
317GND              VIA   -    MD0100PA00X+074548Y+129725X0200Y         S0      
317GND              VIA   -    MD0100PA00X+074548Y+129975X0200Y         S0      
317GND              VIA   -    MD0100PA00X+074548Y+130235X0200Y         S0      
317GND              VIA   -    MD0100PA00X+074548Y+130495X0200Y         S0      
317GND              VIA   -    MD0100PA00X+073950Y+134913X0200Y         S0      
317GND              VIA   -    MD0100PA00X+073950Y+135203X0200Y         S0      
317GND              VIA   -    MD0100PA00X+075192Y+138538X0193Y         S0      
317GND              VIA   -    MD0100PA00X+074949Y+138538X0193Y         S0      
317GND              VIA   -    MD0100PA00X+075042Y+137552X0193Y         S0      
317GND              VIA   -    MD0100PA00X+075042Y+137862X0193Y         S0      
317GND              VIA   -    MD0100PA00X+075042Y+138158X0193Y         S0      
317GND              VIA   -    MD0100PA00X+074522Y+137552X0193Y         S0      
317GND              VIA   -    MD0100PA00X+074782Y+137552X0193Y         S0      
317GND              VIA   -    MD0100PA00X+074782Y+137862X0193Y         S0      
317GND              VIA   -    MD0100PA00X+074522Y+137862X0193Y         S0      
317GND              VIA   -    MD0100PA00X+074706Y+138538X0193Y         S0      
317GND              VIA   -    MD0100PA00X+075302Y+137552X0193Y         S0      
317GND              VIA   -    MD0100PA00X+075302Y+137862X0193Y         S0      
317GND              VIA   -    MD0100PA00X+075302Y+138158X0193Y         S0      
317GND              VIA   -    MD0100PA00X+074191Y+120526X0190Y    R180 S0      
317GND              VIA   -    MD0100PA00X+074715Y+120191X0190Y         S0      
317GND              VIA   -    MD0100PA00X+074086Y+120024X0190Y         S0      
317GND              VIA   -    MD0100PA00X+074191Y+119522X0190Y    R180 S0      
317GND              VIA   -    MD0100PA00X+075260Y+120860X0190Y         S0      
317GND              VIA   -    MD0100PA00X+075260Y+122199X0190Y         S0      
317GND              VIA   -    MD0100PA00X+075260Y+121530X0190Y         S0      
317GND              VIA   -    MD0100PA00X+074086Y+123705X0190Y         S0      
317GND              VIA   -    MD0100PA00X+074715Y+123872X0190Y         S0      
317GND              VIA   -    MD0100PA00X+074191Y+123203X0190Y    R180 S0      
317GND              VIA   -    MD0100PA00X+074715Y+122868X0190Y         S0      
317GND              VIA   -    MD0100PA00X+074715Y+115506X0190Y         S0      
317GND              VIA   -    MD0100PA00X+074191Y+115841X0190Y    R180 S0      
317GND              VIA   -    MD0100PA00X+074715Y+116510X0190Y         S0      
317GND              VIA   -    MD0100PA00X+074086Y+116343X0190Y         S0      
317GND              VIA   -    MD0100PA00X+074191Y+116845X0190Y    R180 S0      
317GND              VIA   -    MD0100PA00X+075260Y+117179X0190Y         S0      
317GND              VIA   -    MD0100PA00X+075260Y+117849X0190Y         S0      
317GND              VIA   -    MD0100PA00X+074715Y+119187X0190Y         S0      
317GND              VIA   -    MD0100PA00X+075260Y+118518X0190Y         S0      
317GND              VIA   -    MD0100PA00X+074715Y+111825X0190Y         S0      
317GND              VIA   -    MD0100PA00X+075260Y+111156X0190Y         S0      
317GND              VIA   -    MD0100PA00X+074191Y+113164X0190Y    R180 S0      
317GND              VIA   -    MD0100PA00X+075260Y+113498X0190Y         S0      
317GND              VIA   -    MD0100PA00X+074191Y+112160X0190Y    R180 S0      
317GND              VIA   -    MD0100PA00X+074086Y+112662X0190Y         S0      
317GND              VIA   -    MD0100PA00X+074715Y+112829X0190Y         S0      
317GND              VIA   -    MD0100PA00X+075260Y+114168X0190Y         S0      
317GND              VIA   -    MD0100PA00X+075260Y+114837X0190Y         S0      
317GND              VIA   -    MD0100PA00X+075260Y+107474X0190Y         S0      
317GND              VIA   -    MD0100PA00X+075260Y+106805X0190Y         S0      
317GND              VIA   -    MD0100PA00X+074086Y+108980X0190Y         S0      
317GND              VIA   -    MD0100PA00X+074191Y+108478X0190Y    R180 S0      
317GND              VIA   -    MD0100PA00X+074715Y+108144X0190Y         S0      
317GND              VIA   -    MD0100PA00X+074715Y+109148X0190Y         S0      
317GND              VIA   -    MD0100PA00X+074191Y+109482X0190Y    R180 S0      
317GND              VIA   -    MD0100PA00X+075260Y+110486X0190Y         S0      
317GND              VIA   -    MD0100PA00X+075260Y+109817X0190Y         S0      
317GND              VIA   -    MD0100PA00X+075260Y+099778X0190Y         S0      
317GND              VIA   -    MD0100PA00X+075260Y+099108X0190Y         S0      
317GND              VIA   -    MD0100PA00X+075260Y+100447X0190Y         S0      
317GND              VIA   -    MD0100PA00X+075260Y+104463X0190Y         S0      
317GND              VIA   -    MD0100PA00X+075260Y+103793X0190Y         S0      
317GND              VIA   -    MD0100PA00X+075260Y+103124X0190Y         S0      
317GND              VIA   -    MD0100PA00X+075260Y+105801X0190Y         S0      
317GND              VIA   -    MD0100PA00X+075260Y+105132X0190Y         S0      
317GND              VIA   -    MD0100PA00X+074191Y+093754X0190Y    R180 S0      
317GND              VIA   -    MD0100PA00X+075260Y+092750X0190Y         S0      
317GND              VIA   -    MD0100PA00X+074086Y+094256X0190Y         S0      
317GND              VIA   -    MD0100PA00X+074191Y+094758X0190Y    R180 S0      
317GND              VIA   -    MD0100PA00X+074715Y+094423X0190Y         S0      
317GND              VIA   -    MD0100PA00X+075260Y+095093X0190Y         S0      
317GND              VIA   -    MD0100PA00X+075260Y+096431X0190Y         S0      
317GND              VIA   -    MD0100PA00X+075260Y+097100X0190Y         S0      
317GND              VIA   -    MD0100PA00X+075260Y+095762X0190Y         S0      
317GND              VIA   -    MD0100PA00X+075260Y+097770X0190Y         S0      
317GND              VIA   -    MD0100PA00X+075260Y+098439X0190Y         S0      
317GND              VIA   -    MD0100PA00X+074086Y+090575X0190Y         S0      
317GND              VIA   -    MD0100PA00X+074191Y+091077X0190Y    R180 S0      
317GND              VIA   -    MD0100PA00X+074715Y+090742X0190Y         S0      
317GND              VIA   -    MD0100PA00X+074191Y+090073X0190Y    R180 S0      
317GND              VIA   -    MD0100PA00X+074715Y+089738X0190Y         S0      
317GND              VIA   -    MD0100PA00X+075260Y+091412X0190Y         S0      
317GND              VIA   -    MD0100PA00X+075260Y+092081X0190Y         S0      
317GND              VIA   -    MD0100PA00X+074715Y+093419X0190Y         S0      
317GND              VIA   -    MD0100PA00X+075260Y+084719X0190Y         S0      
317GND              VIA   -    MD0100PA00X+075260Y+084049X0190Y         S0      
317GND              VIA   -    MD0100PA00X+074191Y+086392X0190Y    R180 S0      
317GND              VIA   -    MD0100PA00X+074715Y+086057X0190Y         S0      
317GND              VIA   -    MD0100PA00X+075260Y+085388X0190Y         S0      
317GND              VIA   -    MD0100PA00X+074086Y+086894X0190Y         S0      
317GND              VIA   -    MD0100PA00X+074715Y+087061X0190Y         S0      
317GND              VIA   -    MD0100PA00X+074191Y+087396X0190Y    R180 S0      
317GND              VIA   -    MD0100PA00X+075260Y+087730X0190Y         S0      
317GND              VIA   -    MD0100PA00X+075260Y+088400X0190Y         S0      
317GND              VIA   -    MD0100PA00X+075260Y+089069X0190Y         S0      
317GND              VIA   -    MD0100PA00X+074086Y+079532X0190Y         S0      
317GND              VIA   -    MD0100PA00X+074191Y+080034X0190Y    R180 S0      
317GND              VIA   -    MD0100PA00X+074715Y+079699X0190Y         S0      
317GND              VIA   -    MD0100PA00X+075260Y+080368X0190Y         S0      
317GND              VIA   -    MD0100PA00X+075260Y+081707X0190Y         S0      
317GND              VIA   -    MD0100PA00X+075260Y+081038X0190Y         S0      
317GND              VIA   -    MD0100PA00X+074086Y+083213X0190Y         S0      
317GND              VIA   -    MD0100PA00X+074191Y+083715X0190Y    R180 S0      
317GND              VIA   -    MD0100PA00X+074191Y+082711X0190Y    R180 S0      
317GND              VIA   -    MD0100PA00X+074715Y+083380X0190Y         S0      
317GND              VIA   -    MD0100PA00X+074715Y+082376X0190Y         S0      
317GND              VIA   -    MD0100PA00X+074191Y+079030X0190Y    R180 S0      
317GND              VIA   -    MD0100PA00X+074715Y+078695X0190Y         S0      
317GND              VIA   -    MD0100PA00X+075260Y+078026X0190Y         S0      
327GND              PU44  -7_9-M      A01X+072016Y+137852X0827Y2126R090 S1      
317GND              VIA   -    MD0100PA00X+072778Y+137543X0193Y         S0      
317GND              VIA   -    MD0100PA00X+072533Y+137542X0193Y         S0      
317GND              VIA   -    MD0100PA00X+073280Y+137538X0200Y         S0      
317GND              VIA   -    MD0100PA00X+073628Y+137958X0193Y         S0      
317GND              VIA   -    MD0100PA00X+073646Y+122534X0190Y         S0      
317GND              VIA   -    MD0100PA00X+072730Y+123370X0190Y         S0      
317GND              VIA   -    MD0100PA00X+073646Y+124876X0190Y         S0      
317GND              VIA   -    MD0100PA00X+073646Y+125545X0190Y         S0      
317GND              VIA   -    MD0100PA00X+073595Y+129755X0200Y         S0      
317GND              VIA   -    MD0100PA00X+073595Y+130005X0200Y         S0      
317GND              VIA   -    MD0100PA00X+073595Y+130265X0200Y         S0      
317GND              VIA   -    MD0100PA00X+073595Y+130525X0200Y         S0      
317GND              VIA   -    MD0100PA00X+073090Y+134923X0200Y         S0      
317GND              VIA   -    MD0100PA00X+072710Y+134908X0200Y         S0      
317GND              VIA   -    MD0100PA00X+073090Y+135213X0200Y         S0      
317GND              VIA   -    MD0100PA00X+072710Y+135198X0200Y         S0      
317GND              VIA   -    MD0100PA00X+073145Y+137028X0200Y         S0      
317GND              VIA   -    MD0100PA00X+073145Y+136768X0200Y         S0      
317GND              VIA   -    MD0100PA00X+073405Y+136768X0200Y         S0      
317GND              VIA   -    MD0100PA00X+073405Y+137028X0200Y         S0      
317GND              VIA   -    MD0100PA00X+073145Y+137288X0200Y         S0      
317GND              VIA   -    MD0100PA00X+073405Y+137288X0200Y         S0      
317GND              VIA   -    MD0100PA00X+072835Y+137788X0193Y         S0      
317GND              VIA   -    MD0100PA00X+072835Y+138083X0193Y         S0      
317GND              VIA   -    MD0100PA00X+073646Y+118852X0190Y         S0      
317GND              VIA   -    MD0100PA00X+073646Y+118183X0190Y         S0      
317GND              VIA   -    MD0100PA00X+072730Y+119689X0190Y         S0      
317GND              VIA   -    MD0100PA00X+073646Y+121864X0190Y         S0      
317GND              VIA   -    MD0100PA00X+073646Y+121195X0190Y         S0      
317GND              VIA   -    MD0100PA00X+073646Y+113833X0190Y         S0      
317GND              VIA   -    MD0100PA00X+073646Y+114502X0190Y         S0      
317GND              VIA   -    MD0100PA00X+073646Y+115171X0190Y         S0      
317GND              VIA   -    MD0100PA00X+072730Y+116008X0190Y         S0      
317GND              VIA   -    MD0100PA00X+073646Y+117514X0190Y         S0      
317GND              VIA   -    MD0100PA00X+073646Y+110152X0190Y         S0      
317GND              VIA   -    MD0100PA00X+073646Y+110821X0190Y         S0      
317GND              VIA   -    MD0100PA00X+073646Y+111490X0190Y         S0      
317GND              VIA   -    MD0100PA00X+072730Y+112327X0190Y         S0      
317GND              VIA   -    MD0100PA00X+073646Y+104128X0190Y         S0      
317GND              VIA   -    MD0100PA00X+073646Y+103459X0190Y         S0      
317GND              VIA   -    MD0100PA00X+073646Y+105467X0190Y         S0      
317GND              VIA   -    MD0100PA00X+073646Y+104797X0190Y         S0      
317GND              VIA   -    MD0100PA00X+073646Y+106136X0190Y         S0      
317GND              VIA   -    MD0100PA00X+073646Y+107140X0190Y         S0      
317GND              VIA   -    MD0100PA00X+073646Y+107809X0190Y         S0      
317GND              VIA   -    MD0100PA00X+072730Y+108646X0190Y         S0      
317GND              VIA   -    MD0100PA00X+073646Y+096766X0190Y         S0      
317GND              VIA   -    MD0100PA00X+073646Y+096097X0190Y         S0      
317GND              VIA   -    MD0100PA00X+073646Y+098104X0190Y         S0      
317GND              VIA   -    MD0100PA00X+073646Y+097435X0190Y         S0      
317GND              VIA   -    MD0100PA00X+073646Y+099443X0190Y         S0      
317GND              VIA   -    MD0100PA00X+073646Y+098774X0190Y         S0      
317GND              VIA   -    MD0100PA00X+073646Y+100447X0190Y         S0      
317GND              VIA   -    MD0100PA00X+073646Y+091746X0190Y         S0      
317GND              VIA   -    MD0100PA00X+073646Y+092416X0190Y         S0      
317GND              VIA   -    MD0100PA00X+073646Y+093085X0190Y         S0      
317GND              VIA   -    MD0100PA00X+072730Y+093921X0190Y         S0      
317GND              VIA   -    MD0100PA00X+073646Y+095427X0190Y         S0      
317GND              VIA   -    MD0100PA00X+073646Y+088065X0190Y         S0      
317GND              VIA   -    MD0100PA00X+073646Y+089404X0190Y         S0      
317GND              VIA   -    MD0100PA00X+073646Y+088734X0190Y         S0      
317GND              VIA   -    MD0100PA00X+072730Y+090240X0190Y         S0      
317GND              VIA   -    MD0100PA00X+073646Y+082042X0190Y         S0      
317GND              VIA   -    MD0100PA00X+073646Y+081372X0190Y         S0      
317GND              VIA   -    MD0100PA00X+072730Y+082878X0190Y         S0      
317GND              VIA   -    MD0100PA00X+073646Y+085053X0190Y         S0      
317GND              VIA   -    MD0100PA00X+073646Y+084384X0190Y         S0      
317GND              VIA   -    MD0100PA00X+073646Y+085723X0190Y         S0      
317GND              VIA   -    MD0100PA00X+072730Y+086559X0190Y         S0      
317GND              VIA   -    MD0100PA00X+073646Y+077691X0190Y         S0      
317GND              VIA   -    MD0100PA00X+072730Y+079197X0190Y         S0      
317GND              VIA   -    MD0100PA00X+073646Y+078360X0190Y         S0      
317GND              VIA   -    MD0100PA00X+073646Y+080703X0190Y         S0      
327GND              PC503_-2          A01X+070955Y+140375X0198Y0197R090 S1      
317GND              VIA   -    MD0100PA00X+070955Y+140658X0200Y         S0      
317GND              VIA   -    MD0100PA00X+072214Y+140591X0200Y    R090 S0      
317GND              VIA   -    MD0100PA00X+071243Y+137542X0193Y         S0      
317GND              VIA   -    MD0100PA00X+071763Y+137542X0193Y         S0      
317GND              VIA   -    MD0100PA00X+071503Y+137542X0193Y         S0      
317GND              VIA   -    MD0100PA00X+071763Y+138148X0193Y         S0      
317GND              VIA   -    MD0100PA00X+071243Y+137852X0193Y         S0      
317GND              VIA   -    MD0100PA00X+071763Y+137852X0193Y         S0      
317GND              VIA   -    MD0100PA00X+071503Y+137852X0193Y         S0      
327GND              PU44  -40  M      A01X+071671Y+138807X0690Y0770     S1      
317GND              VIA   -    MD0100PA00X+071428Y+138528X0193Y         S0      
317GND              VIA   -    MD0100PA00X+072283Y+137542X0193Y         S0      
317GND              VIA   -    MD0100PA00X+072023Y+137542X0193Y         S0      
317GND              VIA   -    MD0100PA00X+072023Y+138148X0193Y         S0      
317GND              VIA   -    MD0100PA00X+072023Y+137852X0193Y         S0      
317GND              VIA   -    MD0100PA00X+071671Y+139088X0193Y         S0      
317GND              VIA   -    MD0100PA00X+071428Y+139088X0193Y         S0      
317GND              VIA   -    MD0100PA00X+071914Y+139088X0193Y         S0      
327GND              PR328 -1          A01X+071660Y+140357X0198Y0197R180 S1      
317GND              VIA   -    MD0100PA00X+071919Y+140330X0200Y         S0      
317GND              VIA   -    MD0100PA00X+072290Y+124542X0190Y         S0      
317GND              VIA   -    MD0100PA00X+072290Y+125211X0190Y         S0      
317GND              VIA   -    MD0100PA00X+071221Y+124207X0190Y    R180 S0      
317GND              VIA   -    MD0100PA00X+071195Y+129755X0200Y         S0      
317GND              VIA   -    MD0100PA00X+072136Y+129755X0200Y         S0      
317GND              VIA   -    MD0100PA00X+071195Y+130005X0200Y         S0      
317GND              VIA   -    MD0100PA00X+071195Y+130265X0200Y         S0      
317GND              VIA   -    MD0100PA00X+071195Y+130525X0200Y         S0      
317GND              VIA   -    MD0100PA00X+072136Y+130005X0200Y         S0      
317GND              VIA   -    MD0100PA00X+072136Y+130265X0200Y         S0      
317GND              VIA   -    MD0100PA00X+072136Y+130525X0200Y         S0      
317GND              VIA   -    MD0100PA00X+071022Y+134949X0200Y         S0      
317GND              VIA   -    MD0100PA00X+071022Y+135199X0200Y         S0      
317GND              VIA   -    MD0100PA00X+071914Y+138528X0193Y         S0      
317GND              VIA   -    MD0100PA00X+071671Y+138528X0193Y         S0      
317GND              VIA   -    MD0100PA00X+071221Y+120526X0190Y    R180 S0      
317GND              VIA   -    MD0100PA00X+071745Y+120191X0190Y         S0      
317GND              VIA   -    MD0100PA00X+071116Y+120024X0190Y         S0      
317GND              VIA   -    MD0100PA00X+071221Y+119522X0190Y    R180 S0      
317GND              VIA   -    MD0100PA00X+072290Y+120860X0190Y         S0      
317GND              VIA   -    MD0100PA00X+072290Y+122199X0190Y         S0      
317GND              VIA   -    MD0100PA00X+072290Y+121530X0190Y         S0      
317GND              VIA   -    MD0100PA00X+071116Y+123705X0190Y         S0      
317GND              VIA   -    MD0100PA00X+071745Y+123872X0190Y         S0      
317GND              VIA   -    MD0100PA00X+071221Y+123203X0190Y    R180 S0      
317GND              VIA   -    MD0100PA00X+071745Y+122868X0190Y         S0      
317GND              VIA   -    MD0100PA00X+071221Y+115841X0190Y    R180 S0      
317GND              VIA   -    MD0100PA00X+071745Y+115506X0190Y         S0      
317GND              VIA   -    MD0100PA00X+071116Y+116343X0190Y         S0      
317GND              VIA   -    MD0100PA00X+071745Y+116510X0190Y         S0      
317GND              VIA   -    MD0100PA00X+071221Y+116845X0190Y    R180 S0      
317GND              VIA   -    MD0100PA00X+072290Y+117179X0190Y         S0      
317GND              VIA   -    MD0100PA00X+072290Y+117849X0190Y         S0      
317GND              VIA   -    MD0100PA00X+071745Y+119187X0190Y         S0      
317GND              VIA   -    MD0100PA00X+072290Y+118518X0190Y         S0      
317GND              VIA   -    MD0100PA00X+072290Y+110486X0190Y         S0      
317GND              VIA   -    MD0100PA00X+072290Y+109817X0190Y         S0      
317GND              VIA   -    MD0100PA00X+071745Y+111825X0190Y         S0      
317GND              VIA   -    MD0100PA00X+072290Y+111156X0190Y         S0      
317GND              VIA   -    MD0100PA00X+071221Y+113164X0190Y    R180 S0      
317GND              VIA   -    MD0100PA00X+072290Y+113498X0190Y         S0      
317GND              VIA   -    MD0100PA00X+071116Y+112662X0190Y         S0      
317GND              VIA   -    MD0100PA00X+071221Y+112160X0190Y    R180 S0      
317GND              VIA   -    MD0100PA00X+071745Y+112829X0190Y         S0      
317GND              VIA   -    MD0100PA00X+072290Y+114168X0190Y         S0      
317GND              VIA   -    MD0100PA00X+072290Y+114837X0190Y         S0      
317GND              VIA   -    MD0100PA00X+072290Y+107474X0190Y         S0      
317GND              VIA   -    MD0100PA00X+072290Y+106805X0190Y         S0      
317GND              VIA   -    MD0100PA00X+071116Y+108980X0190Y         S0      
317GND              VIA   -    MD0100PA00X+071221Y+108478X0190Y    R180 S0      
317GND              VIA   -    MD0100PA00X+071745Y+108144X0190Y         S0      
317GND              VIA   -    MD0100PA00X+071745Y+109148X0190Y         S0      
317GND              VIA   -    MD0100PA00X+071221Y+109482X0190Y    R180 S0      
317GND              VIA   -    MD0100PA00X+072290Y+099778X0190Y         S0      
317GND              VIA   -    MD0100PA00X+072290Y+099108X0190Y         S0      
317GND              VIA   -    MD0100PA00X+072290Y+100447X0190Y         S0      
317GND              VIA   -    MD0100PA00X+072290Y+104463X0190Y         S0      
317GND              VIA   -    MD0100PA00X+072290Y+103793X0190Y         S0      
317GND              VIA   -    MD0100PA00X+072290Y+103124X0190Y         S0      
317GND              VIA   -    MD0100PA00X+072290Y+105801X0190Y         S0      
317GND              VIA   -    MD0100PA00X+072290Y+105132X0190Y         S0      
317GND              VIA   -    MD0100PA00X+071745Y+093419X0190Y         S0      
317GND              VIA   -    MD0100PA00X+071221Y+093754X0190Y    R180 S0      
317GND              VIA   -    MD0100PA00X+072290Y+092750X0190Y         S0      
317GND              VIA   -    MD0100PA00X+071116Y+094256X0190Y         S0      
317GND              VIA   -    MD0100PA00X+071221Y+094758X0190Y    R180 S0      
317GND              VIA   -    MD0100PA00X+071745Y+094423X0190Y         S0      
317GND              VIA   -    MD0100PA00X+072290Y+095093X0190Y         S0      
317GND              VIA   -    MD0100PA00X+072290Y+096431X0190Y         S0      
317GND              VIA   -    MD0100PA00X+072290Y+097100X0190Y         S0      
317GND              VIA   -    MD0100PA00X+072290Y+095762X0190Y         S0      
317GND              VIA   -    MD0100PA00X+072290Y+097770X0190Y         S0      
317GND              VIA   -    MD0100PA00X+072290Y+098439X0190Y         S0      
317GND              VIA   -    MD0100PA00X+072290Y+089069X0190Y         S0      
317GND              VIA   -    MD0100PA00X+071116Y+090575X0190Y         S0      
317GND              VIA   -    MD0100PA00X+071221Y+091077X0190Y    R180 S0      
317GND              VIA   -    MD0100PA00X+071745Y+090742X0190Y         S0      
317GND              VIA   -    MD0100PA00X+071221Y+090073X0190Y    R180 S0      
317GND              VIA   -    MD0100PA00X+071745Y+089738X0190Y         S0      
317GND              VIA   -    MD0100PA00X+072290Y+091412X0190Y         S0      
317GND              VIA   -    MD0100PA00X+072290Y+092081X0190Y         S0      
317GND              VIA   -    MD0100PA00X+072290Y+084049X0190Y         S0      
317GND              VIA   -    MD0100PA00X+072290Y+084719X0190Y         S0      
317GND              VIA   -    MD0100PA00X+071221Y+086392X0190Y    R180 S0      
317GND              VIA   -    MD0100PA00X+071745Y+086057X0190Y         S0      
317GND              VIA   -    MD0100PA00X+072290Y+085388X0190Y         S0      
317GND              VIA   -    MD0100PA00X+071116Y+086894X0190Y         S0      
317GND              VIA   -    MD0100PA00X+071745Y+087061X0190Y         S0      
317GND              VIA   -    MD0100PA00X+071221Y+087396X0190Y    R180 S0      
317GND              VIA   -    MD0100PA00X+072290Y+087730X0190Y         S0      
317GND              VIA   -    MD0100PA00X+072290Y+088400X0190Y         S0      
317GND              VIA   -    MD0100PA00X+071745Y+079699X0190Y         S0      
317GND              VIA   -    MD0100PA00X+071116Y+079532X0190Y         S0      
317GND              VIA   -    MD0100PA00X+071221Y+080034X0190Y    R180 S0      
317GND              VIA   -    MD0100PA00X+072290Y+080368X0190Y         S0      
317GND              VIA   -    MD0100PA00X+072290Y+081707X0190Y         S0      
317GND              VIA   -    MD0100PA00X+072290Y+081038X0190Y         S0      
317GND              VIA   -    MD0100PA00X+071116Y+083213X0190Y         S0      
317GND              VIA   -    MD0100PA00X+071221Y+083715X0190Y    R180 S0      
317GND              VIA   -    MD0100PA00X+071221Y+082711X0190Y    R180 S0      
317GND              VIA   -    MD0100PA00X+071745Y+083380X0190Y         S0      
317GND              VIA   -    MD0100PA00X+071745Y+082376X0190Y         S0      
317GND              VIA   -    MD0100PA00X+071221Y+079030X0190Y    R180 S0      
317GND              VIA   -    MD0100PA00X+071745Y+078695X0190Y         S0      
317GND              VIA   -    MD0100PA00X+072290Y+078026X0190Y         S0      
327GND              PC638 -2   M      A01X+065878Y+137506X0198Y0197     S1      
327GND              PC8   -2          A01X+065874Y+137893X0198Y0197     S1      
317GND              VIA   -    MD0100PA00X+066171Y+137398X0200Y         S0      
317GND              VIA   -    MD0100PA00X+070676Y+124876X0190Y         S0      
317GND              VIA   -    MD0100PA00X+070676Y+125545X0190Y         S0      
317GND              VIA   -    MD0100PA00X+069748Y+129751X0200Y         S0      
317GND              VIA   -    MD0100PA00X+069748Y+130261X0200Y         S0      
317GND              VIA   -    MD0100PA00X+069748Y+130001X0200Y         S0      
317GND              VIA   -    MD0100PA00X+069748Y+130521X0200Y         S0      
317GND              VIA   -    MD0100PA00X+070177Y+134949X0200Y         S0      
317GND              VIA   -    MD0100PA00X+070177Y+135199X0200Y         S0      
317GND              VIA   -    MD0100PA00X+069947Y+136611X0200Y         S0      
317GND              VIA   -    MD0100PA00X+069947Y+136351X0200Y         S0      
317GND              VIA   -    MD0100PA00X+069947Y+136871X0200Y         S0      
317GND              VIA   -    MD0100PA00X+070357Y+137948X0193Y         S0      
317GND              VIA   -    MD0100PA00X+070676Y+121864X0190Y         S0      
317GND              VIA   -    MD0100PA00X+070676Y+121195X0190Y         S0      
317GND              VIA   -    MD0100PA00X+070676Y+122534X0190Y         S0      
317GND              VIA   -    MD0100PA00X+070676Y+115171X0190Y         S0      
317GND              VIA   -    MD0100PA00X+070676Y+117514X0190Y         S0      
317GND              VIA   -    MD0100PA00X+070676Y+118852X0190Y         S0      
317GND              VIA   -    MD0100PA00X+070676Y+118183X0190Y         S0      
317GND              VIA   -    MD0100PA00X+070676Y+110152X0190Y         S0      
317GND              VIA   -    MD0100PA00X+070676Y+110821X0190Y         S0      
317GND              VIA   -    MD0100PA00X+070676Y+111490X0190Y         S0      
317GND              VIA   -    MD0100PA00X+070676Y+113833X0190Y         S0      
317GND              VIA   -    MD0100PA00X+070676Y+114502X0190Y         S0      
317GND              VIA   -    MD0100PA00X+070676Y+103459X0190Y         S0      
317GND              VIA   -    MD0100PA00X+070676Y+105467X0190Y         S0      
317GND              VIA   -    MD0100PA00X+070676Y+104797X0190Y         S0      
317GND              VIA   -    MD0100PA00X+070676Y+106136X0190Y         S0      
317GND              VIA   -    MD0100PA00X+070676Y+107140X0190Y         S0      
317GND              VIA   -    MD0100PA00X+070676Y+107809X0190Y         S0      
317GND              VIA   -    MD0100PA00X+070676Y+098104X0190Y         S0      
317GND              VIA   -    MD0100PA00X+070676Y+097435X0190Y         S0      
317GND              VIA   -    MD0100PA00X+070676Y+099443X0190Y         S0      
317GND              VIA   -    MD0100PA00X+070676Y+098774X0190Y         S0      
317GND              VIA   -    MD0100PA00X+070676Y+100447X0190Y         S0      
317GND              VIA   -    MD0100PA00X+070676Y+104128X0190Y         S0      
317GND              VIA   -    MD0100PA00X+070676Y+093085X0190Y         S0      
317GND              VIA   -    MD0100PA00X+070676Y+095427X0190Y         S0      
317GND              VIA   -    MD0100PA00X+070676Y+096766X0190Y         S0      
317GND              VIA   -    MD0100PA00X+070676Y+096097X0190Y         S0      
317GND              VIA   -    MD0100PA00X+070676Y+088065X0190Y         S0      
317GND              VIA   -    MD0100PA00X+070676Y+089404X0190Y         S0      
317GND              VIA   -    MD0100PA00X+070676Y+088734X0190Y         S0      
317GND              VIA   -    MD0100PA00X+070676Y+091746X0190Y         S0      
317GND              VIA   -    MD0100PA00X+070676Y+092416X0190Y         S0      
317GND              VIA   -    MD0100PA00X+070676Y+085053X0190Y         S0      
317GND              VIA   -    MD0100PA00X+070676Y+084384X0190Y         S0      
317GND              VIA   -    MD0100PA00X+070676Y+085723X0190Y         S0      
317GND              VIA   -    MD0100PA00X+070676Y+078360X0190Y         S0      
317GND              VIA   -    MD0100PA00X+070676Y+080703X0190Y         S0      
317GND              VIA   -    MD0100PA00X+070676Y+082042X0190Y         S0      
317GND              VIA   -    MD0100PA00X+070676Y+081372X0190Y         S0      
317GND              VIA   -    MD0100PA00X+070676Y+077691X0190Y         S0      
317GND              VIA   -    MD0100PA00X+068305Y+134955X0200Y         S0      
317GND              VIA   -    MD0100PA00X+068305Y+135205X0200Y         S0      
317GND              VIA   -    MD0100PA00X+068519Y+136610X0200Y         S0      
317GND              VIA   -    MD0100PA00X+068519Y+136350X0200Y         S0      
317GND              VIA   -    MD0100PA00X+068519Y+136870X0200Y         S0      
327GND              PR14  -2          A01X+065004Y+135336X0198Y0197R270 S1      
317GND              VIA   -    MD0100PA00X+065004Y+135088X0200Y         S0      
327GND              PR408 -2          A01X+065384Y+135336X0198Y0197R270 S1      
317GND              VIA   -    MD0100PA00X+065384Y+135088X0200Y         S0      
327GND              PR409 -2          A01X+065784Y+135336X0198Y0197R270 S1      
317GND              VIA   -    MD0100PA00X+065784Y+135088X0200Y         S0      
317GND              VIA   -    MD0100PA00X+066168Y+136728X0200Y    R180 S0      
327GND              PC643 -2          A01X+065881Y+137120X0198Y0197     S1      
327GND              PR464 -1   M      A01X+065883Y+136728X0198Y0197R180 S1      
327GND              PC645 -2          A01X+065956Y+138844X0198Y0197R090 S1      
317GND              VIA   -    MD0100PA00X+065956Y+139103X0200Y         S0      
327GND              PC95  -2          A01X+065570Y+138850X0198Y0197R090 S1      
317GND              VIA   -    MD0100PA00X+065570Y+139111X0200Y         S0      
327GND              PC644 -2          A01X+064744Y+139000X0198Y0197R090 S1      
317GND              VIA   -    MD0100PA00X+064744Y+139260X0200Y         S0      
317GND              VIA   -    MD0100PA00X+068808Y+129751X0200Y         S0      
317GND              VIA   -    MD0100PA00X+068808Y+130261X0200Y         S0      
317GND              VIA   -    MD0100PA00X+068808Y+130001X0200Y         S0      
317GND              VIA   -    MD0100PA00X+068808Y+130521X0200Y         S0      
327GND              PU54  -TH  M      A01X+063870Y+137226X1440Y1440R270 S1      
317GND              VIA   -    MD0100PA00X+064340Y+137286X0200Y    R180 S0      
317GND              VIA   -    MD0100PA00X+064480Y+137826X0200Y    R180 S0      
317GND              VIA   -    MD0100PA00X+063270Y+137826X0200Y    R180 S0      
317GND              VIA   -    MD0100PA00X+063870Y+137826X0200Y    R180 S0      
317GND              VIA   -    MD0100PA00X+063270Y+137226X0200Y    R180 S0      
327GND              PC96  -2          A01X+064356Y+138997X0198Y0197R090 S1      
317GND              VIA   -    MD0100PA00X+064356Y+139258X0200Y         S0      
317GND              VIA   -    MD0100PA00X+067455Y+134949X0200Y         S0      
317GND              VIA   -    MD0100PA00X+067455Y+135199X0200Y         S0      
327GND              PR406 -2          A01X+063844Y+135336X0198Y0197R270 S1      
317GND              VIA   -    MD0100PA00X+063844Y+135088X0200Y         S0      
317GND              VIA   -    MD0100PA00X+064624Y+135088X0200Y         S0      
327GND              PR407 -2          A01X+064244Y+135336X0198Y0197R270 S1      
317GND              VIA   -    MD0100PA00X+064244Y+135088X0200Y         S0      
317GND              VIA   -    MD0100PA00X+064480Y+136616X0200Y    R180 S0      
317GND              VIA   -    MD0100PA00X+063270Y+136616X0200Y    R180 S0      
317GND              VIA   -    MD0100PA00X+063870Y+136616X0200Y    R180 S0      
317GND              VIA   -    MD0100PA00X+061653Y+139073X0200Y         S0      
317GND              VIA   -    MD0100PA00X+061665Y+138286X0200Y    R270 S0      
327GND              C8641 -2   M      A01X+061926Y+138286X0198Y0197R180 S1      
327GND              C642  -2          A01X+061926Y+137896X0198Y0197R180 S1      
327GND              PC518_-2          A18X+075792Y+140145X0400Y0500R090 S2      
327GND              PC517_-2          A18X+072490Y+140135X0400Y0500R090 S2      
327GND              PC521_-2          A18X+072564Y+140814X0400Y0500R180 S2      
327GND              PR390 -2          A18X+063121Y+136875X0198Y0197R180 S2      
327GND              PR6   -2          A18X+064538Y+137491X0198Y0197     S2      
327GND              PR604 -2          A18X+064538Y+138095X0198Y0197     S2      
327GND              PR415 -2          A18X+064538Y+137079X0198Y0197     S2      
327GND              PU54  -20         A01X+062925Y+136517X0070Y0240R270 S1      
327GND              PU54  -32         A01X+064814Y+136674X0070Y0240R270 S1      
327GND              PU54  -31         A01X+064814Y+136517X0070Y0240R270 S1      
327GND              PU54  -17         A01X+062925Y+136990X0070Y0240R270 S1      
327GND              PU54  -18         A01X+062925Y+136832X0070Y0240R270 S1      
317GND              VIA   -    MD0100PA00X+073989Y+140485X0200Y         S0      
317GND              VIA   -    MD0100PA00X+073823Y+140290X0200Y         S0      
327GND              PC504_-2          A01X+074233Y+140385X0198Y0197R090 S1      
327GND              PC509_-2          A01X+073823Y+140041X0198Y0197     S1      
317GND              VIA   -    MD0100PA00X+072290Y+077356X0190Y         S0      
327GND              J100  -6          A01X+072290Y+077356X0205Y0590R090 S1      
317GND              VIA   -    MD0100PA00X+075260Y+077356X0190Y         S0      
327GND              J29   -6          A01X+075260Y+077356X0205Y0590R090 S1      
317GND              VIA   -    MD0100PA00X+078230Y+077356X0190Y         S0      
327GND              J99   -6          A01X+078230Y+077356X0205Y0590R090 S1      
317GND              VIA   -    MD0100PA00X+081200Y+077356X0190Y         S0      
327GND              J37   -6          A01X+081200Y+077356X0205Y0590R090 S1      
317GND              VIA   -    MD0100PA00X+066350Y+078026X0190Y         S0      
327GND              J102  -8          A01X+066350Y+078026X0205Y0590R090 S1      
317GND              VIA   -    MD0100PA00X+065805Y+078695X0190Y         S0      
327GND              J102  -10         A01X+066350Y+078695X0205Y0590R090 S1      
317GND              VIA   -    MD0100PA00X+065280Y+079030X0190Y    R180 S0      
327GND              J102  -155        A01X+064735Y+079030X0205Y0590R090 S1      
317GND              VIA   -    MD0100PA00X+067706Y+078360X0190Y         S0      
327GND              J27   -153        A01X+067706Y+078360X0205Y0590R090 S1      
317GND              VIA   -    MD0100PA00X+066790Y+079197X0190Y         S0      
317GND              VIA   -    MD0100PA00X+069320Y+078026X0190Y         S0      
327GND              J27   -8          A01X+069320Y+078026X0205Y0590R090 S1      
317GND              VIA   -    MD0100PA00X+068775Y+078695X0190Y         S0      
327GND              J27   -10         A01X+069320Y+078695X0205Y0590R090 S1      
317GND              VIA   -    MD0100PA00X+068250Y+079030X0190Y    R180 S0      
327GND              J27   -155        A01X+067706Y+079030X0205Y0590R090 S1      
317GND              VIA   -    MD0100PA00X+069760Y+079197X0190Y         S0      
317GND              VIA   -    MD0100PA00X+066350Y+080368X0190Y         S0      
327GND              J102  -15         A01X+066350Y+080368X0205Y0590R090 S1      
317GND              VIA   -    MD0100PA00X+065805Y+079699X0190Y         S0      
327GND              J102  -13         A01X+066350Y+079699X0205Y0590R090 S1      
317GND              VIA   -    MD0100PA00X+065280Y+080034X0190Y    R180 S0      
327GND              J102  -158        A01X+064735Y+080034X0205Y0590R090 S1      
317GND              VIA   -    MD0100PA00X+065175Y+079532X0190Y         S0      
317GND              VIA   -    MD0100PA00X+067706Y+080703X0190Y         S0      
327GND              J27   -160        A01X+067706Y+080703X0205Y0590R090 S1      
317GND              VIA   -    MD0100PA00X+069320Y+080368X0190Y         S0      
327GND              J27   -15         A01X+069320Y+080368X0205Y0590R090 S1      
317GND              VIA   -    MD0100PA00X+068775Y+079699X0190Y         S0      
327GND              J27   -13         A01X+069320Y+079699X0205Y0590R090 S1      
317GND              VIA   -    MD0100PA00X+068250Y+080034X0190Y    R180 S0      
327GND              J27   -158        A01X+067706Y+080034X0205Y0590R090 S1      
317GND              VIA   -    MD0100PA00X+068146Y+079532X0190Y         S0      
317GND              VIA   -    MD0100PA00X+066350Y+081707X0190Y         S0      
327GND              J102  -19         A01X+066350Y+081707X0205Y0590R090 S1      
317GND              VIA   -    MD0100PA00X+066350Y+081038X0190Y         S0      
327GND              J102  -17         A01X+066350Y+081038X0205Y0590R090 S1      
317GND              VIA   -    MD0100PA00X+067706Y+082042X0190Y         S0      
327GND              J27   -164        A01X+067706Y+082042X0205Y0590R090 S1      
317GND              VIA   -    MD0100PA00X+067706Y+081372X0190Y         S0      
327GND              J27   -162        A01X+067706Y+081372X0205Y0590R090 S1      
317GND              VIA   -    MD0100PA00X+069320Y+081707X0190Y         S0      
327GND              J27   -19         A01X+069320Y+081707X0205Y0590R090 S1      
317GND              VIA   -    MD0100PA00X+069320Y+081038X0190Y         S0      
327GND              J27   -17         A01X+069320Y+081038X0205Y0590R090 S1      
317GND              VIA   -    MD0100PA00X+065805Y+082376X0190Y         S0      
327GND              J102  -21         A01X+066350Y+082376X0205Y0590R090 S1      
317GND              VIA   -    MD0100PA00X+065805Y+083380X0190Y         S0      
327GND              J102  -24         A01X+066350Y+083380X0205Y0590R090 S1      
317GND              VIA   -    MD0100PA00X+065280Y+082711X0190Y    R180 S0      
327GND              J102  -166        A01X+064735Y+082711X0205Y0590R090 S1      
317GND              VIA   -    MD0100PA00X+065280Y+083715X0190Y    R180 S0      
327GND              J102  -169        A01X+064735Y+083715X0205Y0590R090 S1      
317GND              VIA   -    MD0100PA00X+065175Y+083213X0190Y         S0      
317GND              VIA   -    MD0100PA00X+066790Y+082878X0190Y         S0      
317GND              VIA   -    MD0100PA00X+068775Y+082376X0190Y         S0      
327GND              J27   -21         A01X+069320Y+082376X0205Y0590R090 S1      
317GND              VIA   -    MD0100PA00X+068775Y+083380X0190Y         S0      
327GND              J27   -24         A01X+069320Y+083380X0205Y0590R090 S1      
317GND              VIA   -    MD0100PA00X+068250Y+082711X0190Y    R180 S0      
327GND              J27   -166        A01X+067706Y+082711X0205Y0590R090 S1      
317GND              VIA   -    MD0100PA00X+068250Y+083715X0190Y    R180 S0      
327GND              J27   -169        A01X+067706Y+083715X0205Y0590R090 S1      
317GND              VIA   -    MD0100PA00X+068146Y+083213X0190Y         S0      
317GND              VIA   -    MD0100PA00X+069760Y+082878X0190Y         S0      
317GND              VIA   -    MD0100PA00X+066350Y+084719X0190Y         S0      
327GND              J102  -28         A01X+066350Y+084719X0205Y0590R090 S1      
317GND              VIA   -    MD0100PA00X+066350Y+084049X0190Y         S0      
327GND              J102  -26         A01X+066350Y+084049X0205Y0590R090 S1      
317GND              VIA   -    MD0100PA00X+067706Y+085053X0190Y         S0      
327GND              J27   -173        A01X+067706Y+085053X0205Y0590R090 S1      
317GND              VIA   -    MD0100PA00X+067706Y+084384X0190Y         S0      
327GND              J27   -171        A01X+067706Y+084384X0205Y0590R090 S1      
317GND              VIA   -    MD0100PA00X+069320Y+084719X0190Y         S0      
327GND              J27   -28         A01X+069320Y+084719X0205Y0590R090 S1      
317GND              VIA   -    MD0100PA00X+069320Y+084049X0190Y         S0      
327GND              J27   -26         A01X+069320Y+084049X0205Y0590R090 S1      
317GND              VIA   -    MD0100PA00X+066350Y+085388X0190Y         S0      
327GND              J102  -30         A01X+066350Y+085388X0205Y0590R090 S1      
317GND              VIA   -    MD0100PA00X+065805Y+086057X0190Y         S0      
327GND              J102  -32         A01X+066350Y+086057X0205Y0590R090 S1      
317GND              VIA   -    MD0100PA00X+065280Y+086392X0190Y    R180 S0      
327GND              J102  -177        A01X+064735Y+086392X0205Y0590R090 S1      
317GND              VIA   -    MD0100PA00X+067706Y+085723X0190Y         S0      
327GND              J27   -175        A01X+067706Y+085723X0205Y0590R090 S1      
317GND              VIA   -    MD0100PA00X+066790Y+086559X0190Y         S0      
317GND              VIA   -    MD0100PA00X+069320Y+085388X0190Y         S0      
327GND              J27   -30         A01X+069320Y+085388X0205Y0590R090 S1      
317GND              VIA   -    MD0100PA00X+068775Y+086057X0190Y         S0      
327GND              J27   -32         A01X+069320Y+086057X0205Y0590R090 S1      
317GND              VIA   -    MD0100PA00X+068250Y+086392X0190Y    R180 S0      
327GND              J27   -177        A01X+067706Y+086392X0205Y0590R090 S1      
317GND              VIA   -    MD0100PA00X+069760Y+086559X0190Y         S0      
317GND              VIA   -    MD0100PA00X+066350Y+087730X0190Y         S0      
327GND              J102  -37         A01X+066350Y+087730X0205Y0590R090 S1      
317GND              VIA   -    MD0100PA00X+065805Y+087061X0190Y         S0      
327GND              J102  -35         A01X+066350Y+087061X0205Y0590R090 S1      
317GND              VIA   -    MD0100PA00X+065280Y+087396X0190Y    R180 S0      
327GND              J102  -180        A01X+064735Y+087396X0205Y0590R090 S1      
317GND              VIA   -    MD0100PA00X+065175Y+086894X0190Y         S0      
317GND              VIA   -    MD0100PA00X+067706Y+088065X0190Y         S0      
327GND              J27   -182        A01X+067706Y+088065X0205Y0590R090 S1      
317GND              VIA   -    MD0100PA00X+069320Y+087730X0190Y         S0      
327GND              J27   -37         A01X+069320Y+087730X0205Y0590R090 S1      
317GND              VIA   -    MD0100PA00X+068775Y+087061X0190Y         S0      
327GND              J27   -35         A01X+069320Y+087061X0205Y0590R090 S1      
317GND              VIA   -    MD0100PA00X+068250Y+087396X0190Y    R180 S0      
327GND              J27   -180        A01X+067706Y+087396X0205Y0590R090 S1      
317GND              VIA   -    MD0100PA00X+068146Y+086894X0190Y         S0      
317GND              VIA   -    MD0100PA00X+066350Y+089069X0190Y         S0      
327GND              J102  -41         A01X+066350Y+089069X0205Y0590R090 S1      
317GND              VIA   -    MD0100PA00X+066350Y+088400X0190Y         S0      
327GND              J102  -39         A01X+066350Y+088400X0205Y0590R090 S1      
317GND              VIA   -    MD0100PA00X+067706Y+089404X0190Y         S0      
327GND              J27   -186        A01X+067706Y+089404X0205Y0590R090 S1      
317GND              VIA   -    MD0100PA00X+067706Y+088734X0190Y         S0      
327GND              J27   -184        A01X+067706Y+088734X0205Y0590R090 S1      
317GND              VIA   -    MD0100PA00X+069320Y+089069X0190Y         S0      
327GND              J27   -41         A01X+069320Y+089069X0205Y0590R090 S1      
317GND              VIA   -    MD0100PA00X+069320Y+088400X0190Y         S0      
327GND              J27   -39         A01X+069320Y+088400X0205Y0590R090 S1      
317GND              VIA   -    MD0100PA00X+065805Y+090742X0190Y         S0      
327GND              J102  -46         A01X+066350Y+090742X0205Y0590R090 S1      
317GND              VIA   -    MD0100PA00X+065805Y+089738X0190Y         S0      
327GND              J102  -43         A01X+066350Y+089738X0205Y0590R090 S1      
317GND              VIA   -    MD0100PA00X+065280Y+091077X0190Y    R180 S0      
327GND              J102  -191        A01X+064735Y+091077X0205Y0590R090 S1      
317GND              VIA   -    MD0100PA00X+065280Y+090073X0190Y    R180 S0      
327GND              J102  -188        A01X+064735Y+090073X0205Y0590R090 S1      
317GND              VIA   -    MD0100PA00X+065175Y+090575X0190Y         S0      
317GND              VIA   -    MD0100PA00X+066790Y+090240X0190Y         S0      
317GND              VIA   -    MD0100PA00X+068775Y+090742X0190Y         S0      
327GND              J27   -46         A01X+069320Y+090742X0205Y0590R090 S1      
317GND              VIA   -    MD0100PA00X+068775Y+089738X0190Y         S0      
327GND              J27   -43         A01X+069320Y+089738X0205Y0590R090 S1      
317GND              VIA   -    MD0100PA00X+068250Y+091077X0190Y    R180 S0      
327GND              J27   -191        A01X+067706Y+091077X0205Y0590R090 S1      
317GND              VIA   -    MD0100PA00X+068250Y+090073X0190Y    R180 S0      
327GND              J27   -188        A01X+067706Y+090073X0205Y0590R090 S1      
317GND              VIA   -    MD0100PA00X+068146Y+090575X0190Y         S0      
317GND              VIA   -    MD0100PA00X+069760Y+090240X0190Y         S0      
317GND              VIA   -    MD0100PA00X+066350Y+092081X0190Y         S0      
327GND              J102  -50         A01X+066350Y+092081X0205Y0590R090 S1      
317GND              VIA   -    MD0100PA00X+066350Y+091412X0190Y         S0      
327GND              J102  -48         A01X+066350Y+091412X0205Y0590R090 S1      
317GND              VIA   -    MD0100PA00X+067706Y+092416X0190Y         S0      
327GND              J27   -195        A01X+067706Y+092416X0205Y0590R090 S1      
317GND              VIA   -    MD0100PA00X+067706Y+091746X0190Y         S0      
327GND              J27   -193        A01X+067706Y+091746X0205Y0590R090 S1      
317GND              VIA   -    MD0100PA00X+069320Y+092081X0190Y         S0      
327GND              J27   -50         A01X+069320Y+092081X0205Y0590R090 S1      
317GND              VIA   -    MD0100PA00X+069320Y+091412X0190Y         S0      
327GND              J27   -48         A01X+069320Y+091412X0205Y0590R090 S1      
317GND              VIA   -    MD0100PA00X+066350Y+092750X0190Y         S0      
327GND              J102  -52         A01X+066350Y+092750X0205Y0590R090 S1      
317GND              VIA   -    MD0100PA00X+065805Y+093419X0190Y         S0      
327GND              J102  -54         A01X+066350Y+093419X0205Y0590R090 S1      
317GND              VIA   -    MD0100PA00X+065280Y+093754X0190Y    R180 S0      
327GND              J102  -199        A01X+064735Y+093754X0205Y0590R090 S1      
317GND              VIA   -    MD0100PA00X+067706Y+093085X0190Y         S0      
327GND              J27   -197        A01X+067706Y+093085X0205Y0590R090 S1      
317GND              VIA   -    MD0100PA00X+066790Y+093921X0190Y         S0      
317GND              VIA   -    MD0100PA00X+069320Y+092750X0190Y         S0      
327GND              J27   -52         A01X+069320Y+092750X0205Y0590R090 S1      
317GND              VIA   -    MD0100PA00X+068775Y+093419X0190Y         S0      
327GND              J27   -54         A01X+069320Y+093419X0205Y0590R090 S1      
317GND              VIA   -    MD0100PA00X+068250Y+093754X0190Y    R180 S0      
327GND              J27   -199        A01X+067706Y+093754X0205Y0590R090 S1      
317GND              VIA   -    MD0100PA00X+069760Y+093921X0190Y         S0      
317GND              VIA   -    MD0100PA00X+066350Y+095093X0190Y         S0      
327GND              J102  -59         A01X+066350Y+095093X0205Y0590R090 S1      
317GND              VIA   -    MD0100PA00X+065805Y+094423X0190Y         S0      
327GND              J102  -57         A01X+066350Y+094423X0205Y0590R090 S1      
317GND              VIA   -    MD0100PA00X+065280Y+094758X0190Y    R180 S0      
327GND              J102  -202        A01X+064735Y+094758X0205Y0590R090 S1      
317GND              VIA   -    MD0100PA00X+065175Y+094256X0190Y         S0      
317GND              VIA   -    MD0100PA00X+067706Y+095427X0190Y         S0      
327GND              J27   -204        A01X+067706Y+095427X0205Y0590R090 S1      
317GND              VIA   -    MD0100PA00X+069320Y+095093X0190Y         S0      
327GND              J27   -59         A01X+069320Y+095093X0205Y0590R090 S1      
317GND              VIA   -    MD0100PA00X+068775Y+094423X0190Y         S0      
327GND              J27   -57         A01X+069320Y+094423X0205Y0590R090 S1      
317GND              VIA   -    MD0100PA00X+068250Y+094758X0190Y    R180 S0      
327GND              J27   -202        A01X+067706Y+094758X0205Y0590R090 S1      
317GND              VIA   -    MD0100PA00X+068146Y+094256X0190Y         S0      
317GND              VIA   -    MD0100PA00X+066350Y+097100X0190Y         S0      
327GND              J102  -65         A01X+066350Y+097100X0205Y0590R090 S1      
317GND              VIA   -    MD0100PA00X+066350Y+096431X0190Y         S0      
327GND              J102  -63         A01X+066350Y+096431X0205Y0590R090 S1      
317GND              VIA   -    MD0100PA00X+066350Y+095762X0190Y         S0      
327GND              J102  -61         A01X+066350Y+095762X0205Y0590R090 S1      
317GND              VIA   -    MD0100PA00X+067706Y+096766X0190Y         S0      
327GND              J27   -208        A01X+067706Y+096766X0205Y0590R090 S1      
317GND              VIA   -    MD0100PA00X+067706Y+096097X0190Y         S0      
327GND              J27   -206        A01X+067706Y+096097X0205Y0590R090 S1      
317GND              VIA   -    MD0100PA00X+069320Y+097100X0190Y         S0      
327GND              J27   -65         A01X+069320Y+097100X0205Y0590R090 S1      
317GND              VIA   -    MD0100PA00X+069320Y+096431X0190Y         S0      
327GND              J27   -63         A01X+069320Y+096431X0205Y0590R090 S1      
317GND              VIA   -    MD0100PA00X+069320Y+095762X0190Y         S0      
327GND              J27   -61         A01X+069320Y+095762X0205Y0590R090 S1      
317GND              VIA   -    MD0100PA00X+066350Y+098439X0190Y         S0      
327GND              J102  -69         A01X+066350Y+098439X0205Y0590R090 S1      
317GND              VIA   -    MD0100PA00X+066350Y+097770X0190Y         S0      
327GND              J102  -67         A01X+066350Y+097770X0205Y0590R090 S1      
317GND              VIA   -    MD0100PA00X+067706Y+098104X0190Y         S0      
327GND              J27   -212        A01X+067706Y+098104X0205Y0590R090 S1      
317GND              VIA   -    MD0100PA00X+067706Y+097435X0190Y         S0      
327GND              J27   -210        A01X+067706Y+097435X0205Y0590R090 S1      
317GND              VIA   -    MD0100PA00X+069320Y+098439X0190Y         S0      
327GND              J27   -69         A01X+069320Y+098439X0205Y0590R090 S1      
317GND              VIA   -    MD0100PA00X+069320Y+097770X0190Y         S0      
327GND              J27   -67         A01X+069320Y+097770X0205Y0590R090 S1      
317GND              VIA   -    MD0100PA00X+066350Y+099778X0190Y         S0      
327GND              J102  -73         A01X+066350Y+099778X0205Y0590R090 S1      
317GND              VIA   -    MD0100PA00X+066350Y+099108X0190Y         S0      
327GND              J102  -71         A01X+066350Y+099108X0205Y0590R090 S1      
317GND              VIA   -    MD0100PA00X+067706Y+099443X0190Y         S0      
327GND              J27   -216        A01X+067706Y+099443X0205Y0590R090 S1      
317GND              VIA   -    MD0100PA00X+067706Y+098774X0190Y         S0      
327GND              J27   -214        A01X+067706Y+098774X0205Y0590R090 S1      
317GND              VIA   -    MD0100PA00X+069320Y+099778X0190Y         S0      
327GND              J27   -73         A01X+069320Y+099778X0205Y0590R090 S1      
317GND              VIA   -    MD0100PA00X+069320Y+099108X0190Y         S0      
327GND              J27   -71         A01X+069320Y+099108X0205Y0590R090 S1      
317GND              VIA   -    MD0100PA00X+066350Y+100447X0190Y         S0      
327GND              J102  -75         A01X+066350Y+100447X0205Y0590R090 S1      
317GND              VIA   -    MD0100PA00X+067706Y+100447X0190Y         S0      
327GND              J27   -219        A01X+067706Y+100447X0205Y0590R090 S1      
317GND              VIA   -    MD0100PA00X+069320Y+100447X0190Y         S0      
327GND              J27   -75         A01X+069320Y+100447X0205Y0590R090 S1      
317GND              J102  -G2  MD0480PA00X+065542Y+102140X0680Y1370R090 S3      
317GND              J27   -G2  MD0480PA00X+068513Y+102140X0680Y1370R090 S3      
317GND              VIA   -    MD0100PA00X+066350Y+104463X0190Y         S0      
327GND              J102  -81         A01X+066350Y+104463X0205Y0590R090 S1      
317GND              VIA   -    MD0100PA00X+066350Y+103793X0190Y         S0      
327GND              J102  -79         A01X+066350Y+103793X0205Y0590R090 S1      
317GND              VIA   -    MD0100PA00X+066350Y+103124X0190Y         S0      
327GND              J102  -77         A01X+066350Y+103124X0205Y0590R090 S1      
317GND              VIA   -    MD0100PA00X+067706Y+104128X0190Y         S0      
327GND              J27   -224        A01X+067706Y+104128X0205Y0590R090 S1      
317GND              VIA   -    MD0100PA00X+067706Y+103459X0190Y         S0      
327GND              J27   -222        A01X+067706Y+103459X0205Y0590R090 S1      
317GND              VIA   -    MD0100PA00X+069320Y+104463X0190Y         S0      
327GND              J27   -81         A01X+069320Y+104463X0205Y0590R090 S1      
317GND              VIA   -    MD0100PA00X+069320Y+103793X0190Y         S0      
327GND              J27   -79         A01X+069320Y+103793X0205Y0590R090 S1      
317GND              VIA   -    MD0100PA00X+069320Y+103124X0190Y         S0      
327GND              J27   -77         A01X+069320Y+103124X0205Y0590R090 S1      
317GND              VIA   -    MD0100PA00X+067706Y+104797X0190Y         S0      
327GND              J27   -226        A01X+067706Y+104797X0205Y0590R090 S1      
317GND              VIA   -    MD0100PA00X+077099Y+135199X0200Y         S0      
317GND              VIA   -    MD0100PA00X+077099Y+134909X0200Y         S0      
317GND              VIA   -    MD0100PA00X+064735Y+077691X0190Y         S0      
327GND              J102  -151        A01X+064735Y+077691X0205Y0590R090 S1      
317GND              VIA   -    MD0100PA00X+063429Y+076665X0200Y         S0      
317GND              VIA   -    MD0100PA00X+023397Y+077356X0190Y         S0      
327GND              J24   -6          A01X+023397Y+077356X0205Y0590R090 S1      
317GND              VIA   -    MD0100PA00X+021783Y+077691X0190Y         S0      
327GND              J24   -151        A01X+021783Y+077691X0205Y0590R090 S1      
317GND              VIA   -    MD0100PA00X+022942Y+076312X0190Y         S0      
327GND              C136  -2          A18X+023229Y+076377X0198Y0197     S2      
317GND              VIA   -    MD0100PA00X+022238Y+076727X0190Y         S0      
327GND              R36   -2   M      A18X+022234Y+076727X0198Y0197R180 S2      
317GND              VIA   -    MD0100PA00X+020427Y+077356X0190Y         S0      
327GND              J26   -6          A01X+020427Y+077356X0205Y0590R090 S1      
317GND              VIA   -    MD0100PA00X+018813Y+077691X0190Y         S0      
327GND              J26   -151        A01X+018813Y+077691X0205Y0590R090 S1      
317GND              VIA   -    MD0100PA00X+019972Y+076377X0190Y         S0      
327GND              C140  -2   M      A18X+019969Y+076377X0198Y0197     S2      
317GND              VIA   -    MD0100PA00X+019268Y+076727X0190Y         S0      
327GND              R770  -2          A18X+019274Y+076727X0198Y0197R180 S2      
317GND              VIA   -    MD0100PA00X+017457Y+077356X0190Y         S0      
327GND              J28   -6          A01X+017457Y+077356X0205Y0590R090 S1      
317GND              VIA   -    MD0100PA00X+016298Y+076727X0190Y         S0      
327GND              R771  -2          A18X+016298Y+076727X0198Y0197R180 S2      
317GND              VIA   -    MD0100PA00X+017002Y+076377X0190Y         S0      
327GND              C144  -2          A18X+016999Y+076367X0198Y0197     S2      
317GND              VIA   -    MD0100PA00X+014487Y+077356X0190Y         S0      
327GND              J30   -6          A01X+014487Y+077356X0205Y0590R090 S1      
317GND              VIA   -    MD0100PA00X+013312Y+076727X0190Y         S0      
327GND              R772  -2   M      A18X+013334Y+076727X0198Y0197R180 S2      
317GND              VIA   -    MD0100PA00X+014032Y+076377X0190Y         S0      
327GND              C148  -2   M      A18X+014032Y+076370X0198Y0197     S2      
317GND              VIA   -    MD0100PA00X+011517Y+077356X0190Y         S0      
327GND              J32   -6          A01X+011517Y+077356X0205Y0590R090 S1      
317GND              VIA   -    MD0100PA00X+010357Y+076727X0190Y         S0      
327GND              R6    -2   M      A18X+010364Y+076727X0198Y0197R180 S2      
317GND              VIA   -    MD0100PA00X+011062Y+076377X0190Y         S0      
327GND              C152  -2   M      A18X+011048Y+076377X0198Y0197     S2      
317GND              VIA   -    MD0100PA00X+008546Y+077356X0190Y         S0      
327GND              J33   -6          A01X+008546Y+077356X0205Y0590R090 S1      
317GND              VIA   -    MD0100PA00X+008092Y+076377X0190Y         S0      
327GND              C156  -2   M      A18X+008078Y+076377X0198Y0197     S2      
317GND              VIA   -    MD0100PA00X+006492Y+079532X0190Y         S0      
317GND              VIA   -    MD0100PA00X+006492Y+086894X0190Y         S0      
317GND              VIA   -    MD0100PA00X+006492Y+083213X0190Y         S0      
317GND              VIA   -    MD0100PA00X+006492Y+090575X0190Y         S0      
317GND              VIA   -    MD0100PA00X+006492Y+094256X0190Y         S0      
317GND              VIA   -    MD0100PA00X+006492Y+112662X0190Y         S0      
317GND              VIA   -    MD0100PA00X+006492Y+108980X0190Y         S0      
317GND              VIA   -    MD0100PA00X+006492Y+116343X0190Y         S0      
317GND              VIA   -    MD0100PA00X+006492Y+123705X0190Y         S0      
317GND              VIA   -    MD0100PA00X+006492Y+120024X0190Y         S0      
317GND              VIA   -    MD0100PA00X+008106Y+079197X0190Y         S0      
317GND              VIA   -    MD0100PA00X+007477Y+079030X0190Y    R180 S0      
317GND              VIA   -    MD0100PA00X+006932Y+078360X0190Y         S0      
317GND              VIA   -    MD0100PA00X+008002Y+078695X0190Y         S0      
317GND              VIA   -    MD0100PA00X+006932Y+077691X0190Y         S0      
317GND              VIA   -    MD0100PA00X+006932Y+085053X0190Y         S0      
317GND              VIA   -    MD0100PA00X+006932Y+084384X0190Y         S0      
317GND              VIA   -    MD0100PA00X+007477Y+083715X0190Y    R180 S0      
317GND              VIA   -    MD0100PA00X+007477Y+082711X0190Y    R180 S0      
317GND              VIA   -    MD0100PA00X+008106Y+082878X0190Y         S0      
317GND              VIA   -    MD0100PA00X+008002Y+083380X0190Y         S0      
317GND              VIA   -    MD0100PA00X+008002Y+082376X0190Y         S0      
317GND              VIA   -    MD0100PA00X+006932Y+082042X0190Y         S0      
317GND              VIA   -    MD0100PA00X+006932Y+081372X0190Y         S0      
317GND              VIA   -    MD0100PA00X+007477Y+080034X0190Y    R180 S0      
317GND              VIA   -    MD0100PA00X+006932Y+080703X0190Y         S0      
317GND              VIA   -    MD0100PA00X+008002Y+079699X0190Y         S0      
317GND              VIA   -    MD0100PA00X+008106Y+090240X0190Y         S0      
317GND              VIA   -    MD0100PA00X+008002Y+089738X0190Y         S0      
317GND              VIA   -    MD0100PA00X+006932Y+089404X0190Y         S0      
317GND              VIA   -    MD0100PA00X+006932Y+088734X0190Y         S0      
317GND              VIA   -    MD0100PA00X+007477Y+087396X0190Y    R180 S0      
317GND              VIA   -    MD0100PA00X+006932Y+088065X0190Y         S0      
317GND              VIA   -    MD0100PA00X+008002Y+087061X0190Y         S0      
317GND              VIA   -    MD0100PA00X+007477Y+086392X0190Y    R180 S0      
317GND              VIA   -    MD0100PA00X+006932Y+085723X0190Y         S0      
317GND              VIA   -    MD0100PA00X+008106Y+086559X0190Y         S0      
317GND              VIA   -    MD0100PA00X+008002Y+086057X0190Y         S0      
317GND              VIA   -    MD0100PA00X+006932Y+096766X0190Y         S0      
317GND              VIA   -    MD0100PA00X+006932Y+096097X0190Y         S0      
317GND              VIA   -    MD0100PA00X+007477Y+094758X0190Y    R180 S0      
317GND              VIA   -    MD0100PA00X+006932Y+095427X0190Y         S0      
317GND              VIA   -    MD0100PA00X+008002Y+094423X0190Y         S0      
317GND              VIA   -    MD0100PA00X+006932Y+093085X0190Y         S0      
317GND              VIA   -    MD0100PA00X+007477Y+093754X0190Y    R180 S0      
317GND              VIA   -    MD0100PA00X+008002Y+093419X0190Y         S0      
317GND              VIA   -    MD0100PA00X+008106Y+093921X0190Y         S0      
317GND              VIA   -    MD0100PA00X+006932Y+091746X0190Y         S0      
317GND              VIA   -    MD0100PA00X+006932Y+092416X0190Y         S0      
317GND              VIA   -    MD0100PA00X+007477Y+091077X0190Y    R180 S0      
317GND              VIA   -    MD0100PA00X+008002Y+090742X0190Y         S0      
317GND              VIA   -    MD0100PA00X+007477Y+090073X0190Y    R180 S0      
317GND              VIA   -    MD0100PA00X+006932Y+106136X0190Y         S0      
317GND              VIA   -    MD0100PA00X+006932Y+107140X0190Y         S0      
317GND              VIA   -    MD0100PA00X+006932Y+105467X0190Y         S0      
317GND              VIA   -    MD0100PA00X+006932Y+104797X0190Y         S0      
317GND              VIA   -    MD0100PA00X+006932Y+104128X0190Y         S0      
317GND              VIA   -    MD0100PA00X+006932Y+103459X0190Y         S0      
317GND              VIA   -    MD0100PA00X+006932Y+100447X0190Y         S0      
317GND              VIA   -    MD0100PA00X+006932Y+099443X0190Y         S0      
317GND              VIA   -    MD0100PA00X+006932Y+098774X0190Y         S0      
317GND              VIA   -    MD0100PA00X+006932Y+098104X0190Y         S0      
317GND              VIA   -    MD0100PA00X+006932Y+097435X0190Y         S0      
317GND              VIA   -    MD0100PA00X+007477Y+113164X0190Y    R180 S0      
317GND              VIA   -    MD0100PA00X+007477Y+112160X0190Y    R180 S0      
317GND              VIA   -    MD0100PA00X+008106Y+112327X0190Y         S0      
317GND              VIA   -    MD0100PA00X+008002Y+112829X0190Y         S0      
317GND              VIA   -    MD0100PA00X+006932Y+110821X0190Y         S0      
317GND              VIA   -    MD0100PA00X+006932Y+111490X0190Y         S0      
317GND              VIA   -    MD0100PA00X+008002Y+111825X0190Y         S0      
317GND              VIA   -    MD0100PA00X+007477Y+109482X0190Y    R180 S0      
317GND              VIA   -    MD0100PA00X+006932Y+110152X0190Y         S0      
317GND              VIA   -    MD0100PA00X+008002Y+109148X0190Y         S0      
317GND              VIA   -    MD0100PA00X+006932Y+107809X0190Y         S0      
317GND              VIA   -    MD0100PA00X+007477Y+108478X0190Y    R180 S0      
317GND              VIA   -    MD0100PA00X+008106Y+108646X0190Y         S0      
317GND              VIA   -    MD0100PA00X+008002Y+108144X0190Y         S0      
317GND              VIA   -    MD0100PA00X+006932Y+118852X0190Y         S0      
317GND              VIA   -    MD0100PA00X+008002Y+119187X0190Y         S0      
317GND              VIA   -    MD0100PA00X+006932Y+118183X0190Y         S0      
317GND              VIA   -    MD0100PA00X+007477Y+116845X0190Y    R180 S0      
317GND              VIA   -    MD0100PA00X+006932Y+117514X0190Y         S0      
317GND              VIA   -    MD0100PA00X+007477Y+115841X0190Y    R180 S0      
317GND              VIA   -    MD0100PA00X+006932Y+115171X0190Y         S0      
317GND              VIA   -    MD0100PA00X+008002Y+115506X0190Y         S0      
317GND              VIA   -    MD0100PA00X+008106Y+116008X0190Y         S0      
317GND              VIA   -    MD0100PA00X+008002Y+116510X0190Y         S0      
317GND              VIA   -    MD0100PA00X+006932Y+113833X0190Y         S0      
317GND              VIA   -    MD0100PA00X+006932Y+114502X0190Y         S0      
317GND              VIA   -    MD0100PA00X+006932Y+125545X0190Y         S0      
317GND              VIA   -    MD0100PA00X+006932Y+124876X0190Y         S0      
317GND              VIA   -    MD0100PA00X+007477Y+124207X0190Y    R180 S0      
317GND              VIA   -    MD0100PA00X+007477Y+123203X0190Y    R180 S0      
317GND              VIA   -    MD0100PA00X+006932Y+122534X0190Y         S0      
317GND              VIA   -    MD0100PA00X+008106Y+123370X0190Y         S0      
317GND              VIA   -    MD0100PA00X+008002Y+122868X0190Y         S0      
317GND              VIA   -    MD0100PA00X+008002Y+123872X0190Y         S0      
317GND              VIA   -    MD0100PA00X+006932Y+121864X0190Y         S0      
317GND              VIA   -    MD0100PA00X+006932Y+121195X0190Y         S0      
317GND              VIA   -    MD0100PA00X+007477Y+120526X0190Y    R180 S0      
317GND              VIA   -    MD0100PA00X+007477Y+119522X0190Y    R180 S0      
317GND              VIA   -    MD0100PA00X+008002Y+120191X0190Y         S0      
317GND              VIA   -    MD0100PA00X+008106Y+119689X0190Y         S0      
317GND              VIA   -    MD0100PA00X+008546Y+078026X0190Y         S0      
317GND              VIA   -    MD0100PA00X+008546Y+081707X0190Y         S0      
317GND              VIA   -    MD0100PA00X+008546Y+081038X0190Y         S0      
317GND              VIA   -    MD0100PA00X+009462Y+079532X0190Y         S0      
317GND              VIA   -    MD0100PA00X+008546Y+080368X0190Y         S0      
317GND              VIA   -    MD0100PA00X+009462Y+083213X0190Y         S0      
317GND              VIA   -    MD0100PA00X+008546Y+085388X0190Y         S0      
317GND              VIA   -    MD0100PA00X+008546Y+084719X0190Y         S0      
317GND              VIA   -    MD0100PA00X+008546Y+084049X0190Y         S0      
317GND              VIA   -    MD0100PA00X+008546Y+088400X0190Y         S0      
317GND              VIA   -    MD0100PA00X+008546Y+089069X0190Y         S0      
317GND              VIA   -    MD0100PA00X+009462Y+086894X0190Y         S0      
317GND              VIA   -    MD0100PA00X+008546Y+087730X0190Y         S0      
317GND              VIA   -    MD0100PA00X+008546Y+091412X0190Y         S0      
317GND              VIA   -    MD0100PA00X+008546Y+092081X0190Y         S0      
317GND              VIA   -    MD0100PA00X+009462Y+090575X0190Y         S0      
317GND              VIA   -    MD0100PA00X+009462Y+094256X0190Y         S0      
317GND              VIA   -    MD0100PA00X+008546Y+095093X0190Y         S0      
317GND              VIA   -    MD0100PA00X+008546Y+092750X0190Y         S0      
317GND              VIA   -    MD0100PA00X+008546Y+096431X0190Y         S0      
317GND              VIA   -    MD0100PA00X+008546Y+097100X0190Y         S0      
317GND              VIA   -    MD0100PA00X+008546Y+095762X0190Y         S0      
317GND              VIA   -    MD0100PA00X+008546Y+100447X0190Y         S0      
317GND              VIA   -    MD0100PA00X+008546Y+099778X0190Y         S0      
317GND              VIA   -    MD0100PA00X+008546Y+099108X0190Y         S0      
317GND              VIA   -    MD0100PA00X+008546Y+097770X0190Y         S0      
317GND              VIA   -    MD0100PA00X+008546Y+098439X0190Y         S0      
317GND              VIA   -    MD0100PA00X+008546Y+105801X0190Y         S0      
317GND              VIA   -    MD0100PA00X+008546Y+105132X0190Y         S0      
317GND              VIA   -    MD0100PA00X+008546Y+103793X0190Y         S0      
317GND              VIA   -    MD0100PA00X+008546Y+103124X0190Y         S0      
317GND              VIA   -    MD0100PA00X+008546Y+104463X0190Y         S0      
317GND              VIA   -    MD0100PA00X+009462Y+108980X0190Y         S0      
317GND              VIA   -    MD0100PA00X+008546Y+107474X0190Y         S0      
317GND              VIA   -    MD0100PA00X+008546Y+106805X0190Y         S0      
317GND              VIA   -    MD0100PA00X+008546Y+111156X0190Y         S0      
317GND              VIA   -    MD0100PA00X+008546Y+110486X0190Y         S0      
317GND              VIA   -    MD0100PA00X+008546Y+109817X0190Y         S0      
317GND              VIA   -    MD0100PA00X+008546Y+114168X0190Y         S0      
317GND              VIA   -    MD0100PA00X+008546Y+114837X0190Y         S0      
317GND              VIA   -    MD0100PA00X+008546Y+113498X0190Y         S0      
317GND              VIA   -    MD0100PA00X+009462Y+112662X0190Y         S0      
317GND              VIA   -    MD0100PA00X+008546Y+117179X0190Y         S0      
317GND              VIA   -    MD0100PA00X+008546Y+117849X0190Y         S0      
317GND              VIA   -    MD0100PA00X+009462Y+116343X0190Y         S0      
317GND              VIA   -    MD0100PA00X+009462Y+120024X0190Y         S0      
317GND              VIA   -    MD0100PA00X+008546Y+120860X0190Y         S0      
317GND              VIA   -    MD0100PA00X+008546Y+118518X0190Y         S0      
317GND              VIA   -    MD0100PA00X+009462Y+123705X0190Y         S0      
317GND              VIA   -    MD0100PA00X+008546Y+122199X0190Y         S0      
317GND              VIA   -    MD0100PA00X+008546Y+121530X0190Y         S0      
317GND              VIA   -    MD0100PA00X+008546Y+124542X0190Y         S0      
317GND              VIA   -    MD0100PA00X+008546Y+125211X0190Y         S0      
317GND              VIA   -    MD0100PA00X+011077Y+079197X0190Y         S0      
317GND              VIA   -    MD0100PA00X+010972Y+078695X0190Y         S0      
317GND              VIA   -    MD0100PA00X+009902Y+078360X0190Y         S0      
317GND              VIA   -    MD0100PA00X+010447Y+079030X0190Y    R180 S0      
317GND              VIA   -    MD0100PA00X+009902Y+077691X0190Y         S0      
317GND              VIA   -    MD0100PA00X+011077Y+082878X0190Y         S0      
317GND              VIA   -    MD0100PA00X+010972Y+083380X0190Y         S0      
317GND              VIA   -    MD0100PA00X+010972Y+082376X0190Y         S0      
317GND              VIA   -    MD0100PA00X+010447Y+083715X0190Y    R180 S0      
317GND              VIA   -    MD0100PA00X+010447Y+082711X0190Y    R180 S0      
317GND              VIA   -    MD0100PA00X+009902Y+082042X0190Y         S0      
317GND              VIA   -    MD0100PA00X+009902Y+081372X0190Y         S0      
317GND              VIA   -    MD0100PA00X+010972Y+079699X0190Y         S0      
317GND              VIA   -    MD0100PA00X+010447Y+080034X0190Y    R180 S0      
317GND              VIA   -    MD0100PA00X+009902Y+080703X0190Y         S0      
317GND              VIA   -    MD0100PA00X+009902Y+089404X0190Y         S0      
317GND              VIA   -    MD0100PA00X+009902Y+088734X0190Y         S0      
317GND              VIA   -    MD0100PA00X+010972Y+087061X0190Y         S0      
317GND              VIA   -    MD0100PA00X+010447Y+087396X0190Y    R180 S0      
317GND              VIA   -    MD0100PA00X+009902Y+088065X0190Y         S0      
317GND              VIA   -    MD0100PA00X+011077Y+086559X0190Y         S0      
317GND              VIA   -    MD0100PA00X+010972Y+086057X0190Y         S0      
317GND              VIA   -    MD0100PA00X+010447Y+086392X0190Y    R180 S0      
317GND              VIA   -    MD0100PA00X+009902Y+085723X0190Y         S0      
317GND              VIA   -    MD0100PA00X+009902Y+085053X0190Y         S0      
317GND              VIA   -    MD0100PA00X+009902Y+084384X0190Y         S0      
317GND              VIA   -    MD0100PA00X+009902Y+096766X0190Y         S0      
317GND              VIA   -    MD0100PA00X+009902Y+096097X0190Y         S0      
317GND              VIA   -    MD0100PA00X+010972Y+094423X0190Y         S0      
317GND              VIA   -    MD0100PA00X+010447Y+094758X0190Y    R180 S0      
317GND              VIA   -    MD0100PA00X+009902Y+095427X0190Y         S0      
317GND              VIA   -    MD0100PA00X+010972Y+093419X0190Y         S0      
317GND              VIA   -    MD0100PA00X+011077Y+093921X0190Y         S0      
317GND              VIA   -    MD0100PA00X+009902Y+093085X0190Y         S0      
317GND              VIA   -    MD0100PA00X+010447Y+093754X0190Y    R180 S0      
317GND              VIA   -    MD0100PA00X+009902Y+091746X0190Y         S0      
317GND              VIA   -    MD0100PA00X+009902Y+092416X0190Y         S0      
317GND              VIA   -    MD0100PA00X+010972Y+090742X0190Y         S0      
317GND              VIA   -    MD0100PA00X+010447Y+091077X0190Y    R180 S0      
317GND              VIA   -    MD0100PA00X+011077Y+090240X0190Y         S0      
317GND              VIA   -    MD0100PA00X+010972Y+089738X0190Y         S0      
317GND              VIA   -    MD0100PA00X+010447Y+090073X0190Y    R180 S0      
317GND              VIA   -    MD0100PA00X+010447Y+108478X0190Y    R180 S0      
317GND              VIA   -    MD0100PA00X+009902Y+106136X0190Y         S0      
317GND              VIA   -    MD0100PA00X+009902Y+107140X0190Y         S0      
317GND              VIA   -    MD0100PA00X+009902Y+105467X0190Y         S0      
317GND              VIA   -    MD0100PA00X+009902Y+104797X0190Y         S0      
317GND              VIA   -    MD0100PA00X+009902Y+104128X0190Y         S0      
317GND              VIA   -    MD0100PA00X+009902Y+103459X0190Y         S0      
317GND              VIA   -    MD0100PA00X+009902Y+100447X0190Y         S0      
317GND              VIA   -    MD0100PA00X+009902Y+099443X0190Y         S0      
317GND              VIA   -    MD0100PA00X+009902Y+098774X0190Y         S0      
317GND              VIA   -    MD0100PA00X+009902Y+098104X0190Y         S0      
317GND              VIA   -    MD0100PA00X+009902Y+097435X0190Y         S0      
317GND              VIA   -    MD0100PA00X+009902Y+113833X0190Y         S0      
317GND              VIA   -    MD0100PA00X+009902Y+114502X0190Y         S0      
317GND              VIA   -    MD0100PA00X+010447Y+113164X0190Y    R180 S0      
317GND              VIA   -    MD0100PA00X+011077Y+112327X0190Y         S0      
317GND              VIA   -    MD0100PA00X+010972Y+112829X0190Y         S0      
317GND              VIA   -    MD0100PA00X+010447Y+112160X0190Y    R180 S0      
317GND              VIA   -    MD0100PA00X+010972Y+111825X0190Y         S0      
317GND              VIA   -    MD0100PA00X+009902Y+110821X0190Y         S0      
317GND              VIA   -    MD0100PA00X+009902Y+111490X0190Y         S0      
317GND              VIA   -    MD0100PA00X+010972Y+109148X0190Y         S0      
317GND              VIA   -    MD0100PA00X+010447Y+109482X0190Y    R180 S0      
317GND              VIA   -    MD0100PA00X+009902Y+110152X0190Y         S0      
317GND              VIA   -    MD0100PA00X+011077Y+108646X0190Y         S0      
317GND              VIA   -    MD0100PA00X+010972Y+108144X0190Y         S0      
317GND              VIA   -    MD0100PA00X+009902Y+107809X0190Y         S0      
317GND              VIA   -    MD0100PA00X+009902Y+121864X0190Y         S0      
317GND              VIA   -    MD0100PA00X+009902Y+121195X0190Y         S0      
317GND              VIA   -    MD0100PA00X+010972Y+120191X0190Y         S0      
317GND              VIA   -    MD0100PA00X+011077Y+119689X0190Y         S0      
317GND              VIA   -    MD0100PA00X+010447Y+120526X0190Y    R180 S0      
317GND              VIA   -    MD0100PA00X+010447Y+119522X0190Y    R180 S0      
317GND              VIA   -    MD0100PA00X+010972Y+119187X0190Y         S0      
317GND              VIA   -    MD0100PA00X+009902Y+118852X0190Y         S0      
317GND              VIA   -    MD0100PA00X+009902Y+118183X0190Y         S0      
317GND              VIA   -    MD0100PA00X+010447Y+116845X0190Y    R180 S0      
317GND              VIA   -    MD0100PA00X+009902Y+117514X0190Y         S0      
317GND              VIA   -    MD0100PA00X+010972Y+115506X0190Y         S0      
317GND              VIA   -    MD0100PA00X+011077Y+116008X0190Y         S0      
317GND              VIA   -    MD0100PA00X+010972Y+116510X0190Y         S0      
317GND              VIA   -    MD0100PA00X+009902Y+115171X0190Y         S0      
317GND              VIA   -    MD0100PA00X+010447Y+115841X0190Y    R180 S0      
317GND              VIA   -    MD0100PA00X+009902Y+125545X0190Y         S0      
317GND              VIA   -    MD0100PA00X+009902Y+124876X0190Y         S0      
317GND              VIA   -    MD0100PA00X+010447Y+124207X0190Y    R180 S0      
317GND              VIA   -    MD0100PA00X+011077Y+123370X0190Y         S0      
317GND              VIA   -    MD0100PA00X+010972Y+123872X0190Y         S0      
317GND              VIA   -    MD0100PA00X+010972Y+122868X0190Y         S0      
317GND              VIA   -    MD0100PA00X+009902Y+122534X0190Y         S0      
317GND              VIA   -    MD0100PA00X+010447Y+123203X0190Y    R180 S0      
317GND              VIA   -    MD0100PA00X+011517Y+078026X0190Y         S0      
317GND              VIA   -    MD0100PA00X+011517Y+080368X0190Y         S0      
317GND              VIA   -    MD0100PA00X+012432Y+079532X0190Y         S0      
317GND              VIA   -    MD0100PA00X+012432Y+083213X0190Y         S0      
317GND              VIA   -    MD0100PA00X+011517Y+081707X0190Y         S0      
317GND              VIA   -    MD0100PA00X+011517Y+081038X0190Y         S0      
317GND              VIA   -    MD0100PA00X+011517Y+084719X0190Y         S0      
317GND              VIA   -    MD0100PA00X+011517Y+084049X0190Y         S0      
317GND              VIA   -    MD0100PA00X+012432Y+086894X0190Y         S0      
317GND              VIA   -    MD0100PA00X+011517Y+087730X0190Y         S0      
317GND              VIA   -    MD0100PA00X+011517Y+085388X0190Y         S0      
317GND              VIA   -    MD0100PA00X+012432Y+090575X0190Y         S0      
317GND              VIA   -    MD0100PA00X+011517Y+088400X0190Y         S0      
317GND              VIA   -    MD0100PA00X+011517Y+089069X0190Y         S0      
317GND              VIA   -    MD0100PA00X+012432Y+094256X0190Y         S0      
317GND              VIA   -    MD0100PA00X+011517Y+095093X0190Y         S0      
317GND              VIA   -    MD0100PA00X+011517Y+092750X0190Y         S0      
317GND              VIA   -    MD0100PA00X+011517Y+091412X0190Y         S0      
317GND              VIA   -    MD0100PA00X+011517Y+092081X0190Y         S0      
317GND              VIA   -    MD0100PA00X+011517Y+097770X0190Y         S0      
317GND              VIA   -    MD0100PA00X+011517Y+098439X0190Y         S0      
317GND              VIA   -    MD0100PA00X+011517Y+096431X0190Y         S0      
317GND              VIA   -    MD0100PA00X+011517Y+097100X0190Y         S0      
317GND              VIA   -    MD0100PA00X+011517Y+095762X0190Y         S0      
317GND              VIA   -    MD0100PA00X+011517Y+105801X0190Y         S0      
317GND              VIA   -    MD0100PA00X+011517Y+105132X0190Y         S0      
317GND              VIA   -    MD0100PA00X+011517Y+104463X0190Y         S0      
317GND              VIA   -    MD0100PA00X+011517Y+103793X0190Y         S0      
317GND              VIA   -    MD0100PA00X+011517Y+103124X0190Y         S0      
317GND              VIA   -    MD0100PA00X+011517Y+100447X0190Y         S0      
317GND              VIA   -    MD0100PA00X+011517Y+099778X0190Y         S0      
317GND              VIA   -    MD0100PA00X+011517Y+099108X0190Y         S0      
317GND              VIA   -    MD0100PA00X+012432Y+108980X0190Y         S0      
317GND              VIA   -    MD0100PA00X+011517Y+107474X0190Y         S0      
317GND              VIA   -    MD0100PA00X+011517Y+106805X0190Y         S0      
317GND              VIA   -    MD0100PA00X+011517Y+113498X0190Y         S0      
317GND              VIA   -    MD0100PA00X+012432Y+112662X0190Y         S0      
317GND              VIA   -    MD0100PA00X+011517Y+111156X0190Y         S0      
317GND              VIA   -    MD0100PA00X+011517Y+110486X0190Y         S0      
317GND              VIA   -    MD0100PA00X+011517Y+109817X0190Y         S0      
317GND              VIA   -    MD0100PA00X+011517Y+117179X0190Y         S0      
317GND              VIA   -    MD0100PA00X+011517Y+117849X0190Y         S0      
317GND              VIA   -    MD0100PA00X+012432Y+116343X0190Y         S0      
317GND              VIA   -    MD0100PA00X+011517Y+114168X0190Y         S0      
317GND              VIA   -    MD0100PA00X+011517Y+114837X0190Y         S0      
317GND              VIA   -    MD0100PA00X+012432Y+120024X0190Y         S0      
317GND              VIA   -    MD0100PA00X+011517Y+120860X0190Y         S0      
317GND              VIA   -    MD0100PA00X+011517Y+118518X0190Y         S0      
317GND              VIA   -    MD0100PA00X+011517Y+124542X0190Y         S0      
317GND              VIA   -    MD0100PA00X+011517Y+125211X0190Y         S0      
317GND              VIA   -    MD0100PA00X+012432Y+123705X0190Y         S0      
317GND              VIA   -    MD0100PA00X+011517Y+122199X0190Y         S0      
317GND              VIA   -    MD0100PA00X+011517Y+121530X0190Y         S0      
317GND              VIA   -    MD0100PA00X+012872Y+077691X0190Y         S0      
317GND              VIA   -    MD0100PA00X+012872Y+082042X0190Y         S0      
317GND              VIA   -    MD0100PA00X+012872Y+081372X0190Y         S0      
317GND              VIA   -    MD0100PA00X+013942Y+079699X0190Y         S0      
317GND              VIA   -    MD0100PA00X+013417Y+080034X0190Y    R180 S0      
317GND              VIA   -    MD0100PA00X+012872Y+080703X0190Y         S0      
317GND              VIA   -    MD0100PA00X+014047Y+079197X0190Y         S0      
317GND              VIA   -    MD0100PA00X+012872Y+078360X0190Y         S0      
317GND              VIA   -    MD0100PA00X+013942Y+078695X0190Y         S0      
317GND              VIA   -    MD0100PA00X+013417Y+079030X0190Y    R180 S0      
317GND              VIA   -    MD0100PA00X+014047Y+086559X0190Y         S0      
317GND              VIA   -    MD0100PA00X+013942Y+086057X0190Y         S0      
317GND              VIA   -    MD0100PA00X+013417Y+086392X0190Y    R180 S0      
317GND              VIA   -    MD0100PA00X+012872Y+085723X0190Y         S0      
317GND              VIA   -    MD0100PA00X+012872Y+085053X0190Y         S0      
317GND              VIA   -    MD0100PA00X+012872Y+084384X0190Y         S0      
317GND              VIA   -    MD0100PA00X+013417Y+082711X0190Y    R180 S0      
317GND              VIA   -    MD0100PA00X+014047Y+082878X0190Y         S0      
317GND              VIA   -    MD0100PA00X+013942Y+083380X0190Y         S0      
317GND              VIA   -    MD0100PA00X+013942Y+082376X0190Y         S0      
317GND              VIA   -    MD0100PA00X+013417Y+083715X0190Y    R180 S0      
317GND              VIA   -    MD0100PA00X+012872Y+093085X0190Y         S0      
317GND              VIA   -    MD0100PA00X+013942Y+093419X0190Y         S0      
317GND              VIA   -    MD0100PA00X+014047Y+093921X0190Y         S0      
317GND              VIA   -    MD0100PA00X+013417Y+093754X0190Y    R180 S0      
317GND              VIA   -    MD0100PA00X+012872Y+091746X0190Y         S0      
317GND              VIA   -    MD0100PA00X+012872Y+092416X0190Y         S0      
317GND              VIA   -    MD0100PA00X+013942Y+090742X0190Y         S0      
317GND              VIA   -    MD0100PA00X+013417Y+091077X0190Y    R180 S0      
317GND              VIA   -    MD0100PA00X+014047Y+090240X0190Y         S0      
317GND              VIA   -    MD0100PA00X+013942Y+089738X0190Y         S0      
317GND              VIA   -    MD0100PA00X+013417Y+090073X0190Y    R180 S0      
317GND              VIA   -    MD0100PA00X+012872Y+089404X0190Y         S0      
317GND              VIA   -    MD0100PA00X+012872Y+088734X0190Y         S0      
317GND              VIA   -    MD0100PA00X+013942Y+087061X0190Y         S0      
317GND              VIA   -    MD0100PA00X+012872Y+088065X0190Y         S0      
317GND              VIA   -    MD0100PA00X+013417Y+087396X0190Y    R180 S0      
317GND              VIA   -    MD0100PA00X+012872Y+100447X0190Y         S0      
317GND              VIA   -    MD0100PA00X+012872Y+099443X0190Y         S0      
317GND              VIA   -    MD0100PA00X+012872Y+098774X0190Y         S0      
317GND              VIA   -    MD0100PA00X+012872Y+098104X0190Y         S0      
317GND              VIA   -    MD0100PA00X+012872Y+097435X0190Y         S0      
317GND              VIA   -    MD0100PA00X+012872Y+096766X0190Y         S0      
317GND              VIA   -    MD0100PA00X+012872Y+096097X0190Y         S0      
317GND              VIA   -    MD0100PA00X+013942Y+094423X0190Y         S0      
317GND              VIA   -    MD0100PA00X+013417Y+094758X0190Y    R180 S0      
317GND              VIA   -    MD0100PA00X+012872Y+095427X0190Y         S0      
317GND              VIA   -    MD0100PA00X+013417Y+109482X0190Y    R180 S0      
317GND              VIA   -    MD0100PA00X+013942Y+109148X0190Y         S0      
317GND              VIA   -    MD0100PA00X+012872Y+110152X0190Y         S0      
317GND              VIA   -    MD0100PA00X+012872Y+107809X0190Y         S0      
317GND              VIA   -    MD0100PA00X+014047Y+108646X0190Y         S0      
317GND              VIA   -    MD0100PA00X+013417Y+108478X0190Y    R180 S0      
317GND              VIA   -    MD0100PA00X+013942Y+108144X0190Y         S0      
317GND              VIA   -    MD0100PA00X+012872Y+106136X0190Y         S0      
317GND              VIA   -    MD0100PA00X+012872Y+107140X0190Y         S0      
317GND              VIA   -    MD0100PA00X+012872Y+105467X0190Y         S0      
317GND              VIA   -    MD0100PA00X+012872Y+104797X0190Y         S0      
317GND              VIA   -    MD0100PA00X+012872Y+104128X0190Y         S0      
317GND              VIA   -    MD0100PA00X+012872Y+103459X0190Y         S0      
317GND              VIA   -    MD0100PA00X+012872Y+115171X0190Y         S0      
317GND              VIA   -    MD0100PA00X+013942Y+115506X0190Y         S0      
317GND              VIA   -    MD0100PA00X+013417Y+115841X0190Y    R180 S0      
317GND              VIA   -    MD0100PA00X+014047Y+116008X0190Y         S0      
317GND              VIA   -    MD0100PA00X+013942Y+116510X0190Y         S0      
317GND              VIA   -    MD0100PA00X+012872Y+113833X0190Y         S0      
317GND              VIA   -    MD0100PA00X+012872Y+114502X0190Y         S0      
317GND              VIA   -    MD0100PA00X+013417Y+113164X0190Y    R180 S0      
317GND              VIA   -    MD0100PA00X+014047Y+112327X0190Y         S0      
317GND              VIA   -    MD0100PA00X+013417Y+112160X0190Y    R180 S0      
317GND              VIA   -    MD0100PA00X+013942Y+112829X0190Y         S0      
317GND              VIA   -    MD0100PA00X+012872Y+110821X0190Y         S0      
317GND              VIA   -    MD0100PA00X+013942Y+111825X0190Y         S0      
317GND              VIA   -    MD0100PA00X+012872Y+111490X0190Y         S0      
317GND              VIA   -    MD0100PA00X+013942Y+123872X0190Y         S0      
317GND              VIA   -    MD0100PA00X+014047Y+123370X0190Y         S0      
317GND              VIA   -    MD0100PA00X+013942Y+122868X0190Y         S0      
317GND              VIA   -    MD0100PA00X+012872Y+121864X0190Y         S0      
317GND              VIA   -    MD0100PA00X+012872Y+121195X0190Y         S0      
317GND              VIA   -    MD0100PA00X+013942Y+120191X0190Y         S0      
317GND              VIA   -    MD0100PA00X+013417Y+120526X0190Y    R180 S0      
317GND              VIA   -    MD0100PA00X+014047Y+119689X0190Y         S0      
317GND              VIA   -    MD0100PA00X+013417Y+119522X0190Y    R180 S0      
317GND              VIA   -    MD0100PA00X+012872Y+118852X0190Y         S0      
317GND              VIA   -    MD0100PA00X+013942Y+119187X0190Y         S0      
317GND              VIA   -    MD0100PA00X+012872Y+118183X0190Y         S0      
317GND              VIA   -    MD0100PA00X+013417Y+116845X0190Y    R180 S0      
317GND              VIA   -    MD0100PA00X+012872Y+117514X0190Y         S0      
317GND              VIA   -    MD0100PA00X+012872Y+125545X0190Y         S0      
317GND              VIA   -    MD0100PA00X+012872Y+124876X0190Y         S0      
317GND              VIA   -    MD0100PA00X+013417Y+124207X0190Y    R180 S0      
317GND              VIA   -    MD0100PA00X+013417Y+123203X0190Y    R180 S0      
317GND              VIA   -    MD0100PA00X+012872Y+122534X0190Y         S0      
317GND              VIA   -    MD0100PA00X+014487Y+078026X0190Y         S0      
317GND              VIA   -    MD0100PA00X+014487Y+080368X0190Y         S0      
317GND              VIA   -    MD0100PA00X+015402Y+079532X0190Y         S0      
317GND              VIA   -    MD0100PA00X+015402Y+083213X0190Y         S0      
317GND              VIA   -    MD0100PA00X+014487Y+081707X0190Y         S0      
317GND              VIA   -    MD0100PA00X+014487Y+081038X0190Y         S0      
317GND              VIA   -    MD0100PA00X+014487Y+084719X0190Y         S0      
317GND              VIA   -    MD0100PA00X+014487Y+084049X0190Y         S0      
317GND              VIA   -    MD0100PA00X+014487Y+085388X0190Y         S0      
317GND              VIA   -    MD0100PA00X+015402Y+090575X0190Y         S0      
317GND              VIA   -    MD0100PA00X+014487Y+088400X0190Y         S0      
317GND              VIA   -    MD0100PA00X+014487Y+089069X0190Y         S0      
317GND              VIA   -    MD0100PA00X+015402Y+086894X0190Y         S0      
317GND              VIA   -    MD0100PA00X+014487Y+087730X0190Y         S0      
317GND              VIA   -    MD0100PA00X+014487Y+092750X0190Y         S0      
317GND              VIA   -    MD0100PA00X+014487Y+091412X0190Y         S0      
317GND              VIA   -    MD0100PA00X+014487Y+092081X0190Y         S0      
317GND              VIA   -    MD0100PA00X+014487Y+097770X0190Y         S0      
317GND              VIA   -    MD0100PA00X+014487Y+098439X0190Y         S0      
317GND              VIA   -    MD0100PA00X+014487Y+096431X0190Y         S0      
317GND              VIA   -    MD0100PA00X+014487Y+097100X0190Y         S0      
317GND              VIA   -    MD0100PA00X+014487Y+095762X0190Y         S0      
317GND              VIA   -    MD0100PA00X+014487Y+095093X0190Y         S0      
317GND              VIA   -    MD0100PA00X+015402Y+094256X0190Y         S0      
317GND              VIA   -    MD0100PA00X+014487Y+104463X0190Y         S0      
317GND              VIA   -    MD0100PA00X+014487Y+103793X0190Y         S0      
317GND              VIA   -    MD0100PA00X+014487Y+103124X0190Y         S0      
317GND              VIA   -    MD0100PA00X+014487Y+100447X0190Y         S0      
317GND              VIA   -    MD0100PA00X+014487Y+099778X0190Y         S0      
317GND              VIA   -    MD0100PA00X+014487Y+099108X0190Y         S0      
317GND              VIA   -    MD0100PA00X+015402Y+108980X0190Y         S0      
317GND              VIA   -    MD0100PA00X+014487Y+107474X0190Y         S0      
317GND              VIA   -    MD0100PA00X+014487Y+106805X0190Y         S0      
317GND              VIA   -    MD0100PA00X+014487Y+105801X0190Y         S0      
317GND              VIA   -    MD0100PA00X+014487Y+105132X0190Y         S0      
317GND              VIA   -    MD0100PA00X+014487Y+111156X0190Y         S0      
317GND              VIA   -    MD0100PA00X+014487Y+110486X0190Y         S0      
317GND              VIA   -    MD0100PA00X+014487Y+109817X0190Y         S0      
317GND              VIA   -    MD0100PA00X+015402Y+116343X0190Y         S0      
317GND              VIA   -    MD0100PA00X+014487Y+114168X0190Y         S0      
317GND              VIA   -    MD0100PA00X+014487Y+114837X0190Y         S0      
317GND              VIA   -    MD0100PA00X+014487Y+113498X0190Y         S0      
317GND              VIA   -    MD0100PA00X+015402Y+112662X0190Y         S0      
317GND              VIA   -    MD0100PA00X+015402Y+120024X0190Y         S0      
317GND              VIA   -    MD0100PA00X+014487Y+120860X0190Y         S0      
317GND              VIA   -    MD0100PA00X+014487Y+118518X0190Y         S0      
317GND              VIA   -    MD0100PA00X+014487Y+117179X0190Y         S0      
317GND              VIA   -    MD0100PA00X+014487Y+117849X0190Y         S0      
317GND              VIA   -    MD0100PA00X+015402Y+123705X0190Y         S0      
317GND              VIA   -    MD0100PA00X+014487Y+122199X0190Y         S0      
317GND              VIA   -    MD0100PA00X+014487Y+121530X0190Y         S0      
317GND              VIA   -    MD0100PA00X+014487Y+124542X0190Y         S0      
317GND              VIA   -    MD0100PA00X+014487Y+125211X0190Y         S0      
317GND              VIA   -    MD0100PA00X+015842Y+077691X0190Y         S0      
317GND              VIA   -    MD0100PA00X+016388Y+082711X0190Y    R180 S0      
317GND              VIA   -    MD0100PA00X+015842Y+082042X0190Y         S0      
317GND              VIA   -    MD0100PA00X+015842Y+081372X0190Y         S0      
317GND              VIA   -    MD0100PA00X+016912Y+079699X0190Y         S0      
317GND              VIA   -    MD0100PA00X+015842Y+080703X0190Y         S0      
317GND              VIA   -    MD0100PA00X+016388Y+080034X0190Y    R180 S0      
317GND              VIA   -    MD0100PA00X+017017Y+079197X0190Y         S0      
317GND              VIA   -    MD0100PA00X+016912Y+078695X0190Y         S0      
317GND              VIA   -    MD0100PA00X+015842Y+078360X0190Y         S0      
317GND              VIA   -    MD0100PA00X+016388Y+079030X0190Y    R180 S0      
317GND              VIA   -    MD0100PA00X+015842Y+089404X0190Y         S0      
317GND              VIA   -    MD0100PA00X+015842Y+088734X0190Y         S0      
317GND              VIA   -    MD0100PA00X+016912Y+087061X0190Y         S0      
317GND              VIA   -    MD0100PA00X+015842Y+088065X0190Y         S0      
317GND              VIA   -    MD0100PA00X+016388Y+087396X0190Y    R180 S0      
317GND              VIA   -    MD0100PA00X+017017Y+086559X0190Y         S0      
317GND              VIA   -    MD0100PA00X+016912Y+086057X0190Y         S0      
317GND              VIA   -    MD0100PA00X+015842Y+085723X0190Y         S0      
317GND              VIA   -    MD0100PA00X+016388Y+086392X0190Y    R180 S0      
317GND              VIA   -    MD0100PA00X+015842Y+085053X0190Y         S0      
317GND              VIA   -    MD0100PA00X+015842Y+084384X0190Y         S0      
317GND              VIA   -    MD0100PA00X+017017Y+082878X0190Y         S0      
317GND              VIA   -    MD0100PA00X+016912Y+083380X0190Y         S0      
317GND              VIA   -    MD0100PA00X+016912Y+082376X0190Y         S0      
317GND              VIA   -    MD0100PA00X+016388Y+083715X0190Y    R180 S0      
317GND              VIA   -    MD0100PA00X+016912Y+093419X0190Y         S0      
317GND              VIA   -    MD0100PA00X+017017Y+093921X0190Y         S0      
317GND              VIA   -    MD0100PA00X+015842Y+093085X0190Y         S0      
317GND              VIA   -    MD0100PA00X+016388Y+093754X0190Y    R180 S0      
317GND              VIA   -    MD0100PA00X+015842Y+091746X0190Y         S0      
317GND              VIA   -    MD0100PA00X+015842Y+092416X0190Y         S0      
317GND              VIA   -    MD0100PA00X+016912Y+090742X0190Y         S0      
317GND              VIA   -    MD0100PA00X+016388Y+091077X0190Y    R180 S0      
317GND              VIA   -    MD0100PA00X+017017Y+090240X0190Y         S0      
317GND              VIA   -    MD0100PA00X+016912Y+089738X0190Y         S0      
317GND              VIA   -    MD0100PA00X+016388Y+090073X0190Y    R180 S0      
317GND              VIA   -    MD0100PA00X+015842Y+100447X0190Y         S0      
317GND              VIA   -    MD0100PA00X+015842Y+099443X0190Y         S0      
317GND              VIA   -    MD0100PA00X+015842Y+098774X0190Y         S0      
317GND              VIA   -    MD0100PA00X+015842Y+098104X0190Y         S0      
317GND              VIA   -    MD0100PA00X+015842Y+097435X0190Y         S0      
317GND              VIA   -    MD0100PA00X+015842Y+096766X0190Y         S0      
317GND              VIA   -    MD0100PA00X+015842Y+096097X0190Y         S0      
317GND              VIA   -    MD0100PA00X+016912Y+094423X0190Y         S0      
317GND              VIA   -    MD0100PA00X+015842Y+095427X0190Y         S0      
317GND              VIA   -    MD0100PA00X+016388Y+094758X0190Y    R180 S0      
317GND              VIA   -    MD0100PA00X+016912Y+109148X0190Y         S0      
317GND              VIA   -    MD0100PA00X+015842Y+110152X0190Y         S0      
317GND              VIA   -    MD0100PA00X+016388Y+109482X0190Y    R180 S0      
317GND              VIA   -    MD0100PA00X+017017Y+108646X0190Y         S0      
317GND              VIA   -    MD0100PA00X+016912Y+108144X0190Y         S0      
317GND              VIA   -    MD0100PA00X+015842Y+107809X0190Y         S0      
317GND              VIA   -    MD0100PA00X+016388Y+108478X0190Y    R180 S0      
317GND              VIA   -    MD0100PA00X+015842Y+106136X0190Y         S0      
317GND              VIA   -    MD0100PA00X+015842Y+107140X0190Y         S0      
317GND              VIA   -    MD0100PA00X+015842Y+105467X0190Y         S0      
317GND              VIA   -    MD0100PA00X+015842Y+104797X0190Y         S0      
317GND              VIA   -    MD0100PA00X+015842Y+104128X0190Y         S0      
317GND              VIA   -    MD0100PA00X+015842Y+103459X0190Y         S0      
317GND              VIA   -    MD0100PA00X+015842Y+115171X0190Y         S0      
317GND              VIA   -    MD0100PA00X+016388Y+115841X0190Y    R180 S0      
317GND              VIA   -    MD0100PA00X+015842Y+113833X0190Y         S0      
317GND              VIA   -    MD0100PA00X+015842Y+114502X0190Y         S0      
317GND              VIA   -    MD0100PA00X+016388Y+113164X0190Y    R180 S0      
317GND              VIA   -    MD0100PA00X+017017Y+112327X0190Y         S0      
317GND              VIA   -    MD0100PA00X+016912Y+112829X0190Y         S0      
317GND              VIA   -    MD0100PA00X+016388Y+112160X0190Y    R180 S0      
317GND              VIA   -    MD0100PA00X+016912Y+111825X0190Y         S0      
317GND              VIA   -    MD0100PA00X+015842Y+110821X0190Y         S0      
317GND              VIA   -    MD0100PA00X+015842Y+111490X0190Y         S0      
317GND              VIA   -    MD0100PA00X+015842Y+121864X0190Y         S0      
317GND              VIA   -    MD0100PA00X+015842Y+121195X0190Y         S0      
317GND              VIA   -    MD0100PA00X+016912Y+120191X0190Y         S0      
317GND              VIA   -    MD0100PA00X+017017Y+119689X0190Y         S0      
317GND              VIA   -    MD0100PA00X+016388Y+120526X0190Y    R180 S0      
317GND              VIA   -    MD0100PA00X+016388Y+119522X0190Y    R180 S0      
317GND              VIA   -    MD0100PA00X+016912Y+119187X0190Y         S0      
317GND              VIA   -    MD0100PA00X+015842Y+118852X0190Y         S0      
317GND              VIA   -    MD0100PA00X+015842Y+118183X0190Y         S0      
317GND              VIA   -    MD0100PA00X+015842Y+117514X0190Y         S0      
317GND              VIA   -    MD0100PA00X+016388Y+116845X0190Y    R180 S0      
317GND              VIA   -    MD0100PA00X+016912Y+115506X0190Y         S0      
317GND              VIA   -    MD0100PA00X+017017Y+116008X0190Y         S0      
317GND              VIA   -    MD0100PA00X+016912Y+116510X0190Y         S0      
317GND              VIA   -    MD0100PA00X+015842Y+125545X0190Y         S0      
317GND              VIA   -    MD0100PA00X+015842Y+124876X0190Y         S0      
317GND              VIA   -    MD0100PA00X+016388Y+124207X0190Y    R180 S0      
317GND              VIA   -    MD0100PA00X+017017Y+123370X0190Y         S0      
317GND              VIA   -    MD0100PA00X+016912Y+122868X0190Y         S0      
317GND              VIA   -    MD0100PA00X+016912Y+123872X0190Y         S0      
317GND              VIA   -    MD0100PA00X+015842Y+122534X0190Y         S0      
317GND              VIA   -    MD0100PA00X+016388Y+123203X0190Y    R180 S0      
317GND              VIA   -    MD0100PA00X+017457Y+081707X0190Y         S0      
317GND              VIA   -    MD0100PA00X+017457Y+081038X0190Y         S0      
317GND              VIA   -    MD0100PA00X+017457Y+080368X0190Y         S0      
317GND              VIA   -    MD0100PA00X+017457Y+078026X0190Y         S0      
317GND              VIA   -    MD0100PA00X+017457Y+084719X0190Y         S0      
317GND              VIA   -    MD0100PA00X+017457Y+084049X0190Y         S0      
317GND              VIA   -    MD0100PA00X+017457Y+088400X0190Y         S0      
317GND              VIA   -    MD0100PA00X+017457Y+089069X0190Y         S0      
317GND              VIA   -    MD0100PA00X+017457Y+087730X0190Y         S0      
317GND              VIA   -    MD0100PA00X+017457Y+085388X0190Y         S0      
317GND              VIA   -    MD0100PA00X+017457Y+091412X0190Y         S0      
317GND              VIA   -    MD0100PA00X+017457Y+092081X0190Y         S0      
317GND              VIA   -    MD0100PA00X+017457Y+096431X0190Y         S0      
317GND              VIA   -    MD0100PA00X+017457Y+097100X0190Y         S0      
317GND              VIA   -    MD0100PA00X+017457Y+095762X0190Y         S0      
317GND              VIA   -    MD0100PA00X+017457Y+095093X0190Y         S0      
317GND              VIA   -    MD0100PA00X+017457Y+092750X0190Y         S0      
317GND              VIA   -    MD0100PA00X+017457Y+100447X0190Y         S0      
317GND              VIA   -    MD0100PA00X+017457Y+099778X0190Y         S0      
317GND              VIA   -    MD0100PA00X+017457Y+099108X0190Y         S0      
317GND              VIA   -    MD0100PA00X+017457Y+097770X0190Y         S0      
317GND              VIA   -    MD0100PA00X+017457Y+098439X0190Y         S0      
317GND              VIA   -    MD0100PA00X+017457Y+105801X0190Y         S0      
317GND              VIA   -    MD0100PA00X+017457Y+105132X0190Y         S0      
317GND              VIA   -    MD0100PA00X+017457Y+104463X0190Y         S0      
317GND              VIA   -    MD0100PA00X+017457Y+103793X0190Y         S0      
317GND              VIA   -    MD0100PA00X+017457Y+103124X0190Y         S0      
317GND              VIA   -    MD0100PA00X+017457Y+110486X0190Y         S0      
317GND              VIA   -    MD0100PA00X+017457Y+109817X0190Y         S0      
317GND              VIA   -    MD0100PA00X+017457Y+107474X0190Y         S0      
317GND              VIA   -    MD0100PA00X+017457Y+106805X0190Y         S0      
317GND              VIA   -    MD0100PA00X+017457Y+113498X0190Y         S0      
317GND              VIA   -    MD0100PA00X+017457Y+111156X0190Y         S0      
317GND              VIA   -    MD0100PA00X+017457Y+117179X0190Y         S0      
317GND              VIA   -    MD0100PA00X+017457Y+117849X0190Y         S0      
317GND              VIA   -    MD0100PA00X+017457Y+114168X0190Y         S0      
317GND              VIA   -    MD0100PA00X+017457Y+114837X0190Y         S0      
317GND              VIA   -    MD0100PA00X+017457Y+120860X0190Y         S0      
317GND              VIA   -    MD0100PA00X+017457Y+118518X0190Y         S0      
317GND              VIA   -    MD0100PA00X+017457Y+124542X0190Y         S0      
317GND              VIA   -    MD0100PA00X+017457Y+125211X0190Y         S0      
317GND              VIA   -    MD0100PA00X+017457Y+122199X0190Y         S0      
317GND              VIA   -    MD0100PA00X+017457Y+121530X0190Y         S0      
327GND              J32   -155        A01X+009902Y+079030X0205Y0590R090 S1      
327GND              J33   -10         A01X+008546Y+078695X0205Y0590R090 S1      
327GND              J33   -155        A01X+006932Y+079030X0205Y0590R090 S1      
327GND              J32   -166        A01X+009902Y+082711X0205Y0590R090 S1      
327GND              J32   -169        A01X+009902Y+083715X0205Y0590R090 S1      
327GND              J32   -158        A01X+009902Y+080034X0205Y0590R090 S1      
327GND              J33   -21         A01X+008546Y+082376X0205Y0590R090 S1      
327GND              J33   -24         A01X+008546Y+083380X0205Y0590R090 S1      
327GND              J33   -13         A01X+008546Y+079699X0205Y0590R090 S1      
327GND              J33   -166        A01X+006932Y+082711X0205Y0590R090 S1      
327GND              J33   -169        A01X+006932Y+083715X0205Y0590R090 S1      
327GND              J33   -158        A01X+006932Y+080034X0205Y0590R090 S1      
327GND              J32   -188        A01X+009902Y+090073X0205Y0590R090 S1      
327GND              J32   -180        A01X+009902Y+087396X0205Y0590R090 S1      
327GND              J32   -177        A01X+009902Y+086392X0205Y0590R090 S1      
327GND              J33   -43         A01X+008546Y+089738X0205Y0590R090 S1      
327GND              J33   -32         A01X+008546Y+086057X0205Y0590R090 S1      
327GND              J33   -35         A01X+008546Y+087061X0205Y0590R090 S1      
327GND              J33   -188        A01X+006932Y+090073X0205Y0590R090 S1      
327GND              J33   -180        A01X+006932Y+087396X0205Y0590R090 S1      
327GND              J33   -177        A01X+006932Y+086392X0205Y0590R090 S1      
327GND              J32   -199        A01X+009902Y+093754X0205Y0590R090 S1      
327GND              J32   -202        A01X+009902Y+094758X0205Y0590R090 S1      
327GND              J32   -191        A01X+009902Y+091077X0205Y0590R090 S1      
327GND              J33   -57         A01X+008546Y+094423X0205Y0590R090 S1      
327GND              J33   -54         A01X+008546Y+093419X0205Y0590R090 S1      
327GND              J33   -46         A01X+008546Y+090742X0205Y0590R090 S1      
327GND              J33   -199        A01X+006932Y+093754X0205Y0590R090 S1      
327GND              J33   -202        A01X+006932Y+094758X0205Y0590R090 S1      
327GND              J33   -191        A01X+006932Y+091077X0205Y0590R090 S1      
327GND              J32   -248        A01X+009902Y+112160X0205Y0590R090 S1      
327GND              J32   -237        A01X+009902Y+108478X0205Y0590R090 S1      
327GND              J32   -240        A01X+009902Y+109482X0205Y0590R090 S1      
327GND              J33   -106        A01X+008546Y+112829X0205Y0590R090 S1      
327GND              J33   -103        A01X+008546Y+111825X0205Y0590R090 S1      
327GND              J33   -92         A01X+008546Y+108144X0205Y0590R090 S1      
327GND              J33   -95         A01X+008546Y+109148X0205Y0590R090 S1      
327GND              J33   -248        A01X+006932Y+112160X0205Y0590R090 S1      
327GND              J33   -237        A01X+006932Y+108478X0205Y0590R090 S1      
327GND              J33   -240        A01X+006932Y+109482X0205Y0590R090 S1      
327GND              J32   -262        A01X+009902Y+116845X0205Y0590R090 S1      
327GND              J32   -259        A01X+009902Y+115841X0205Y0590R090 S1      
327GND              J32   -251        A01X+009902Y+113164X0205Y0590R090 S1      
327GND              J33   -117        A01X+008546Y+116510X0205Y0590R090 S1      
327GND              J33   -114        A01X+008546Y+115506X0205Y0590R090 S1      
327GND              J33   -262        A01X+006932Y+116845X0205Y0590R090 S1      
327GND              J33   -259        A01X+006932Y+115841X0205Y0590R090 S1      
327GND              J33   -251        A01X+006932Y+113164X0205Y0590R090 S1      
327GND              J32   -284        A01X+009902Y+124207X0205Y0590R090 S1      
327GND              J32   -281        A01X+009902Y+123203X0205Y0590R090 S1      
327GND              J32   -270        A01X+009902Y+119522X0205Y0590R090 S1      
327GND              J32   -273        A01X+009902Y+120526X0205Y0590R090 S1      
327GND              J33   -136        A01X+008546Y+122868X0205Y0590R090 S1      
327GND              J33   -139        A01X+008546Y+123872X0205Y0590R090 S1      
327GND              J33   -128        A01X+008546Y+120191X0205Y0590R090 S1      
327GND              J33   -125        A01X+008546Y+119187X0205Y0590R090 S1      
327GND              J33   -284        A01X+006932Y+124207X0205Y0590R090 S1      
327GND              J33   -281        A01X+006932Y+123203X0205Y0590R090 S1      
327GND              J33   -270        A01X+006932Y+119522X0205Y0590R090 S1      
327GND              J33   -273        A01X+006932Y+120526X0205Y0590R090 S1      
327GND              J28   -155        A01X+015842Y+079030X0205Y0590R090 S1      
327GND              J30   -10         A01X+014487Y+078695X0205Y0590R090 S1      
327GND              J30   -155        A01X+012872Y+079030X0205Y0590R090 S1      
327GND              J32   -10         A01X+011517Y+078695X0205Y0590R090 S1      
327GND              J28   -166        A01X+015842Y+082711X0205Y0590R090 S1      
327GND              J28   -169        A01X+015842Y+083715X0205Y0590R090 S1      
327GND              J28   -158        A01X+015842Y+080034X0205Y0590R090 S1      
327GND              J30   -21         A01X+014487Y+082376X0205Y0590R090 S1      
327GND              J30   -24         A01X+014487Y+083380X0205Y0590R090 S1      
327GND              J30   -13         A01X+014487Y+079699X0205Y0590R090 S1      
327GND              J30   -169        A01X+012872Y+083715X0205Y0590R090 S1      
327GND              J30   -166        A01X+012872Y+082711X0205Y0590R090 S1      
327GND              J30   -158        A01X+012872Y+080034X0205Y0590R090 S1      
327GND              J32   -21         A01X+011517Y+082376X0205Y0590R090 S1      
327GND              J32   -24         A01X+011517Y+083380X0205Y0590R090 S1      
327GND              J32   -13         A01X+011517Y+079699X0205Y0590R090 S1      
327GND              J28   -188        A01X+015842Y+090073X0205Y0590R090 S1      
327GND              J28   -180        A01X+015842Y+087396X0205Y0590R090 S1      
327GND              J28   -177        A01X+015842Y+086392X0205Y0590R090 S1      
327GND              J30   -43         A01X+014487Y+089738X0205Y0590R090 S1      
327GND              J30   -32         A01X+014487Y+086057X0205Y0590R090 S1      
327GND              J30   -35         A01X+014487Y+087061X0205Y0590R090 S1      
327GND              J30   -188        A01X+012872Y+090073X0205Y0590R090 S1      
327GND              J30   -180        A01X+012872Y+087396X0205Y0590R090 S1      
327GND              J30   -177        A01X+012872Y+086392X0205Y0590R090 S1      
327GND              J32   -43         A01X+011517Y+089738X0205Y0590R090 S1      
327GND              J32   -32         A01X+011517Y+086057X0205Y0590R090 S1      
327GND              J32   -35         A01X+011517Y+087061X0205Y0590R090 S1      
327GND              J28   -199        A01X+015842Y+093754X0205Y0590R090 S1      
327GND              J28   -202        A01X+015842Y+094758X0205Y0590R090 S1      
327GND              J28   -191        A01X+015842Y+091077X0205Y0590R090 S1      
327GND              J30   -57         A01X+014487Y+094423X0205Y0590R090 S1      
327GND              J30   -54         A01X+014487Y+093419X0205Y0590R090 S1      
327GND              J30   -46         A01X+014487Y+090742X0205Y0590R090 S1      
327GND              J30   -199        A01X+012872Y+093754X0205Y0590R090 S1      
327GND              J30   -202        A01X+012872Y+094758X0205Y0590R090 S1      
327GND              J30   -191        A01X+012872Y+091077X0205Y0590R090 S1      
327GND              J32   -57         A01X+011517Y+094423X0205Y0590R090 S1      
327GND              J32   -54         A01X+011517Y+093419X0205Y0590R090 S1      
327GND              J32   -46         A01X+011517Y+090742X0205Y0590R090 S1      
327GND              J28   -248        A01X+015842Y+112160X0205Y0590R090 S1      
327GND              J28   -237        A01X+015842Y+108478X0205Y0590R090 S1      
327GND              J28   -240        A01X+015842Y+109482X0205Y0590R090 S1      
327GND              J30   -106        A01X+014487Y+112829X0205Y0590R090 S1      
327GND              J30   -103        A01X+014487Y+111825X0205Y0590R090 S1      
327GND              J30   -92         A01X+014487Y+108144X0205Y0590R090 S1      
327GND              J30   -95         A01X+014487Y+109148X0205Y0590R090 S1      
327GND              J30   -248        A01X+012872Y+112160X0205Y0590R090 S1      
327GND              J30   -237        A01X+012872Y+108478X0205Y0590R090 S1      
327GND              J30   -240        A01X+012872Y+109482X0205Y0590R090 S1      
327GND              J32   -106        A01X+011517Y+112829X0205Y0590R090 S1      
327GND              J32   -103        A01X+011517Y+111825X0205Y0590R090 S1      
327GND              J32   -92         A01X+011517Y+108144X0205Y0590R090 S1      
327GND              J32   -95         A01X+011517Y+109148X0205Y0590R090 S1      
327GND              J28   -262        A01X+015842Y+116845X0205Y0590R090 S1      
327GND              J28   -259        A01X+015842Y+115841X0205Y0590R090 S1      
327GND              J28   -251        A01X+015842Y+113164X0205Y0590R090 S1      
327GND              J30   -117        A01X+014487Y+116510X0205Y0590R090 S1      
327GND              J30   -114        A01X+014487Y+115506X0205Y0590R090 S1      
327GND              J30   -262        A01X+012872Y+116845X0205Y0590R090 S1      
327GND              J30   -259        A01X+012872Y+115841X0205Y0590R090 S1      
327GND              J30   -251        A01X+012872Y+113164X0205Y0590R090 S1      
327GND              J32   -117        A01X+011517Y+116510X0205Y0590R090 S1      
327GND              J32   -114        A01X+011517Y+115506X0205Y0590R090 S1      
327GND              J28   -284        A01X+015842Y+124207X0205Y0590R090 S1      
327GND              J28   -281        A01X+015842Y+123203X0205Y0590R090 S1      
327GND              J28   -270        A01X+015842Y+119522X0205Y0590R090 S1      
327GND              J28   -273        A01X+015842Y+120526X0205Y0590R090 S1      
327GND              J30   -136        A01X+014487Y+122868X0205Y0590R090 S1      
327GND              J30   -139        A01X+014487Y+123872X0205Y0590R090 S1      
327GND              J30   -128        A01X+014487Y+120191X0205Y0590R090 S1      
327GND              J30   -125        A01X+014487Y+119187X0205Y0590R090 S1      
327GND              J30   -284        A01X+012872Y+124207X0205Y0590R090 S1      
327GND              J30   -281        A01X+012872Y+123203X0205Y0590R090 S1      
327GND              J30   -270        A01X+012872Y+119522X0205Y0590R090 S1      
327GND              J30   -273        A01X+012872Y+120526X0205Y0590R090 S1      
327GND              J32   -136        A01X+011517Y+122868X0205Y0590R090 S1      
327GND              J32   -139        A01X+011517Y+123872X0205Y0590R090 S1      
327GND              J32   -128        A01X+011517Y+120191X0205Y0590R090 S1      
327GND              J32   -125        A01X+011517Y+119187X0205Y0590R090 S1      
327GND              J28   -10         A01X+017457Y+078695X0205Y0590R090 S1      
327GND              J28   -21         A01X+017457Y+082376X0205Y0590R090 S1      
327GND              J28   -24         A01X+017457Y+083380X0205Y0590R090 S1      
327GND              J28   -13         A01X+017457Y+079699X0205Y0590R090 S1      
327GND              J28   -43         A01X+017457Y+089738X0205Y0590R090 S1      
327GND              J28   -32         A01X+017457Y+086057X0205Y0590R090 S1      
327GND              J28   -35         A01X+017457Y+087061X0205Y0590R090 S1      
327GND              J28   -57         A01X+017457Y+094423X0205Y0590R090 S1      
327GND              J28   -54         A01X+017457Y+093419X0205Y0590R090 S1      
327GND              J28   -46         A01X+017457Y+090742X0205Y0590R090 S1      
327GND              J28   -106        A01X+017457Y+112829X0205Y0590R090 S1      
327GND              J28   -103        A01X+017457Y+111825X0205Y0590R090 S1      
327GND              J28   -92         A01X+017457Y+108144X0205Y0590R090 S1      
327GND              J28   -95         A01X+017457Y+109148X0205Y0590R090 S1      
327GND              J28   -117        A01X+017457Y+116510X0205Y0590R090 S1      
327GND              J28   -114        A01X+017457Y+115506X0205Y0590R090 S1      
327GND              J28   -136        A01X+017457Y+122868X0205Y0590R090 S1      
327GND              J28   -139        A01X+017457Y+123872X0205Y0590R090 S1      
327GND              J28   -128        A01X+017457Y+120191X0205Y0590R090 S1      
327GND              J28   -125        A01X+017457Y+119187X0205Y0590R090 S1      
327GND              J32   -151        A01X+009902Y+077691X0205Y0590R090 S1      
327GND              J32   -153        A01X+009902Y+078360X0205Y0590R090 S1      
327GND              J33   -8          A01X+008546Y+078026X0205Y0590R090 S1      
327GND              J33   -151        A01X+006932Y+077691X0205Y0590R090 S1      
327GND              J33   -153        A01X+006932Y+078360X0205Y0590R090 S1      
327GND              J32   -171        A01X+009902Y+084384X0205Y0590R090 S1      
327GND              J32   -162        A01X+009902Y+081372X0205Y0590R090 S1      
327GND              J32   -164        A01X+009902Y+082042X0205Y0590R090 S1      
327GND              J32   -160        A01X+009902Y+080703X0205Y0590R090 S1      
327GND              J33   -26         A01X+008546Y+084049X0205Y0590R090 S1      
327GND              J33   -28         A01X+008546Y+084719X0205Y0590R090 S1      
327GND              J33   -17         A01X+008546Y+081038X0205Y0590R090 S1      
327GND              J33   -19         A01X+008546Y+081707X0205Y0590R090 S1      
327GND              J33   -15         A01X+008546Y+080368X0205Y0590R090 S1      
327GND              J33   -171        A01X+006932Y+084384X0205Y0590R090 S1      
327GND              J33   -162        A01X+006932Y+081372X0205Y0590R090 S1      
327GND              J33   -164        A01X+006932Y+082042X0205Y0590R090 S1      
327GND              J33   -160        A01X+006932Y+080703X0205Y0590R090 S1      
327GND              J32   -184        A01X+009902Y+088734X0205Y0590R090 S1      
327GND              J32   -186        A01X+009902Y+089404X0205Y0590R090 S1      
327GND              J32   -182        A01X+009902Y+088065X0205Y0590R090 S1      
327GND              J32   -175        A01X+009902Y+085723X0205Y0590R090 S1      
327GND              J32   -173        A01X+009902Y+085053X0205Y0590R090 S1      
327GND              J33   -41         A01X+008546Y+089069X0205Y0590R090 S1      
327GND              J33   -37         A01X+008546Y+087730X0205Y0590R090 S1      
327GND              J33   -39         A01X+008546Y+088400X0205Y0590R090 S1      
327GND              J33   -30         A01X+008546Y+085388X0205Y0590R090 S1      
327GND              J33   -184        A01X+006932Y+088734X0205Y0590R090 S1      
327GND              J33   -186        A01X+006932Y+089404X0205Y0590R090 S1      
327GND              J33   -182        A01X+006932Y+088065X0205Y0590R090 S1      
327GND              J33   -175        A01X+006932Y+085723X0205Y0590R090 S1      
327GND              J33   -173        A01X+006932Y+085053X0205Y0590R090 S1      
327GND              J32   -204        A01X+009902Y+095427X0205Y0590R090 S1      
327GND              J32   -206        A01X+009902Y+096097X0205Y0590R090 S1      
327GND              J32   -195        A01X+009902Y+092416X0205Y0590R090 S1      
327GND              J32   -197        A01X+009902Y+093085X0205Y0590R090 S1      
327GND              J32   -193        A01X+009902Y+091746X0205Y0590R090 S1      
327GND              J33   -61         A01X+008546Y+095762X0205Y0590R090 S1      
327GND              J33   -59         A01X+008546Y+095093X0205Y0590R090 S1      
327GND              J33   -50         A01X+008546Y+092081X0205Y0590R090 S1      
327GND              J33   -52         A01X+008546Y+092750X0205Y0590R090 S1      
327GND              J33   -48         A01X+008546Y+091412X0205Y0590R090 S1      
327GND              J33   -204        A01X+006932Y+095427X0205Y0590R090 S1      
327GND              J33   -206        A01X+006932Y+096097X0205Y0590R090 S1      
327GND              J33   -195        A01X+006932Y+092416X0205Y0590R090 S1      
327GND              J33   -197        A01X+006932Y+093085X0205Y0590R090 S1      
327GND              J33   -193        A01X+006932Y+091746X0205Y0590R090 S1      
327GND              J32   -219        A01X+009902Y+100447X0205Y0590R090 S1      
327GND              J32   -214        A01X+009902Y+098774X0205Y0590R090 S1      
327GND              J32   -216        A01X+009902Y+099443X0205Y0590R090 S1      
327GND              J32   -208        A01X+009902Y+096766X0205Y0590R090 S1      
327GND              J32   -210        A01X+009902Y+097435X0205Y0590R090 S1      
327GND              J32   -212        A01X+009902Y+098104X0205Y0590R090 S1      
327GND              J33   -75         A01X+008546Y+100447X0205Y0590R090 S1      
327GND              J33   -69         A01X+008546Y+098439X0205Y0590R090 S1      
327GND              J33   -71         A01X+008546Y+099108X0205Y0590R090 S1      
327GND              J33   -73         A01X+008546Y+099778X0205Y0590R090 S1      
327GND              J33   -65         A01X+008546Y+097100X0205Y0590R090 S1      
327GND              J33   -67         A01X+008546Y+097770X0205Y0590R090 S1      
327GND              J33   -63         A01X+008546Y+096431X0205Y0590R090 S1      
327GND              J33   -219        A01X+006932Y+100447X0205Y0590R090 S1      
327GND              J33   -214        A01X+006932Y+098774X0205Y0590R090 S1      
327GND              J33   -216        A01X+006932Y+099443X0205Y0590R090 S1      
327GND              J33   -210        A01X+006932Y+097435X0205Y0590R090 S1      
327GND              J33   -212        A01X+006932Y+098104X0205Y0590R090 S1      
327GND              J33   -208        A01X+006932Y+096766X0205Y0590R090 S1      
327GND              J32   -233        A01X+009902Y+107140X0205Y0590R090 S1      
327GND              J32   -226        A01X+009902Y+104797X0205Y0590R090 S1      
327GND              J32   -228        A01X+009902Y+105467X0205Y0590R090 S1      
327GND              J32   -230        A01X+009902Y+106136X0205Y0590R090 S1      
327GND              J32   -222        A01X+009902Y+103459X0205Y0590R090 S1      
327GND              J32   -224        A01X+009902Y+104128X0205Y0590R090 S1      
327GND              J33   -88         A01X+008546Y+106805X0205Y0590R090 S1      
327GND              J33   -83         A01X+008546Y+105132X0205Y0590R090 S1      
327GND              J33   -85         A01X+008546Y+105801X0205Y0590R090 S1      
327GND              J33   -81         A01X+008546Y+104463X0205Y0590R090 S1      
327GND              J33   -77         A01X+008546Y+103124X0205Y0590R090 S1      
327GND              J33   -79         A01X+008546Y+103793X0205Y0590R090 S1      
327GND              J33   -233        A01X+006932Y+107140X0205Y0590R090 S1      
327GND              J33   -226        A01X+006932Y+104797X0205Y0590R090 S1      
327GND              J33   -228        A01X+006932Y+105467X0205Y0590R090 S1      
327GND              J33   -230        A01X+006932Y+106136X0205Y0590R090 S1      
327GND              J33   -222        A01X+006932Y+103459X0205Y0590R090 S1      
327GND              J33   -224        A01X+006932Y+104128X0205Y0590R090 S1      
327GND              J32   -246        A01X+009902Y+111490X0205Y0590R090 S1      
327GND              J32   -242        A01X+009902Y+110152X0205Y0590R090 S1      
327GND              J32   -244        A01X+009902Y+110821X0205Y0590R090 S1      
327GND              J32   -235        A01X+009902Y+107809X0205Y0590R090 S1      
327GND              J33   -101        A01X+008546Y+111156X0205Y0590R090 S1      
327GND              J33   -97         A01X+008546Y+109817X0205Y0590R090 S1      
327GND              J33   -99         A01X+008546Y+110486X0205Y0590R090 S1      
327GND              J33   -90         A01X+008546Y+107474X0205Y0590R090 S1      
327GND              J33   -246        A01X+006932Y+111490X0205Y0590R090 S1      
327GND              J33   -242        A01X+006932Y+110152X0205Y0590R090 S1      
327GND              J33   -244        A01X+006932Y+110821X0205Y0590R090 S1      
327GND              J33   -235        A01X+006932Y+107809X0205Y0590R090 S1      
327GND              J32   -264        A01X+009902Y+117514X0205Y0590R090 S1      
327GND              J32   -266        A01X+009902Y+118183X0205Y0590R090 S1      
327GND              J32   -255        A01X+009902Y+114502X0205Y0590R090 S1      
327GND              J32   -257        A01X+009902Y+115171X0205Y0590R090 S1      
327GND              J32   -253        A01X+009902Y+113833X0205Y0590R090 S1      
327GND              J33   -121        A01X+008546Y+117849X0205Y0590R090 S1      
327GND              J33   -123        A01X+008546Y+118518X0205Y0590R090 S1      
327GND              J33   -119        A01X+008546Y+117179X0205Y0590R090 S1      
327GND              J33   -112        A01X+008546Y+114837X0205Y0590R090 S1      
327GND              J33   -108        A01X+008546Y+113498X0205Y0590R090 S1      
327GND              J33   -110        A01X+008546Y+114168X0205Y0590R090 S1      
327GND              J33   -264        A01X+006932Y+117514X0205Y0590R090 S1      
327GND              J33   -266        A01X+006932Y+118183X0205Y0590R090 S1      
327GND              J33   -255        A01X+006932Y+114502X0205Y0590R090 S1      
327GND              J33   -257        A01X+006932Y+115171X0205Y0590R090 S1      
327GND              J33   -253        A01X+006932Y+113833X0205Y0590R090 S1      
327GND              J32   -279        A01X+009902Y+122534X0205Y0590R090 S1      
327GND              J32   -275        A01X+009902Y+121195X0205Y0590R090 S1      
327GND              J32   -277        A01X+009902Y+121864X0205Y0590R090 S1      
327GND              J32   -268        A01X+009902Y+118852X0205Y0590R090 S1      
327GND              J33   -132        A01X+008546Y+121530X0205Y0590R090 S1      
327GND              J33   -134        A01X+008546Y+122199X0205Y0590R090 S1      
327GND              J33   -130        A01X+008546Y+120860X0205Y0590R090 S1      
327GND              J33   -279        A01X+006932Y+122534X0205Y0590R090 S1      
327GND              J33   -275        A01X+006932Y+121195X0205Y0590R090 S1      
327GND              J33   -277        A01X+006932Y+121864X0205Y0590R090 S1      
327GND              J33   -268        A01X+006932Y+118852X0205Y0590R090 S1      
327GND              J32   -288        A01X+009902Y+125545X0205Y0590R090 S1      
327GND              J32   -286        A01X+009902Y+124876X0205Y0590R090 S1      
327GND              J33   -143        A01X+008546Y+125211X0205Y0590R090 S1      
327GND              J33   -141        A01X+008546Y+124542X0205Y0590R090 S1      
327GND              J33   -288        A01X+006932Y+125545X0205Y0590R090 S1      
327GND              J33   -286        A01X+006932Y+124876X0205Y0590R090 S1      
327GND              J30   -8          A01X+014487Y+078026X0205Y0590R090 S1      
327GND              J28   -151        A01X+015842Y+077691X0205Y0590R090 S1      
327GND              J28   -153        A01X+015842Y+078360X0205Y0590R090 S1      
327GND              J30   -151        A01X+012872Y+077691X0205Y0590R090 S1      
327GND              J30   -153        A01X+012872Y+078360X0205Y0590R090 S1      
327GND              J32   -8          A01X+011517Y+078026X0205Y0590R090 S1      
327GND              J30   -26         A01X+014487Y+084049X0205Y0590R090 S1      
327GND              J30   -28         A01X+014487Y+084719X0205Y0590R090 S1      
327GND              J28   -171        A01X+015842Y+084384X0205Y0590R090 S1      
327GND              J30   -17         A01X+014487Y+081038X0205Y0590R090 S1      
327GND              J30   -19         A01X+014487Y+081707X0205Y0590R090 S1      
327GND              J28   -162        A01X+015842Y+081372X0205Y0590R090 S1      
327GND              J28   -164        A01X+015842Y+082042X0205Y0590R090 S1      
327GND              J30   -15         A01X+014487Y+080368X0205Y0590R090 S1      
327GND              J28   -160        A01X+015842Y+080703X0205Y0590R090 S1      
327GND              J30   -171        A01X+012872Y+084384X0205Y0590R090 S1      
327GND              J30   -162        A01X+012872Y+081372X0205Y0590R090 S1      
327GND              J30   -164        A01X+012872Y+082042X0205Y0590R090 S1      
327GND              J30   -160        A01X+012872Y+080703X0205Y0590R090 S1      
327GND              J32   -26         A01X+011517Y+084049X0205Y0590R090 S1      
327GND              J32   -28         A01X+011517Y+084719X0205Y0590R090 S1      
327GND              J32   -17         A01X+011517Y+081038X0205Y0590R090 S1      
327GND              J32   -19         A01X+011517Y+081707X0205Y0590R090 S1      
327GND              J32   -15         A01X+011517Y+080368X0205Y0590R090 S1      
327GND              J30   -41         A01X+014487Y+089069X0205Y0590R090 S1      
327GND              J28   -184        A01X+015842Y+088734X0205Y0590R090 S1      
327GND              J28   -186        A01X+015842Y+089404X0205Y0590R090 S1      
327GND              J30   -37         A01X+014487Y+087730X0205Y0590R090 S1      
327GND              J30   -39         A01X+014487Y+088400X0205Y0590R090 S1      
327GND              J28   -182        A01X+015842Y+088065X0205Y0590R090 S1      
327GND              J28   -175        A01X+015842Y+085723X0205Y0590R090 S1      
327GND              J30   -30         A01X+014487Y+085388X0205Y0590R090 S1      
327GND              J28   -173        A01X+015842Y+085053X0205Y0590R090 S1      
327GND              J30   -184        A01X+012872Y+088734X0205Y0590R090 S1      
327GND              J30   -186        A01X+012872Y+089404X0205Y0590R090 S1      
327GND              J30   -182        A01X+012872Y+088065X0205Y0590R090 S1      
327GND              J30   -175        A01X+012872Y+085723X0205Y0590R090 S1      
327GND              J30   -173        A01X+012872Y+085053X0205Y0590R090 S1      
327GND              J32   -41         A01X+011517Y+089069X0205Y0590R090 S1      
327GND              J32   -37         A01X+011517Y+087730X0205Y0590R090 S1      
327GND              J32   -39         A01X+011517Y+088400X0205Y0590R090 S1      
327GND              J32   -30         A01X+011517Y+085388X0205Y0590R090 S1      
327GND              J30   -61         A01X+014487Y+095762X0205Y0590R090 S1      
327GND              J28   -204        A01X+015842Y+095427X0205Y0590R090 S1      
327GND              J28   -206        A01X+015842Y+096097X0205Y0590R090 S1      
327GND              J30   -59         A01X+014487Y+095093X0205Y0590R090 S1      
327GND              J30   -50         A01X+014487Y+092081X0205Y0590R090 S1      
327GND              J30   -52         A01X+014487Y+092750X0205Y0590R090 S1      
327GND              J28   -195        A01X+015842Y+092416X0205Y0590R090 S1      
327GND              J28   -197        A01X+015842Y+093085X0205Y0590R090 S1      
327GND              J30   -48         A01X+014487Y+091412X0205Y0590R090 S1      
327GND              J28   -193        A01X+015842Y+091746X0205Y0590R090 S1      
327GND              J30   -204        A01X+012872Y+095427X0205Y0590R090 S1      
327GND              J30   -206        A01X+012872Y+096097X0205Y0590R090 S1      
327GND              J30   -195        A01X+012872Y+092416X0205Y0590R090 S1      
327GND              J30   -197        A01X+012872Y+093085X0205Y0590R090 S1      
327GND              J30   -193        A01X+012872Y+091746X0205Y0590R090 S1      
327GND              J32   -61         A01X+011517Y+095762X0205Y0590R090 S1      
327GND              J32   -59         A01X+011517Y+095093X0205Y0590R090 S1      
327GND              J32   -50         A01X+011517Y+092081X0205Y0590R090 S1      
327GND              J32   -52         A01X+011517Y+092750X0205Y0590R090 S1      
327GND              J32   -48         A01X+011517Y+091412X0205Y0590R090 S1      
327GND              J30   -75         A01X+014487Y+100447X0205Y0590R090 S1      
327GND              J28   -219        A01X+015842Y+100447X0205Y0590R090 S1      
327GND              J30   -69         A01X+014487Y+098439X0205Y0590R090 S1      
327GND              J30   -71         A01X+014487Y+099108X0205Y0590R090 S1      
327GND              J30   -73         A01X+014487Y+099778X0205Y0590R090 S1      
327GND              J28   -214        A01X+015842Y+098774X0205Y0590R090 S1      
327GND              J28   -216        A01X+015842Y+099443X0205Y0590R090 S1      
327GND              J30   -65         A01X+014487Y+097100X0205Y0590R090 S1      
327GND              J30   -67         A01X+014487Y+097770X0205Y0590R090 S1      
327GND              J28   -208        A01X+015842Y+096766X0205Y0590R090 S1      
327GND              J28   -210        A01X+015842Y+097435X0205Y0590R090 S1      
327GND              J28   -212        A01X+015842Y+098104X0205Y0590R090 S1      
327GND              J30   -63         A01X+014487Y+096431X0205Y0590R090 S1      
327GND              J30   -219        A01X+012872Y+100447X0205Y0590R090 S1      
327GND              J30   -214        A01X+012872Y+098774X0205Y0590R090 S1      
327GND              J30   -216        A01X+012872Y+099443X0205Y0590R090 S1      
327GND              J30   -208        A01X+012872Y+096766X0205Y0590R090 S1      
327GND              J30   -210        A01X+012872Y+097435X0205Y0590R090 S1      
327GND              J30   -212        A01X+012872Y+098104X0205Y0590R090 S1      
327GND              J32   -75         A01X+011517Y+100447X0205Y0590R090 S1      
327GND              J32   -69         A01X+011517Y+098439X0205Y0590R090 S1      
327GND              J32   -71         A01X+011517Y+099108X0205Y0590R090 S1      
327GND              J32   -73         A01X+011517Y+099778X0205Y0590R090 S1      
327GND              J32   -65         A01X+011517Y+097100X0205Y0590R090 S1      
327GND              J32   -67         A01X+011517Y+097770X0205Y0590R090 S1      
327GND              J32   -63         A01X+011517Y+096431X0205Y0590R090 S1      
327GND              J30   -88         A01X+014487Y+106805X0205Y0590R090 S1      
327GND              J28   -233        A01X+015842Y+107140X0205Y0590R090 S1      
327GND              J30   -83         A01X+014487Y+105132X0205Y0590R090 S1      
327GND              J30   -85         A01X+014487Y+105801X0205Y0590R090 S1      
327GND              J28   -230        A01X+015842Y+106136X0205Y0590R090 S1      
327GND              J28   -226        A01X+015842Y+104797X0205Y0590R090 S1      
327GND              J28   -228        A01X+015842Y+105467X0205Y0590R090 S1      
327GND              J30   -77         A01X+014487Y+103124X0205Y0590R090 S1      
327GND              J30   -79         A01X+014487Y+103793X0205Y0590R090 S1      
327GND              J30   -81         A01X+014487Y+104463X0205Y0590R090 S1      
327GND              J28   -222        A01X+015842Y+103459X0205Y0590R090 S1      
327GND              J28   -224        A01X+015842Y+104128X0205Y0590R090 S1      
327GND              J30   -233        A01X+012872Y+107140X0205Y0590R090 S1      
327GND              J30   -226        A01X+012872Y+104797X0205Y0590R090 S1      
327GND              J30   -228        A01X+012872Y+105467X0205Y0590R090 S1      
327GND              J30   -230        A01X+012872Y+106136X0205Y0590R090 S1      
327GND              J30   -222        A01X+012872Y+103459X0205Y0590R090 S1      
327GND              J30   -224        A01X+012872Y+104128X0205Y0590R090 S1      
327GND              J32   -88         A01X+011517Y+106805X0205Y0590R090 S1      
327GND              J32   -83         A01X+011517Y+105132X0205Y0590R090 S1      
327GND              J32   -85         A01X+011517Y+105801X0205Y0590R090 S1      
327GND              J32   -77         A01X+011517Y+103124X0205Y0590R090 S1      
327GND              J32   -79         A01X+011517Y+103793X0205Y0590R090 S1      
327GND              J32   -81         A01X+011517Y+104463X0205Y0590R090 S1      
327GND              J30   -101        A01X+014487Y+111156X0205Y0590R090 S1      
327GND              J28   -246        A01X+015842Y+111490X0205Y0590R090 S1      
327GND              J30   -97         A01X+014487Y+109817X0205Y0590R090 S1      
327GND              J30   -99         A01X+014487Y+110486X0205Y0590R090 S1      
327GND              J28   -242        A01X+015842Y+110152X0205Y0590R090 S1      
327GND              J28   -244        A01X+015842Y+110821X0205Y0590R090 S1      
327GND              J30   -90         A01X+014487Y+107474X0205Y0590R090 S1      
327GND              J28   -235        A01X+015842Y+107809X0205Y0590R090 S1      
327GND              J30   -246        A01X+012872Y+111490X0205Y0590R090 S1      
327GND              J30   -242        A01X+012872Y+110152X0205Y0590R090 S1      
327GND              J30   -244        A01X+012872Y+110821X0205Y0590R090 S1      
327GND              J30   -235        A01X+012872Y+107809X0205Y0590R090 S1      
327GND              J32   -101        A01X+011517Y+111156X0205Y0590R090 S1      
327GND              J32   -97         A01X+011517Y+109817X0205Y0590R090 S1      
327GND              J32   -99         A01X+011517Y+110486X0205Y0590R090 S1      
327GND              J32   -90         A01X+011517Y+107474X0205Y0590R090 S1      
327GND              J30   -121        A01X+014487Y+117849X0205Y0590R090 S1      
327GND              J30   -123        A01X+014487Y+118518X0205Y0590R090 S1      
327GND              J28   -264        A01X+015842Y+117514X0205Y0590R090 S1      
327GND              J28   -266        A01X+015842Y+118183X0205Y0590R090 S1      
327GND              J30   -119        A01X+014487Y+117179X0205Y0590R090 S1      
327GND              J28   -255        A01X+015842Y+114502X0205Y0590R090 S1      
327GND              J28   -257        A01X+015842Y+115171X0205Y0590R090 S1      
327GND              J30   -112        A01X+014487Y+114837X0205Y0590R090 S1      
327GND              J30   -108        A01X+014487Y+113498X0205Y0590R090 S1      
327GND              J30   -110        A01X+014487Y+114168X0205Y0590R090 S1      
327GND              J28   -253        A01X+015842Y+113833X0205Y0590R090 S1      
327GND              J30   -264        A01X+012872Y+117514X0205Y0590R090 S1      
327GND              J30   -266        A01X+012872Y+118183X0205Y0590R090 S1      
327GND              J30   -255        A01X+012872Y+114502X0205Y0590R090 S1      
327GND              J30   -257        A01X+012872Y+115171X0205Y0590R090 S1      
327GND              J30   -253        A01X+012872Y+113833X0205Y0590R090 S1      
327GND              J32   -121        A01X+011517Y+117849X0205Y0590R090 S1      
327GND              J32   -123        A01X+011517Y+118518X0205Y0590R090 S1      
327GND              J32   -119        A01X+011517Y+117179X0205Y0590R090 S1      
327GND              J32   -112        A01X+011517Y+114837X0205Y0590R090 S1      
327GND              J32   -110        A01X+011517Y+114168X0205Y0590R090 S1      
327GND              J32   -108        A01X+011517Y+113498X0205Y0590R090 S1      
327GND              J28   -279        A01X+015842Y+122534X0205Y0590R090 S1      
327GND              J30   -132        A01X+014487Y+121530X0205Y0590R090 S1      
327GND              J30   -134        A01X+014487Y+122199X0205Y0590R090 S1      
327GND              J28   -275        A01X+015842Y+121195X0205Y0590R090 S1      
327GND              J28   -277        A01X+015842Y+121864X0205Y0590R090 S1      
327GND              J30   -130        A01X+014487Y+120860X0205Y0590R090 S1      
327GND              J28   -268        A01X+015842Y+118852X0205Y0590R090 S1      
327GND              J30   -279        A01X+012872Y+122534X0205Y0590R090 S1      
327GND              J30   -275        A01X+012872Y+121195X0205Y0590R090 S1      
327GND              J30   -277        A01X+012872Y+121864X0205Y0590R090 S1      
327GND              J30   -268        A01X+012872Y+118852X0205Y0590R090 S1      
327GND              J32   -132        A01X+011517Y+121530X0205Y0590R090 S1      
327GND              J32   -134        A01X+011517Y+122199X0205Y0590R090 S1      
327GND              J32   -130        A01X+011517Y+120860X0205Y0590R090 S1      
327GND              J28   -288        A01X+015842Y+125545X0205Y0590R090 S1      
327GND              J30   -143        A01X+014487Y+125211X0205Y0590R090 S1      
327GND              J28   -286        A01X+015842Y+124876X0205Y0590R090 S1      
327GND              J30   -141        A01X+014487Y+124542X0205Y0590R090 S1      
327GND              J30   -288        A01X+012872Y+125545X0205Y0590R090 S1      
327GND              J30   -286        A01X+012872Y+124876X0205Y0590R090 S1      
327GND              J32   -143        A01X+011517Y+125211X0205Y0590R090 S1      
327GND              J32   -141        A01X+011517Y+124542X0205Y0590R090 S1      
327GND              J28   -8          A01X+017457Y+078026X0205Y0590R090 S1      
327GND              J28   -26         A01X+017457Y+084049X0205Y0590R090 S1      
327GND              J28   -28         A01X+017457Y+084719X0205Y0590R090 S1      
327GND              J28   -17         A01X+017457Y+081038X0205Y0590R090 S1      
327GND              J28   -19         A01X+017457Y+081707X0205Y0590R090 S1      
327GND              J28   -15         A01X+017457Y+080368X0205Y0590R090 S1      
327GND              J28   -41         A01X+017457Y+089069X0205Y0590R090 S1      
327GND              J28   -37         A01X+017457Y+087730X0205Y0590R090 S1      
327GND              J28   -39         A01X+017457Y+088400X0205Y0590R090 S1      
327GND              J28   -30         A01X+017457Y+085388X0205Y0590R090 S1      
327GND              J28   -61         A01X+017457Y+095762X0205Y0590R090 S1      
327GND              J28   -59         A01X+017457Y+095093X0205Y0590R090 S1      
327GND              J28   -50         A01X+017457Y+092081X0205Y0590R090 S1      
327GND              J28   -52         A01X+017457Y+092750X0205Y0590R090 S1      
327GND              J28   -48         A01X+017457Y+091412X0205Y0590R090 S1      
327GND              J28   -75         A01X+017457Y+100447X0205Y0590R090 S1      
327GND              J28   -69         A01X+017457Y+098439X0205Y0590R090 S1      
327GND              J28   -71         A01X+017457Y+099108X0205Y0590R090 S1      
327GND              J28   -73         A01X+017457Y+099778X0205Y0590R090 S1      
327GND              J28   -65         A01X+017457Y+097100X0205Y0590R090 S1      
327GND              J28   -67         A01X+017457Y+097770X0205Y0590R090 S1      
327GND              J28   -63         A01X+017457Y+096431X0205Y0590R090 S1      
327GND              J28   -88         A01X+017457Y+106805X0205Y0590R090 S1      
327GND              J28   -83         A01X+017457Y+105132X0205Y0590R090 S1      
327GND              J28   -85         A01X+017457Y+105801X0205Y0590R090 S1      
327GND              J28   -77         A01X+017457Y+103124X0205Y0590R090 S1      
327GND              J28   -79         A01X+017457Y+103793X0205Y0590R090 S1      
327GND              J28   -81         A01X+017457Y+104463X0205Y0590R090 S1      
327GND              J28   -101        A01X+017457Y+111156X0205Y0590R090 S1      
327GND              J28   -97         A01X+017457Y+109817X0205Y0590R090 S1      
327GND              J28   -99         A01X+017457Y+110486X0205Y0590R090 S1      
327GND              J28   -90         A01X+017457Y+107474X0205Y0590R090 S1      
327GND              J28   -121        A01X+017457Y+117849X0205Y0590R090 S1      
327GND              J28   -123        A01X+017457Y+118518X0205Y0590R090 S1      
327GND              J28   -119        A01X+017457Y+117179X0205Y0590R090 S1      
327GND              J28   -112        A01X+017457Y+114837X0205Y0590R090 S1      
327GND              J28   -108        A01X+017457Y+113498X0205Y0590R090 S1      
327GND              J28   -110        A01X+017457Y+114168X0205Y0590R090 S1      
327GND              J28   -132        A01X+017457Y+121530X0205Y0590R090 S1      
327GND              J28   -134        A01X+017457Y+122199X0205Y0590R090 S1      
327GND              J28   -130        A01X+017457Y+120860X0205Y0590R090 S1      
327GND              J28   -143        A01X+017457Y+125211X0205Y0590R090 S1      
327GND              J28   -141        A01X+017457Y+124542X0205Y0590R090 S1      
317GND              J28   -G2  MD0480PA00X+016650Y+102140X0680Y1370R090 S3      
317GND              J30   -G2  MD0480PA00X+013680Y+102140X0680Y1370R090 S3      
317GND              J32   -G2  MD0480PA00X+010710Y+102140X0680Y1370R090 S3      
317GND              J33   -G2  MD0480PA00X+007739Y+102140X0680Y1370R090 S3      
317GND              VIA   -    MD0100PA00X+178359Y+075676X0190Y         S0      
327GND              C170  -2          A18X+178464Y+075850X0400Y0500R180 S2      
317GND              VIA   -    MD0100PA00X+177655Y+076026X0190Y         S0      
317GND              VIA   -    MD0100PA00X+177655Y+075676X0190Y         S0      
327GND              C171  -2   M      A18X+177550Y+075850X0400Y0500     S2      
317GND              VIA   -    MD0100PA00X+175389Y+075676X0190Y         S0      
327GND              C169  -2          A18X+175494Y+075850X0400Y0500R180 S2      
317GND              VIA   -    MD0100PA00X+174685Y+076026X0190Y         S0      
317GND              VIA   -    MD0100PA00X+174685Y+075676X0190Y         S0      
327GND              C167  -2   M      A18X+174580Y+075850X0400Y0500     S2      
317GND              VIA   -    MD0100PA00X+172419Y+075676X0190Y         S0      
327GND              C166  -2          A18X+172524Y+075850X0400Y0500R180 S2      
317GND              VIA   -    MD0100PA00X+171715Y+076026X0190Y         S0      
317GND              VIA   -    MD0100PA00X+171715Y+075676X0190Y         S0      
327GND              C165  -2   M      A18X+171610Y+075850X0400Y0500     S2      
317GND              VIA   -    MD0100PA00X+169449Y+075676X0190Y         S0      
327GND              C163  -2          A18X+169554Y+075850X0400Y0500R180 S2      
317GND              VIA   -    MD0100PA00X+168745Y+076026X0190Y         S0      
317GND              VIA   -    MD0100PA00X+168745Y+075676X0190Y         S0      
327GND              C162  -2   M      A18X+168640Y+075850X0400Y0500     S2      
317GND              VIA   -    MD0100PA00X+166479Y+075676X0190Y         S0      
327GND              C159  -2          A18X+166584Y+075850X0400Y0500R180 S2      
317GND              VIA   -    MD0100PA00X+165775Y+076026X0190Y         S0      
317GND              VIA   -    MD0100PA00X+165775Y+075676X0190Y         S0      
327GND              C161  -2   M      A18X+165670Y+075850X0400Y0500     S2      
317GND              VIA   -    MD0100PA00X+163509Y+075676X0190Y         S0      
327GND              C158  -2          A18X+163614Y+075850X0400Y0500R180 S2      
317GND              VIA   -    MD0100PA00X+162805Y+076026X0190Y         S0      
317GND              VIA   -    MD0100PA00X+162805Y+075676X0190Y         S0      
327GND              C157  -2   M      A18X+162700Y+075850X0400Y0500     S2      
317GND              VIA   -    MD0100PA00X+120556Y+075676X0190Y         S0      
327GND              C89   -2          A18X+120661Y+075850X0400Y0500R180 S2      
317GND              VIA   -    MD0100PA00X+119852Y+076026X0190Y         S0      
317GND              VIA   -    MD0100PA00X+119852Y+075676X0190Y         S0      
327GND              C142  -2   M      A18X+119747Y+075850X0400Y0500     S2      
317GND              VIA   -    MD0100PA00X+117586Y+075676X0190Y         S0      
327GND              C143  -2          A18X+117691Y+075850X0400Y0500R180 S2      
317GND              VIA   -    MD0100PA00X+116882Y+076026X0190Y         S0      
317GND              VIA   -    MD0100PA00X+116882Y+075676X0190Y         S0      
327GND              C145  -2   M      A18X+116777Y+075850X0400Y0500     S2      
317GND              VIA   -    MD0100PA00X+114616Y+075676X0190Y         S0      
327GND              C147  -2          A18X+114721Y+075850X0400Y0500R180 S2      
317GND              VIA   -    MD0100PA00X+113912Y+076026X0190Y         S0      
317GND              VIA   -    MD0100PA00X+113912Y+075676X0190Y         S0      
327GND              C146  -2   M      A18X+113807Y+075850X0400Y0500     S2      
317GND              VIA   -    MD0100PA00X+111646Y+075676X0190Y         S0      
327GND              C150  -2          A18X+111751Y+075850X0400Y0500R180 S2      
317GND              VIA   -    MD0100PA00X+110942Y+076026X0190Y         S0      
317GND              VIA   -    MD0100PA00X+110942Y+075676X0190Y         S0      
327GND              C149  -2   M      A18X+110837Y+075850X0400Y0500     S2      
317GND              VIA   -    MD0100PA00X+108676Y+075676X0190Y         S0      
327GND              C151  -2          A18X+108781Y+075850X0400Y0500R180 S2      
317GND              VIA   -    MD0100PA00X+107972Y+076026X0190Y         S0      
317GND              VIA   -    MD0100PA00X+107972Y+075676X0190Y         S0      
327GND              C153  -2   M      A18X+107867Y+075850X0400Y0500     S2      
317GND              VIA   -    MD0100PA00X+105706Y+075676X0190Y         S0      
327GND              C154  -2          A18X+105811Y+075850X0400Y0500R180 S2      
317GND              VIA   -    MD0100PA00X+105002Y+076026X0190Y         S0      
317GND              VIA   -    MD0100PA00X+105002Y+075676X0190Y         S0      
327GND              C155  -2   M      A18X+104896Y+075850X0400Y0500     S2      
317GND              VIA   -    MD0100PA00X+102549Y+075882X0200Y    R180 S0      
317GND              VIA   -    MD0100PA00X+100770Y+075901X0200Y         S0      
317GND              VIA   -    MD0100PA00X+087299Y+075345X0200Y    R090 S0      
317GND              VIA   -    MD0100PA00X+086941Y+075354X0200Y    R270 S0      
317GND              VIA   -    MD0100PA00X+080041Y+076027X0190Y         S0      
317GND              VIA   -    MD0100PA00X+080041Y+075677X0190Y         S0      
327GND              C549  -2   M      A18X+079936Y+075850X0400Y0500     S2      
317GND              VIA   -    MD0100PA00X+080745Y+075677X0190Y         S0      
327GND              C548  -2          A18X+080850Y+075850X0400Y0500R180 S2      
317GND              VIA   -    MD0100PA00X+077071Y+076027X0190Y         S0      
317GND              VIA   -    MD0100PA00X+077071Y+075677X0190Y         S0      
327GND              C547  -2   M      A18X+076966Y+075850X0400Y0500     S2      
317GND              VIA   -    MD0100PA00X+077790Y+075677X0190Y         S0      
327GND              C546  -2          A18X+077880Y+075850X0400Y0500R180 S2      
317GND              VIA   -    MD0100PA00X+074101Y+076027X0190Y         S0      
317GND              VIA   -    MD0100PA00X+074101Y+075677X0190Y         S0      
327GND              C537  -2   M      A18X+073996Y+075850X0400Y0500     S2      
317GND              VIA   -    MD0100PA00X+074805Y+075677X0190Y         S0      
327GND              C536  -2          A18X+074910Y+075850X0400Y0500R180 S2      
317GND              VIA   -    MD0100PA00X+071835Y+075677X0190Y         S0      
327GND              C535  -2          A18X+071940Y+075850X0400Y0500R180 S2      
317GND              VIA   -    MD0100PA00X+071131Y+076018X0190Y         S0      
317GND              VIA   -    MD0100PA00X+071131Y+075677X0190Y         S0      
327GND              C534  -2   M      A18X+071026Y+075850X0400Y0500     S2      
317GND              VIA   -    MD0100PA00X+068865Y+075677X0190Y         S0      
327GND              C533  -2          A18X+068970Y+075850X0400Y0500R180 S2      
317GND              VIA   -    MD0100PA00X+068167Y+076018X0190Y         S0      
317GND              VIA   -    MD0100PA00X+068160Y+075677X0190Y         S0      
327GND              C532  -2   M      A18X+068056Y+075850X0400Y0500     S2      
317GND              VIA   -    MD0100PA00X+065190Y+076027X0190Y         S0      
317GND              VIA   -    MD0100PA00X+065190Y+075677X0190Y         S0      
327GND              C531  -2   M      A18X+065086Y+075850X0400Y0500     S2      
317GND              VIA   -    MD0100PA00X+065895Y+075677X0190Y         S0      
327GND              C530  -2          A18X+066000Y+075850X0400Y0500R180 S2      
317GND              VIA   -    MD0100PA00X+022942Y+075677X0190Y         S0      
327GND              C174  -2          A18X+023047Y+075850X0400Y0500R180 S2      
317GND              VIA   -    MD0100PA00X+022238Y+075677X0190Y         S0      
317GND              VIA   -    MD0100PA00X+022238Y+076027X0190Y         S0      
327GND              C173  -2   M      A18X+022133Y+075850X0400Y0500     S2      
317GND              VIA   -    MD0100PA00X+019972Y+075677X0190Y         S0      
327GND              C177  -2          A18X+020077Y+075850X0400Y0500R180 S2      
317GND              VIA   -    MD0100PA00X+019268Y+075677X0190Y         S0      
317GND              VIA   -    MD0100PA00X+019268Y+076027X0190Y         S0      
327GND              C175  -2   M      A18X+019163Y+075850X0400Y0500     S2      
317GND              VIA   -    MD0100PA00X+017002Y+075677X0190Y         S0      
327GND              C179  -2          A18X+017107Y+075850X0400Y0500R180 S2      
317GND              VIA   -    MD0100PA00X+016298Y+075677X0190Y         S0      
317GND              VIA   -    MD0100PA00X+016298Y+076027X0190Y         S0      
327GND              C178  -2   M      A18X+016193Y+075850X0400Y0500     S2      
317GND              VIA   -    MD0100PA00X+013312Y+076027X0190Y         S0      
317GND              VIA   -    MD0100PA00X+013312Y+075677X0190Y         S0      
327GND              C182  -2   M      A18X+013222Y+075850X0400Y0500     S2      
317GND              VIA   -    MD0100PA00X+014032Y+075677X0190Y         S0      
327GND              C181  -2          A18X+014137Y+075850X0400Y0500R180 S2      
317GND              VIA   -    MD0100PA00X+010357Y+076027X0190Y         S0      
317GND              VIA   -    MD0100PA00X+010357Y+075677X0190Y         S0      
327GND              C509  -2   M      A18X+010252Y+075850X0400Y0500     S2      
317GND              VIA   -    MD0100PA00X+011062Y+075677X0190Y         S0      
327GND              C183  -2          A18X+011167Y+075850X0400Y0500R180 S2      
317GND              VIA   -    MD0100PA00X+007387Y+076027X0190Y         S0      
317GND              VIA   -    MD0100PA00X+007387Y+075677X0190Y         S0      
327GND              C518  -2   M      A18X+007282Y+075850X0400Y0500     S2      
317GND              VIA   -    MD0100PA00X+008092Y+075677X0190Y         S0      
327GND              C527  -2          A18X+008196Y+075850X0400Y0500R180 S2      
317GND              J67   -G1  MD0480PA00X+178007Y+073459X0680Y1370R090 S3      
317GND              J20   -G1  MD0480PA00X+175037Y+073459X0680Y1370R090 S3      
317GND              J68   -G1  MD0480PA00X+172067Y+073459X0680Y1370R090 S3      
317GND              J18   -G1  MD0480PA00X+169097Y+073459X0680Y1370R090 S3      
317GND              J1    -G1  MD0480PA00X+120204Y+073459X0680Y1370R090 S3      
317GND              J15   -G1  MD0480PA00X+117234Y+073459X0680Y1370R090 S3      
317GND              J17   -G1  MD0480PA00X+114264Y+073459X0680Y1370R090 S3      
317GND              J19   -G1  MD0480PA00X+111294Y+073459X0680Y1370R090 S3      
317GND              J21   -G1  MD0480PA00X+108324Y+073459X0680Y1370R090 S3      
317GND              J23   -G1  MD0480PA00X+105354Y+073459X0680Y1370R090 S3      
317GND              J37   -G1  MD0480PA00X+080393Y+073459X0680Y1370R090 S3      
317GND              J99   -G1  MD0480PA00X+077423Y+073459X0680Y1370R090 S3      
317GND              J29   -G1  MD0480PA00X+074453Y+073459X0680Y1370R090 S3      
317GND              J100  -G1  MD0480PA00X+071483Y+073459X0680Y1370R090 S3      
317GND              J27   -G1  MD0480PA00X+068513Y+073459X0680Y1370R090 S3      
317GND              J102  -G1  MD0480PA00X+065542Y+073459X0680Y1370R090 S3      
317GND              J28   -G1  MD0480PA00X+016650Y+073459X0680Y1370R090 S3      
317GND              J30   -G1  MD0480PA00X+013680Y+073459X0680Y1370R090 S3      
317GND              J32   -G1  MD0480PA00X+010710Y+073459X0680Y1370R090 S3      
317GND              J33   -G1  MD0480PA00X+007739Y+073459X0680Y1370R090 S3      
317GND              VIA   -    MD0100PA00X+003585Y+069482X0200Y    R180 S0      
317GND              VIA   -    MD0100PA00X+003585Y+069732X0200Y    R180 S0      
317GND              VIA   -    MD0100PA00X+170830Y+067972X0200Y    R180 S0      
317GND              VIA   -    MD0100PA00X+068808Y+067549X0200Y         S0      
317GND              VIA   -    MD0100PA00X+065468Y+067481X0200Y    R270 S0      
317GND              VIA   -    MD0100PA00X+064365Y+067478X0200Y    R270 S0      
317GND              VIA   -    MD0100PA00X+064013Y+067489X0200Y    R270 S0      
317GND              VIA   -    MD0100PA00X+063453Y+067489X0200Y    R270 S0      
327GND              U107  -5          A01X+015270Y+068040X0130Y0250R180 S1      
317GND              VIA   -    M      A01X+015270Y+068322X0200Y         S2      
017GND              VIA   -    M      A18X+015270Y+068322X0260Y         S2      
017GND                    -    MD0100PA00X+015270Y+068322                       
317GND              VIA   -    MD0100PA00X+003585Y+067551X0200Y    R180 S0      
317GND              VIA   -    MD0100PA00X+003585Y+068391X0200Y         S0      
317GND              VIA   -    MD0100PA00X+003585Y+068641X0200Y         S0      
317GND              VIA   -    MD0100PA00X+174550Y+066009X0200Y    R180 S0      
317GND              VIA   -    MD0100PA00X+174265Y+067149X0200Y         S0      
327GND              U106  -5          A01X+172633Y+066754X0130Y0250R180 S1      
317GND              VIA   -    MD0100PA00X+172633Y+067034X0200Y         S0      
317GND              VIA   -    MD0100PA00X+120718Y+066812X0200Y         S0      
317GND              VIA   -    MD0100PA00X+120144Y+066814X0200Y         S0      
317GND              VIA   -    MD0100PA00X+094637Y+066881X0200Y         S0      
317GND              VIA   -    M      A01X+093093Y+066479X0200Y         S2      
017GND              VIA   -    M      A18X+093093Y+066479X0260Y         S2      
017GND                    -    MD0100PA00X+093093Y+066479                       
317GND              VIA   -    MD0100PA00X+090657Y+066393X0200Y         S0      
317GND              VIA   -    MD0100PA00X+066006Y+067276X0200Y    R270 S0      
327GND              C1338 -2          A01X+014967Y+066836X0198Y0197R180 S1      
317GND              VIA   -    MD0100PA00X+014967Y+066550X0200Y         S0      
317GND              VIA   -    MD0100PA00X+003585Y+066448X0200Y         S0      
317GND              VIA   -    MD0100PA00X+003585Y+067301X0200Y    R180 S0      
317GND              VIA   -    MD0100PA00X+173308Y+065403X0200Y    R090 S0      
327GND              C1337 -2          A01X+172326Y+065624X0198Y0197R180 S1      
317GND              VIA   -    MD0100PA00X+172326Y+065364X0200Y         S0      
317GND              VIA   -    MD0100PA00X+171824Y+065210X0200Y         S0      
317GND              VIA   -    MD0100PA00X+072695Y+064867X0200Y         S0      
327GND              U108  -5          A01X+072344Y+064867X0130Y0250R090 S1      
317GND              VIA   -    MD0100PA00X+071232Y+065495X0200Y         S0      
327GND              C1339 -2          A01X+071170Y+065233X0198Y0197R090 S1      
317GND              VIA   -    MD0100PA00X+170610Y+064166X0200Y    R180 S0      
317GND              VIA   -    MD0100PA00X+170112Y+064166X0200Y    R180 S0      
317GND              VIA   -    MD0100PA00X+095110Y+063221X0200Y    R090 S0      
317GND              VIA   -    MD0100PA00X+093578Y+063405X0200Y    R180 S0      
327GND              U154  -4          A01X+093146Y+063375X0140Y0520R090 S1      
317GND              VIA   -    MD0100PA00X+086759Y+064242X0200Y         S0      
317GND              VIA   -    MD0100PA00X+072400Y+063679X0200Y         S0      
317GND              VIA   -    MD0100PA00X+071328Y+063690X0200Y         S0      
317GND              VIA   -    MD0100PA00X+113239Y+061566X0200Y         S0      
317GND              VIA   -    MD0100PA00X+095553Y+061402X0200Y         S0      
327GND              U14   -4          A01X+093146Y+061925X0140Y0520R090 S1      
317GND              VIA   -    MD0100PA00X+092713Y+061925X0200Y         S0      
317GND              VIA   -    MD0100PA00X+090673Y+061937X0200Y         S0      
327GND              C1523 -2          A01X+090660Y+062591X0198Y0197R180 S1      
317GND              VIA   -    MD0100PA00X+090660Y+062843X0200Y         S0      
317GND              VIA   -    MD0100PA00X+119573Y+059102X0200Y         S0      
317GND              VIA   -    MD0100PA00X+093939Y+060057X0200Y         S0      
327GND              U13   -4          A01X+093146Y+060475X0140Y0520R090 S1      
317GND              VIA   -    M      A01X+092698Y+060475X0200Y         S2      
017GND              VIA   -    M      A18X+092698Y+060475X0260Y         S2      
017GND                    -    MD0100PA00X+092698Y+060475                       
317GND              VIA   -    MD0100PA00X+089968Y+060104X0200Y         S0      
327GND              C1522 -2          A01X+090356Y+061136X0198Y0197R180 S1      
317GND              VIA   -    M      A01X+090356Y+061406X0200Y         S2      
017GND              VIA   -    M      A18X+090356Y+061406X0260Y         S2      
017GND                    -    MD0100PA00X+090356Y+061406                       
327GND              C42   -2          A01X+071191Y+060328X0198Y0197R270 S1      
317GND              VIA   -    MD0100PA00X+071504Y+060328X0200Y         S0      
327GND              U27   -4          A01X+069739Y+060606X0240Y0460     S1      
317GND              VIA   -    MD0100PA00X+069739Y+060169X0200Y         S0      
317GND              VIA   -    MD0100PA00X+118144Y+059287X0200Y         S0      
317GND              VIA   -    MD0100PA00X+119165Y+058957X0200Y         S0      
317GND              VIA   -    MD0100PA00X+118819Y+058926X0200Y         S0      
327GND              U105  -5          A01X+118819Y+058563X0130Y0250R180 S1      
327GND              U153  -4          A01X+093146Y+059025X0140Y0520R090 S1      
317GND              VIA   -    MD0100PA00X+093565Y+059075X0200Y         S0      
327GND              C1520 -2          A01X+094501Y+059042X0198Y0197R180 S1      
317GND              VIA   -    MD0100PA00X+094501Y+059361X0200Y         S0      
317GND              VIA   -    MD0100PA00X+090704Y+059017X0200Y         S0      
327GND              C1521 -2          A01X+090238Y+059745X0198Y0197R180 S1      
317GND              VIA   -    MD0100PA00X+090238Y+059466X0200Y         S0      
327GND              C43   -2          A01X+071184Y+058764X0198Y0197R270 S1      
317GND              VIA   -    MD0100PA00X+071458Y+058764X0200Y         S0      
317GND              VIA   -    MD0100PA00X+065105Y+058730X0200Y    R090 S0      
317GND              VIA   -    MD0100PA00X+064545Y+058730X0200Y    R090 S0      
317GND              VIA   -    MD0100PA00X+063948Y+058749X0200Y    R090 S0      
317GND              VIA   -    MD0100PA00X+063388Y+058749X0200Y    R090 S0      
317GND              VIA   -    MD0100PA00X+120840Y+059163X0200Y         S0      
317GND              VIA   -    MD0100PA00X+118512Y+057181X0200Y         S0      
327GND              C1336 -2          A01X+118512Y+057432X0198Y0197R180 S1      
317GND              VIA   -    MD0100PA00X+093430Y+057832X0200Y    R225 S0      
327GND              C1519 -2          A01X+090660Y+058241X0198Y0197R180 S1      
317GND              VIA   -    MD0100PA00X+090660Y+057970X0200Y         S0      
317GND              VIA   -    MD0100PA00X+071156Y+057508X0200Y         S0      
317GND              VIA   -    MD0100PA00X+070150Y+058056X0200Y         S0      
317GND              VIA   -    MD0100PA00X+069150Y+057508X0200Y         S0      
317GND              VIA   -    MD0100PA00X+103258Y+055993X0200Y         S0      
317GND              VIA   -    MD0100PA00X+102758Y+055893X0200Y         S0      
317GND              VIA   -    MD0100PA00X+102246Y+055893X0200Y         S0      
317GND              VIA   -    MD0100PA00X+101596Y+055443X0200Y         S0      
327GND              Q63   -S          A01X+091997Y+055455X0400Y0560R270 S1      
317GND              VIA   -    M      A01X+091458Y+056003X0200Y         S2      
017GND              VIA   -    M      A18X+091458Y+056003X0260Y         S2      
017GND                    -    MD0100PA00X+091458Y+056003                       
327GND              Q54   -S          A01X+082135Y+055761X0320Y0360R270 S1      
317GND              VIA   -    M      A01X+082378Y+056099X0200Y         S2      
017GND              VIA   -    M      A18X+082378Y+056099X0260Y         S2      
017GND                    -    MD0100PA00X+082378Y+056099                       
317GND              VIA   -    MD0100PA00X+177124Y+055722X0200Y         S0      
317GND              VIA   -    MD0100PA00X+104318Y+054703X0200Y         S0      
327GND              U54   -6          A01X+102752Y+054980X0070Y0280R180 S1      
317GND              VIA   -    MD0100PA00X+102752Y+055272X0200Y    R270 S0      
317GND              VIA   -    MD0100PA00X+101506Y+054757X0200Y         S0      
317GND              VIA   -    MD0100PA00X+101221Y+054757X0200Y         S0      
327GND              U158  -S          A01X+082987Y+054361X0320Y0360R090 S1      
317GND              VIA   -    M      A01X+082655Y+054361X0200Y         S2      
017GND              VIA   -    M      A18X+082655Y+054361X0260Y         S2      
017GND                    -    MD0100PA00X+082655Y+054361                       
317GND              VIA   -    MD0100PA00X+074064Y+054990X0200Y    R180 S0      
317GND              VIA   -    M      A01X+073826Y+055362X0200Y    R180 S2      
017GND              VIA   -    M      A18X+073826Y+055362X0260Y    R180 S2      
017GND                    -    MD0100PA00X+073826Y+055362                       
327GND              R19   -2          A01X+070450Y+055344X0198Y0197R090 S1      
317GND              VIA   -    M      A01X+070450Y+055586X0200Y         S2      
017GND              VIA   -    M      A18X+070450Y+055586X0260Y         S2      
017GND                    -    MD0100PA00X+070450Y+055586                       
327GND              R18   -2          A01X+070050Y+054344X0198Y0197R090 S1      
317GND              VIA   -    M      A01X+070050Y+054586X0200Y         S2      
017GND              VIA   -    M      A18X+070050Y+054586X0260Y         S2      
017GND                    -    MD0100PA00X+070050Y+054586                       
327GND              VIA   -           A18X+026349Y+068441X0260Y         S2      
327GND              VIA   -           A18X+024849Y+068441X0260Y         S2      
327GND              VIA   -           A18X+053049Y+062891X0260Y    R180 S2      
327GND              VIA   -           A18X+055049Y+062891X0260Y    R180 S2      
327GND              VIA   -           A18X+057049Y+062891X0260Y    R180 S2      
327GND              VIA   -           A18X+055049Y+060391X0260Y    R180 S2      
327GND              VIA   -           A18X+055049Y+058391X0260Y    R180 S2      
327GND              VIA   -           A18X+055049Y+056391X0260Y    R180 S2      
327GND              VIA   -           A18X+057049Y+060391X0260Y    R180 S2      
327GND              VIA   -           A18X+057049Y+058391X0260Y    R180 S2      
327GND              VIA   -           A18X+057049Y+056391X0260Y    R180 S2      
327GND              VIA   -           A18X+022599Y+070691X0260Y         S2      
327GND              VIA   -           A18X+021849Y+069941X0260Y         S2      
327GND              VIA   -           A18X+022599Y+069191X0260Y         S2      
327GND              VIA   -           A18X+021099Y+069191X0260Y         S2      
327GND              VIA   -           A18X+021849Y+068441X0260Y         S2      
327GND              VIA   -           A18X+023349Y+068441X0260Y         S2      
327GND              PC285_-2          A01X+043366Y+068076X0198Y0197R270 S1      
327GND              PC255_-2          A01X+036762Y+069850X0198Y0197R270 S1      
317GND              VIA   -    MD0100PA00X+037009Y+069748X0200Y         S0      
327GND              PC293_-2          A01X+040477Y+069621X0198Y0197R090 S1      
317GND              VIA   -    MD0100PA00X+040477Y+069867X0200Y         S0      
327GND              PC284_-2          A01X+040066Y+069856X0198Y0197R270 S1      
317GND              VIA   -    MD0100PA00X+040188Y+069622X0200Y         S0      
327GND              PC290_-2          A01X+037172Y+070194X0198Y0197R180 S1      
317GND              VIA   -    MD0100PA00X+037172Y+069945X0200Y         S0      
327GND              PC254_-2          A01X+033456Y+069876X0198Y0197R270 S1      
317GND              VIA   -    MD0100PA00X+033703Y+069775X0200Y         S0      
327GND              PC261_-2          A01X+033866Y+070220X0198Y0197R180 S1      
317GND              VIA   -    MD0100PA00X+033866Y+069966X0200Y         S0      
317GND              VIA   -    MD0100PA00X+040246Y+072262X0193Y    R180 S0      
317GND              VIA   -    MD0100PA00X+039518Y+072379X0193Y    R180 S0      
317GND              VIA   -    MD0100PA00X+039258Y+072379X0193Y    R180 S0      
317GND              VIA   -    MD0100PA00X+039518Y+072690X0193Y    R180 S0      
317GND              VIA   -    MD0100PA00X+039258Y+072690X0193Y    R180 S0      
317GND              VIA   -    MD0100PA00X+038244Y+072688X0193Y    R180 S0      
317GND              VIA   -    MD0100PA00X+038998Y+072379X0193Y    R180 S0      
317GND              VIA   -    MD0100PA00X+038998Y+072690X0193Y    R180 S0      
317GND              VIA   -    MD0100PA00X+038488Y+072690X0193Y    R180 S0      
317GND              VIA   -    MD0100PA00X+038738Y+072690X0193Y    R180 S0      
317GND              VIA   -    MD0100PA00X+038180Y+072375X0193Y    R180 S0      
317GND              VIA   -    MD0100PA00X+036956Y+072262X0193Y    R180 S0      
317GND              VIA   -    MD0100PA00X+037742Y+072694X0200Y    R180 S0      
317GND              VIA   -    MD0100PA00X+037876Y+073204X0200Y    R180 S0      
317GND              VIA   -    MD0100PA00X+037616Y+073204X0200Y    R180 S0      
317GND              VIA   -    MD0100PA00X+037876Y+072944X0200Y    R180 S0      
317GND              VIA   -    MD0100PA00X+037616Y+072944X0200Y    R180 S0      
317GND              VIA   -    MD0100PA00X+036474Y+072372X0193Y    R180 S0      
317GND              VIA   -    MD0100PA00X+035954Y+072372X0193Y    R180 S0      
317GND              VIA   -    MD0100PA00X+036214Y+072372X0193Y    R180 S0      
317GND              VIA   -    MD0100PA00X+035694Y+072372X0193Y    R180 S0      
317GND              VIA   -    MD0100PA00X+036474Y+072683X0193Y    R180 S0      
317GND              VIA   -    MD0100PA00X+035954Y+072683X0193Y    R180 S0      
317GND              VIA   -    MD0100PA00X+036214Y+072683X0193Y    R180 S0      
317GND              VIA   -    MD0100PA00X+035694Y+072683X0193Y    R180 S0      
317GND              VIA   -    MD0100PA00X+035434Y+072683X0193Y    R180 S0      
317GND              VIA   -    MD0100PA00X+035184Y+072683X0193Y    R180 S0      
317GND              VIA   -    MD0100PA00X+033646Y+072282X0193Y    R180 S0      
317GND              VIA   -    MD0100PA00X+034940Y+072682X0193Y    R180 S0      
317GND              VIA   -    MD0100PA00X+034438Y+072687X0200Y    R180 S0      
317GND              VIA   -    MD0100PA00X+034312Y+073197X0200Y    R180 S0      
317GND              VIA   -    MD0100PA00X+034572Y+073197X0200Y    R180 S0      
317GND              VIA   -    MD0100PA00X+034312Y+072937X0200Y    R180 S0      
317GND              VIA   -    MD0100PA00X+034572Y+072937X0200Y    R180 S0      
317GND              VIA   -    MD0100PA00X+034845Y+072378X0193Y    R180 S0      
317GND              VIA   -    MD0100PA00X+033168Y+072399X0193Y    R180 S0      
317GND              VIA   -    MD0100PA00X+032908Y+072399X0193Y    R180 S0      
317GND              VIA   -    MD0100PA00X+032648Y+072399X0193Y    R180 S0      
317GND              VIA   -    MD0100PA00X+032388Y+072399X0193Y    R180 S0      
317GND              VIA   -    MD0100PA00X+033168Y+072710X0193Y    R180 S0      
317GND              VIA   -    MD0100PA00X+032908Y+072710X0193Y    R180 S0      
317GND              VIA   -    MD0100PA00X+032648Y+072710X0193Y    R180 S0      
317GND              VIA   -    MD0100PA00X+032388Y+072710X0193Y    R180 S0      
317GND              VIA   -    MD0100PA00X+031878Y+072710X0193Y    R180 S0      
317GND              VIA   -    MD0100PA00X+031132Y+072714X0200Y    R180 S0      
317GND              VIA   -    MD0100PA00X+031634Y+072708X0193Y    R180 S0      
317GND              VIA   -    MD0100PA00X+031006Y+073224X0200Y    R180 S0      
317GND              VIA   -    MD0100PA00X+031006Y+072964X0200Y    R180 S0      
317GND              VIA   -    MD0100PA00X+031266Y+073224X0200Y    R180 S0      
317GND              VIA   -    MD0100PA00X+031266Y+072964X0200Y    R180 S0      
317GND              VIA   -    MD0100PA00X+032128Y+072710X0193Y    R180 S0      
317GND              VIA   -    MD0100PA00X+031591Y+072400X0193Y    R180 S0      
317GND              VIA   -    MD0100PA00X+029899Y+072635X0200Y         S0      
317GND              VIA   -    MD0100PA00X+030512Y+072635X0200Y         S0      
317GND              VIA   -    MD0100PA00X+027917Y+072499X0200Y    R180 S0      
317GND              VIA   -    MD0100PA00X+027706Y+072265X0200Y    R180 S0      
317GND              VIA   -    MD0100PA00X+039778Y+072379X0193Y    R180 S0      
317GND              VIA   -    MD0100PA00X+039778Y+072690X0193Y    R180 S0      
317GND              VIA   -    MD0100PA00X+031006Y+073484X0200Y    R180 S0      
317GND              VIA   -    MD0100PA00X+031266Y+073484X0200Y    R180 S0      
317GND              VIA   -    MD0100PA00X+031326Y+074628X0200Y    R180 S0      
317GND              VIA   -    MD0100PA00X+034312Y+073457X0200Y    R180 S0      
317GND              VIA   -    MD0100PA00X+034572Y+073457X0200Y    R180 S0      
317GND              VIA   -    MD0100PA00X+034962Y+074627X0200Y    R180 S0      
317GND              VIA   -    MD0100PA00X+034242Y+074627X0200Y    R180 S0      
317GND              VIA   -    MD0100PA00X+033982Y+074627X0200Y    R180 S0      
317GND              VIA   -    MD0100PA00X+036262Y+074627X0200Y    R180 S0      
317GND              VIA   -    MD0100PA00X+036002Y+074627X0200Y    R180 S0      
317GND              VIA   -    MD0100PA00X+035222Y+074627X0200Y    R180 S0      
317GND              VIA   -    MD0100PA00X+037876Y+073464X0200Y    R180 S0      
317GND              VIA   -    MD0100PA00X+037616Y+073464X0200Y    R180 S0      
317GND              VIA   -    MD0100PA00X+037082Y+074617X0200Y    R180 S0      
317GND              VIA   -    MD0100PA00X+037342Y+074617X0200Y    R180 S0      
317GND              VIA   -    MD0100PA00X+043901Y+074132X0200Y    R180 S0      
317GND              VIA   -    MD0100PA00X+043641Y+074132X0200Y    R180 S0      
317GND              VIA   -    MD0100PA00X+043901Y+074392X0200Y    R180 S0      
317GND              VIA   -    MD0100PA00X+043641Y+074392X0200Y    R180 S0      
317GND              VIA   -    MD0100PA00X+043901Y+073872X0200Y    R180 S0      
317GND              VIA   -    MD0100PA00X+043641Y+073872X0200Y    R180 S0      
317GND              VIA   -    MD0100PA00X+043681Y+073615X0200Y    R180 S0      
317GND              VIA   -    MD0100PA00X+043941Y+073615X0200Y    R180 S0      
317GND              VIA   -    MD0100PA00X+043681Y+073353X0200Y    R180 S0      
317GND              VIA   -    MD0100PA00X+043941Y+073353X0200Y    R180 S0      
327GND              PC303_-2          A18X+040915Y+073198X0400Y0500R270 S2      
327GND              PR522 -2          A01X+040453Y+072452X0198Y0197R270 S1      
327GND              PC275 -2          A18X+038715Y+073328X0950Y1110R090 S2      
327GND              PR486 -2          A01X+037149Y+072445X0198Y0197R270 S1      
327GND              PC276 -2          A18X+035666Y+073331X0950Y1110R090 S2      
327GND              PR485 -2          A01X+033843Y+072472X0198Y0197R270 S1      
327GND              PC277 -2          A18X+032695Y+073331X0950Y1110R090 S2      
327GND              PC280_-2          A18X+030218Y+073003X0400Y0500R270 S2      
327GND              PC281_-2          A18X+027462Y+072641X0400Y0500R270 S2      
327GND              PC302_-2          A18X+031205Y+074988X0400Y0500R270 S2      
327GND              PC283_-2          A18X+034115Y+074988X0400Y0500R270 S2      
327GND              PC282_-2          A18X+037155Y+074988X0400Y0500R270 S2      
327GND              PC304_-2          A18X+040128Y+074956X0400Y0500R270 S2      
327GND              PC305_-2          A18X+043785Y+074796X0400Y0500R270 S2      
317GND              VIA   -    MD0100PA00X+051301Y+061775X0193Y    R180 S0      
317GND              VIA   -    MD0100PA00X+051301Y+062071X0193Y    R180 S0      
317GND              VIA   -    MD0100PA00X+028306Y+070394X0193Y    R180 S0      
317GND              VIA   -    MD0100PA00X+028306Y+070098X0193Y    R180 S0      
317GND              VIA   -    MD0100PA00X+031591Y+072104X0193Y    R180 S0      
317GND              VIA   -    MD0100PA00X+034845Y+072083X0193Y    R180 S0      
317GND              VIA   -    MD0100PA00X+038180Y+072079X0193Y    R180 S0      
317GND              VIA   -    MD0100PA00X+041468Y+070610X0193Y    R180 S0      
317GND              VIA   -    MD0100PA00X+041468Y+070314X0193Y    R180 S0      
317GND              VIA   -    MD0100PA00X+044716Y+068137X0193Y    R180 S0      
317GND              VIA   -    MD0100PA00X+044716Y+067841X0193Y    R180 S0      
317GND              VIA   -    MD0100PA00X+047982Y+065495X0193Y    R180 S0      
317GND              VIA   -    MD0100PA00X+047982Y+065199X0193Y    R180 S0      
317GND              VIA   -    MD0100PA00X+052480Y+061404X0193Y    R180 S0      
317GND              VIA   -    MD0100PA00X+052238Y+061404X0193Y    R180 S0      
317GND              VIA   -    MD0100PA00X+049150Y+064814X0193Y    R180 S0      
317GND              VIA   -    MD0100PA00X+048908Y+064814X0193Y    R180 S0      
317GND              VIA   -    MD0100PA00X+045890Y+067464X0193Y    R180 S0      
317GND              VIA   -    MD0100PA00X+045648Y+067464X0193Y    R180 S0      
317GND              VIA   -    MD0100PA00X+042650Y+069924X0193Y    R180 S0      
317GND              VIA   -    MD0100PA00X+042408Y+069924X0193Y    R180 S0      
317GND              VIA   -    MD0100PA00X+039350Y+071704X0193Y    R180 S0      
317GND              VIA   -    MD0100PA00X+039108Y+071704X0193Y    R180 S0      
317GND              VIA   -    MD0100PA00X+036046Y+071697X0193Y    R180 S0      
317GND              VIA   -    MD0100PA00X+035804Y+071697X0193Y    R180 S0      
317GND              VIA   -    MD0100PA00X+032740Y+071724X0193Y    R180 S0      
317GND              VIA   -    MD0100PA00X+032498Y+071724X0193Y    R180 S0      
317GND              VIA   -    MD0100PA00X+029464Y+069709X0193Y    R180 S0      
317GND              VIA   -    MD0100PA00X+029220Y+069709X0193Y    R180 S0      
317GND              J26   -G1  MD0480PA00X+019620Y+073459X0680Y1370R090 S3      
317GND              VIA   -    MD0100PA00X+037660Y+057740X0200Y    R180 S0      
317GND              VIA   -    MD0100PA00X+037667Y+056238X0200Y    R180 S0      
317GND              VIA   -    MD0100PA00X+036917Y+056988X0200Y    R180 S0      
327GND              PC6004-2          A01X+036771Y+061744X0198Y0197     S1      
327GND              U40   -2          A01X+032838Y+055240X0140Y0440     S1      
327GND              R703  -2   M      A01X+032897Y+054552X0198Y0197     S1      
317GND              VIA   -    MD0100PA00X+032897Y+054803X0200Y    R180 S0      
317GND              VIA   -    MD0100PA00X+032897Y+054301X0200Y         S0      
317GND              H8027 -1   MD1470PA00X+052317Y+057817X2440Y         S3      
317GND              H43   -1   MD1470PA00X+042012Y+065601X2440Y         S3      
317GND              H8028 -1   MD1470PA00X+021542Y+065806X2440Y         S3      
327GND              R8153 -2          A18X+034558Y+058642X0198Y0197     S2      
327GND              C8246 -2   M      A18X+035358Y+057442X0198Y0197     S2      
327GND              C249  -2   M      A18X+035358Y+056242X0198Y0197     S2      
327GND              C248  -2          A18X+035358Y+055842X0198Y0197     S2      
317GND              PC272 -2   MD0400PA00X+032673Y+066324X0600Y    R180 S3      
317GND              PC273 -2   MD0400PA00X+036373Y+066324X0600Y    R180 S3      
327GND              PC61  -2          A01X+028924Y+060583X0400Y0500R270 S1      
327GND              PC150 -2          A01X+029614Y+060583X0400Y0500R270 S1      
327GND              PC152 -2          A01X+030994Y+060583X0400Y0500R270 S1      
327GND              PC269_-2          A18X+034422Y+072243X0400Y0500R090 S2      
327GND              PC328_-2          A18X+048325Y+063198X0400Y0500R270 S2      
327GND              PC327_-2          A18X+045055Y+065848X0400Y0500R270 S2      
327GND              PC350_-2          A18X+051701Y+061922X0400Y0500R090 S2      
327GND              PC351_-2          A18X+050901Y+061922X0400Y0500R090 S2      
327GND              PC352_-2          A18X+051635Y+059778X0400Y0500R270 S2      
327GND              PC353_-2          A18X+050211Y+061922X0400Y0500R090 S2      
327GND              PC265_-2          A18X+035260Y+072243X0400Y0500R090 S2      
327GND              PC267_-2          A18X+035260Y+070019X0400Y0500R270 S2      
327GND              PC264_-2          A18X+031865Y+070108X0400Y0500R270 S2      
327GND              PC266_-2          A18X+031991Y+072262X0400Y0500R090 S2      
327GND              PC268_-2          A18X+031191Y+072262X0400Y0500R090 S2      
327GND              PC295_-2          A18X+041805Y+068288X0400Y0500R270 S2      
327GND              PC297_-2          A18X+041071Y+070472X0400Y0500R090 S2      
327GND              PC294_-2          A18X+038525Y+070078X0400Y0500R270 S2      
327GND              PC296_-2          A18X+038581Y+072222X0400Y0500R090 S2      
327GND              PC299_-2          A18X+041871Y+070472X0400Y0500R090 S2      
327GND              PC298_-2          A18X+037781Y+072222X0400Y0500R090 S2      
327GND              PC129_-2          A18X+025355Y+064658X0400Y0500R270 S2      
327GND              PC130_-2          A18X+025431Y+066833X0400Y0500R090 S2      
327GND              PC311_-2          A18X+028704Y+070237X0400Y0500R090 S2      
327GND              PC312_-2          A18X+027904Y+070237X0400Y0500R090 S2      
327GND              PC132_-2          A18X+024631Y+066833X0400Y0500R090 S2      
327GND              PC313_-2          A18X+028618Y+068103X0400Y0500R270 S2      
327GND              PC330_-2          A18X+048381Y+065342X0400Y0500R090 S2      
327GND              PC329_-2          A18X+045121Y+067982X0400Y0500R090 S2      
327GND              PC331_-2          A18X+044311Y+067982X0400Y0500R090 S2      
327GND              PC332_-2          A18X+047581Y+065342X0400Y0500R090 S2      
327GND              PC335_-2          A18X+046891Y+065342X0400Y0500R090 S2      
327GND              PC334_-2          A18X+043625Y+067978X0400Y0500R090 S2      
327GND              PC60  -2          A01X+030304Y+060583X0400Y0500R270 S1      
317GND              J24   -G1  MD0480PA00X+022590Y+073459X0680Y1370R090 S3      
327GND              PR162 -2          A01X+023586Y+071160X0198Y0197     S1      
327GND              PC278 -2   M      A01X+023984Y+071217X0198Y0197R270 S1      
317GND              VIA   -    MD0100PA00X+023984Y+070972X0200Y    R180 S0      
327GND              PR195 -1          A01X+039362Y+069875X0198Y0197     S1      
317GND              VIA   -    MD0100PA00X+039103Y+069902X0200Y    R180 S0      
327GND              PR188 -1          A01X+036058Y+069868X0198Y0197     S1      
317GND              VIA   -    MD0100PA00X+035799Y+069895X0200Y    R180 S0      
327GND              PC260_-2          A01X+031722Y+069452X0198Y0197     S1      
327GND              PR187 -1          A01X+032752Y+069895X0198Y0197     S1      
317GND              VIA   -    MD0100PA00X+031966Y+069642X0200Y         S0      
317GND              VIA   -    MD0100PA00X+032493Y+069922X0200Y    R180 S0      
327GND              PC309_-2          A01X+028543Y+067415X0198Y0197     S1      
327GND              PC306_-2          A01X+030179Y+067862X0198Y0197R270 S1      
327GND              PR202 -1          A01X+029475Y+067880X0198Y0197     S1      
317GND              VIA   -    MD0100PA00X+028783Y+067415X0200Y         S0      
317GND              VIA   -    M      A01X+030430Y+067904X0200Y    R180 S2      
017GND              VIA   -    M      A18X+030430Y+067904X0260Y    R180 S2      
017GND                    -    MD0100PA00X+030430Y+067904                       
317GND              VIA   -    MD0100PA00X+029216Y+067907X0200Y    R180 S0      
317GND              VIA   -    MD0100PA00X+054011Y+065732X0200Y         S0      
327GND              PC338 -2   M      A01X+054011Y+065972X0198Y0197R270 S1      
327GND              PR164 -2          A01X+054416Y+065949X0198Y0197R180 S1      
327GND              PC124_-2          A01X+026906Y+064437X0198Y0197R270 S1      
327GND              PR423 -1          A01X+026202Y+064456X0198Y0197     S1      
327GND              PC127_-2          A01X+025120Y+064091X0198Y0197     S1      
317GND              VIA   -    M      A01X+027157Y+064480X0200Y    R180 S2      
017GND              VIA   -    M      A18X+027157Y+064480X0260Y    R180 S2      
017GND                    -    MD0100PA00X+027157Y+064480                       
317GND              VIA   -    MD0100PA00X+025943Y+064483X0200Y    R180 S0      
317GND              VIA   -    MD0100PA00X+025467Y+064214X0200Y         S0      
327GND              PC125 -2          A01X+027296Y+065300X0198Y0197R270 S1      
327GND              PC307 -2          A01X+030568Y+068725X0198Y0197R270 S1      
327GND              PC257 -2          A01X+037152Y+070713X0198Y0197R270 S1      
327GND              PC256 -2          A01X+033846Y+070740X0198Y0197R270 S1      
327GND              PC287 -2          A01X+043756Y+068940X0198Y0197R270 S1      
327GND              PR196 -1          A01X+042662Y+068095X0198Y0197     S1      
327GND              PC286 -2          A01X+040456Y+070720X0198Y0197R270 S1      
327GND              PC320 -2          A01X+050256Y+063830X0198Y0197R270 S1      
327GND              PC318_-2          A01X+049866Y+062966X0198Y0197R270 S1      
327GND              PR208 -1          A01X+049162Y+062985X0198Y0197     S1      
327GND              PC319 -2          A01X+046996Y+066480X0198Y0197R270 S1      
327GND              PC317_-2          A01X+046606Y+065616X0198Y0197R270 S1      
327GND              PR207 -1          A01X+045902Y+065635X0198Y0197     S1      
327GND              PC346 -2          A01X+053586Y+060420X0198Y0197R270 S1      
327GND              PL32  -3          A01X+042556Y+074279X0540Y1780R090 S1      
327GND              PR523 -2          A01X+043753Y+070672X0198Y0197R270 S1      
327GND              PL35  -3          A01X+045709Y+071817X0540Y1780R090 S1      
327GND              PU27  -2   M      A01X+039950Y+071208X0090Y0240R270 S1      
327GND              PU27  -5          A01X+039950Y+071739X0090Y0240R270 S1      
327GND              PU27  -7_9-M      A01X+039006Y+072379X0827Y2126R270 S1      
327GND              PU27  -40  M      A01X+039350Y+071424X0690Y0770R180 S1      
327GND              PC288_-2          A01X+040456Y+072085X0198Y0197R090 S1      
327GND              PU26  -2   M      A01X+036646Y+071201X0090Y0240R270 S1      
327GND              PU26  -5          A01X+036646Y+071733X0090Y0240R270 S1      
327GND              PU26  -40  M      A01X+036046Y+071418X0690Y0770R180 S1      
327GND              PC292_-2          A01X+037570Y+072054X0198Y0197R090 S1      
327GND              PC259_-2          A01X+037152Y+072078X0198Y0197R090 S1      
327GND              PU4   -2   M      A01X+033340Y+071228X0090Y0240R270 S1      
327GND              PU4   -5          A01X+033340Y+071759X0090Y0240R270 S1      
327GND              PU4   -7_9-M      A01X+032396Y+072399X0827Y2126R270 S1      
327GND              PU4   -40  M      A01X+032740Y+071444X0690Y0770R180 S1      
327GND              PU26  -7_9-M      A01X+035702Y+072372X0827Y2126R270 S1      
327GND              PC263_-2          A01X+034271Y+072039X0198Y0197R090 S1      
327GND              PC258_-2          A01X+033846Y+072105X0198Y0197R090 S1      
327GND              PR46  -2          A01X+030566Y+070457X0198Y0197R270 S1      
327GND              PC262_-2          A01X+030966Y+072041X0198Y0197R090 S1      
327GND              PR526 -2          A01X+050253Y+065562X0198Y0197R270 S1      
327GND              PU31  -5          A01X+049750Y+064849X0090Y0240R270 S1      
327GND              PU31  -7_9-M      A01X+048806Y+065489X0827Y2126R270 S1      
327GND              PC322_-2          A01X+050256Y+065195X0198Y0197R090 S1      
327GND              PR525 -2          A01X+046993Y+068212X0198Y0197R270 S1      
327GND              PU30  -2   M      A01X+046490Y+066968X0090Y0240R270 S1      
327GND              PU30  -5          A01X+046490Y+067499X0090Y0240R270 S1      
327GND              PC324_-2          A01X+047373Y+065161X0198Y0197R090 S1      
327GND              PC326_-2          A01X+046988Y+065161X0198Y0197R090 S1      
327GND              PC321_-2          A01X+046996Y+067845X0198Y0197R090 S1      
327GND              PC289_-2          A01X+043756Y+070305X0198Y0197R090 S1      
327GND              PC323_-2          A01X+044114Y+067799X0198Y0197R090 S1      
327GND              PC325_-2          A01X+043731Y+067800X0198Y0197R090 S1      
327GND              PU28  -2   M      A01X+043250Y+069428X0090Y0240R270 S1      
327GND              PU28  -5          A01X+043250Y+069959X0090Y0240R270 S1      
327GND              PU28  -7_9-M      A01X+042306Y+070599X0827Y2126R270 S1      
327GND              PU28  -40  M      A01X+042650Y+069644X0690Y0770R180 S1      
327GND              PU30  -7_9-M      A01X+045546Y+068139X0827Y2126R270 S1      
327GND              PU30  -40  M      A01X+045890Y+067184X0690Y0770R180 S1      
327GND              PC291_-2          A01X+040874Y+070267X0198Y0197R090 S1      
327GND              PU29  -2   M      A01X+030063Y+069213X0090Y0240R270 S1      
327GND              PU29  -5          A01X+030063Y+069744X0090Y0240R270 S1      
327GND              PC308_-2          A01X+030568Y+070090X0198Y0197R090 S1      
327GND              PC310_-2          A01X+027686Y+070055X0198Y0197R090 S1      
327GND              PU29  -7_9-M      A01X+029118Y+070384X0827Y2126R270 S1      
327GND              PU29  -40  M      A01X+029463Y+069429X0690Y0770R180 S1      
327GND              PR524 -2          A01X+027293Y+067033X0198Y0197R270 S1      
327GND              PU24  -2   M      A01X+026790Y+065789X0090Y0240R270 S1      
327GND              PU24  -5          A01X+026790Y+066320X0090Y0240R270 S1      
327GND              PU24  -7_9-M      A01X+025846Y+066960X0827Y2126R270 S1      
327GND              PU24  -40  M      A01X+026190Y+066005X0690Y0770R180 S1      
327GND              PC126_-2          A01X+027296Y+066666X0198Y0197R090 S1      
327GND              PC128_-2          A01X+024412Y+066631X0198Y0197R090 S1      
327GND              PL27  -1          A01X+022796Y+068316X0790Y1660R090 S1      
327GND              PL34  -1          A01X+055379Y+062246X0790Y1660R090 S1      
327GND              PR511 -2          A01X+053583Y+062152X0198Y0197R270 S1      
327GND              PU32  -2   M      A01X+053080Y+060908X0090Y0240R270 S1      
327GND              PU32  -5          A01X+053080Y+061439X0090Y0240R270 S1      
327GND              PU32  -40  M      A01X+052480Y+061124X0690Y0770R180 S1      
327GND              PC347_-2          A01X+053586Y+061785X0198Y0197R090 S1      
327GND              PU31  -2   M      A01X+049750Y+064318X0090Y0240R270 S1      
327GND              PU31  -40  M      A01X+049150Y+064534X0690Y0770R180 S1      
327GND              PC348_-2          A01X+050300Y+061749X0198Y0197R090 S1      
327GND              PU32  -7_9-M      A01X+052136Y+062079X0827Y2126R270 S1      
327GND              PC349_-2          A01X+050696Y+061750X0198Y0197R090 S1      
327GND              PC341_-2          A18X+044335Y+070595X0400Y0500R270 S2      
327GND              PC105 -2          A18X+042295Y+071538X0950Y1110R090 S2      
327GND              PC279 -2          A18X+028838Y+071316X0950Y1110R090 S2      
327GND              PR339 -2          A18X+054465Y+064786X0198Y0197R090 S2      
327GND              PC340 -2          A18X+050461Y+066429X0950Y1110R090 S2      
327GND              PC337 -2          A18X+048475Y+066421X0950Y1110R090 S2      
327GND              PC344_-2          A18X+047095Y+069338X0400Y0500R270 S2      
327GND              PC343 -2          A18X+045715Y+069078X0950Y1110R090 S2      
327GND              PC315_-2          A18X+026828Y+069473X0400Y0500R270 S2      
327GND              PC134_-2          A18X+024071Y+069485X0400Y0500R270 S2      
327GND              PC135_-2          A18X+025916Y+069473X0400Y0500R270 S2      
327GND              PC316_-2          A18X+024955Y+069473X0400Y0500R270 S2      
327GND              PR337 -2          A18X+023483Y+069650X0198Y0197R090 S2      
327GND              PC342_-2          A18X+052493Y+064686X0400Y0500R270 S2      
327GND              PC354_-2          A18X+053885Y+064668X0400Y0500R270 S2      
327GND              PC355_-2          A18X+053195Y+064668X0400Y0500R270 S2      
327GND              PC339_-2          A18X+051793Y+064686X0400Y0500R270 S2      
317GND              VIA   -    M      A01X+050117Y+063009X0200Y    R180 S2      
017GND              VIA   -    M      A18X+050117Y+063009X0260Y    R180 S2      
017GND                    -    MD0100PA00X+050117Y+063009                       
317GND              VIA   -    MD0100PA00X+048903Y+063012X0200Y    R180 S0      
317GND              VIA   -    MD0100PA00X+045256Y+065284X0200Y    R180 S0      
317GND              VIA   -    MD0100PA00X+045643Y+065662X0200Y    R180 S0      
317GND              VIA   -    MD0100PA00X+042403Y+068122X0200Y    R180 S0      
317GND              VIA   -    MD0100PA00X+054799Y+061641X0200Y         S0      
317GND              VIA   -    MD0100PA00X+055399Y+061641X0200Y         S0      
317GND              VIA   -    MD0100PA00X+055099Y+061641X0200Y         S0      
317GND              VIA   -    MD0100PA00X+053386Y+061962X0193Y    R180 S0      
317GND              VIA   -    MD0100PA00X+052724Y+061404X0193Y    R180 S0      
317GND              VIA   -    MD0100PA00X+052724Y+060844X0193Y    R180 S0      
317GND              VIA   -    MD0100PA00X+052128Y+061784X0193Y    R180 S0      
317GND              VIA   -    MD0100PA00X+052388Y+061784X0193Y    R180 S0      
317GND              VIA   -    MD0100PA00X+052238Y+060844X0193Y    R180 S0      
317GND              VIA   -    MD0100PA00X+052480Y+060844X0193Y    R180 S0      
317GND              VIA   -    MD0100PA00X+055999Y+061641X0200Y         S0      
317GND              VIA   -    MD0100PA00X+055699Y+061641X0200Y         S0      
317GND              VIA   -    MD0100PA00X+022149Y+067691X0200Y         S0      
317GND              VIA   -    M      A01X+027086Y+066852X0200Y    R180 S2      
017GND              VIA   -    M      A18X+027086Y+066852X0260Y    R180 S2      
017GND                    -    MD0100PA00X+027086Y+066852                       
317GND              VIA   -    MD0100PA00X+026098Y+067271X0193Y    R180 S0      
317GND              VIA   -    MD0100PA00X+026358Y+067271X0193Y    R180 S0      
317GND              VIA   -    MD0100PA00X+026618Y+067271X0193Y    R180 S0      
317GND              VIA   -    MD0100PA00X+026098Y+066960X0193Y    R180 S0      
317GND              VIA   -    MD0100PA00X+026098Y+066664X0193Y    R180 S0      
317GND              VIA   -    MD0100PA00X+026618Y+066960X0193Y    R180 S0      
317GND              VIA   -    MD0100PA00X+026358Y+066960X0193Y    R180 S0      
317GND              VIA   -    MD0100PA00X+026434Y+066284X0193Y    R180 S0      
317GND              VIA   -    MD0100PA00X+025578Y+067271X0193Y    R180 S0      
317GND              VIA   -    MD0100PA00X+025838Y+067271X0193Y    R180 S0      
317GND              VIA   -    MD0100PA00X+025838Y+066960X0193Y    R180 S0      
317GND              VIA   -    MD0100PA00X+025838Y+066664X0193Y    R180 S0      
317GND              VIA   -    MD0100PA00X+025948Y+065724X0193Y    R180 S0      
317GND              VIA   -    MD0100PA00X+026190Y+065724X0193Y    R180 S0      
317GND              VIA   -    MD0100PA00X+026434Y+065724X0193Y    R180 S0      
317GND              VIA   -    MD0100PA00X+025328Y+067271X0193Y    R180 S0      
317GND              VIA   -    MD0100PA00X+025084Y+067269X0193Y    R180 S0      
317GND              VIA   -    MD0100PA00X+024716Y+067525X0200Y    R180 S0      
317GND              VIA   -    MD0100PA00X+024582Y+067275X0200Y    R180 S0      
317GND              VIA   -    MD0100PA00X+024456Y+067525X0200Y    R180 S0      
317GND              VIA   -    MD0100PA00X+023049Y+067691X0200Y         S0      
317GND              VIA   -    MD0100PA00X+022449Y+067691X0200Y         S0      
317GND              VIA   -    MD0100PA00X+022749Y+067691X0200Y         S0      
317GND              VIA   -    MD0100PA00X+049578Y+065800X0193Y    R180 S0      
317GND              VIA   -    MD0100PA00X+049578Y+065489X0193Y    R180 S0      
317GND              VIA   -    MD0100PA00X+050046Y+065372X0193Y    R180 S0      
317GND              VIA   -    MD0100PA00X+048538Y+065800X0193Y    R180 S0      
317GND              VIA   -    MD0100PA00X+048798Y+065800X0193Y    R180 S0      
317GND              VIA   -    MD0100PA00X+049058Y+065800X0193Y    R180 S0      
317GND              VIA   -    MD0100PA00X+049058Y+065489X0193Y    R180 S0      
317GND              VIA   -    MD0100PA00X+048798Y+065489X0193Y    R180 S0      
317GND              VIA   -    MD0100PA00X+049318Y+065800X0193Y    R180 S0      
317GND              VIA   -    MD0100PA00X+049318Y+065489X0193Y    R180 S0      
317GND              VIA   -    MD0100PA00X+049058Y+065194X0193Y    R180 S0      
317GND              VIA   -    MD0100PA00X+048798Y+065194X0193Y    R180 S0      
317GND              VIA   -    MD0100PA00X+049394Y+064814X0193Y    R180 S0      
317GND              VIA   -    MD0100PA00X+048044Y+065798X0193Y    R180 S0      
317GND              VIA   -    MD0100PA00X+048288Y+065800X0193Y    R180 S0      
317GND              VIA   -    MD0100PA00X+049150Y+064254X0193Y    R180 S0      
317GND              VIA   -    MD0100PA00X+048908Y+064254X0193Y    R180 S0      
317GND              VIA   -    MD0100PA00X+049394Y+064254X0193Y    R180 S0      
317GND              VIA   -    MD0100PA00X+047416Y+066574X0200Y    R180 S0      
317GND              VIA   -    MD0100PA00X+047676Y+066574X0200Y    R180 S0      
317GND              VIA   -    MD0100PA00X+047416Y+066314X0200Y    R180 S0      
317GND              VIA   -    MD0100PA00X+047676Y+066314X0200Y    R180 S0      
317GND              VIA   -    MD0100PA00X+046905Y+065706X0200Y    R180 S0      
317GND              VIA   -    MD0100PA00X+047416Y+066054X0200Y    R180 S0      
317GND              VIA   -    MD0100PA00X+047676Y+066054X0200Y    R180 S0      
317GND              VIA   -    MD0100PA00X+047542Y+065804X0200Y    R180 S0      
317GND              VIA   -    MD0100PA00X+046134Y+067464X0193Y    R180 S0      
317GND              VIA   -    MD0100PA00X+046134Y+066904X0193Y    R180 S0      
317GND              VIA   -    MD0100PA00X+045648Y+066904X0193Y    R180 S0      
317GND              VIA   -    MD0100PA00X+045890Y+066904X0193Y    R180 S0      
317GND              VIA   -    MD0100PA00X+052877Y+064314X0200Y    R180 S0      
317GND              VIA   -    MD0100PA00X+053427Y+064314X0200Y    R180 S0      
317GND              VIA   -    MD0100PA00X+052908Y+062390X0193Y    R180 S0      
317GND              VIA   -    MD0100PA00X+052908Y+062079X0193Y    R180 S0      
317GND              VIA   -    MD0100PA00X+052177Y+064314X0200Y    R180 S0      
317GND              VIA   -    MD0100PA00X+051477Y+064314X0200Y    R180 S0      
317GND              VIA   -    MD0100PA00X+051618Y+062390X0193Y    R180 S0      
317GND              VIA   -    MD0100PA00X+051868Y+062390X0193Y    R180 S0      
317GND              VIA   -    MD0100PA00X+052128Y+062390X0193Y    R180 S0      
317GND              VIA   -    MD0100PA00X+052388Y+062390X0193Y    R180 S0      
317GND              VIA   -    MD0100PA00X+052128Y+062079X0193Y    R180 S0      
317GND              VIA   -    MD0100PA00X+052388Y+062079X0193Y    R180 S0      
317GND              VIA   -    MD0100PA00X+051374Y+062388X0193Y    R180 S0      
317GND              VIA   -    MD0100PA00X+052648Y+062390X0193Y    R180 S0      
317GND              VIA   -    MD0100PA00X+052648Y+062079X0193Y    R180 S0      
317GND              VIA   -    MD0100PA00X+050746Y+063164X0200Y    R180 S0      
317GND              VIA   -    MD0100PA00X+051006Y+063164X0200Y    R180 S0      
317GND              VIA   -    MD0100PA00X+050746Y+062644X0200Y    R180 S0      
317GND              VIA   -    MD0100PA00X+050746Y+062904X0200Y    R180 S0      
317GND              VIA   -    MD0100PA00X+050872Y+062394X0200Y    R180 S0      
317GND              VIA   -    MD0100PA00X+051006Y+062644X0200Y    R180 S0      
317GND              VIA   -    MD0100PA00X+051006Y+062904X0200Y    R180 S0      
317GND              VIA   -    MD0100PA00X+027730Y+071469X0200Y    R180 S0      
317GND              VIA   -    MD0100PA00X+027730Y+071209X0200Y    R180 S0      
317GND              VIA   -    MD0100PA00X+027730Y+070949X0200Y    R180 S0      
317GND              VIA   -    MD0100PA00X+027260Y+069551X0200Y         S0      
317GND              VIA   -    MD0100PA00X+027260Y+069291X0200Y         S0      
317GND              VIA   -    MD0100PA00X+026384Y+069205X0200Y    R180 S0      
317GND              VIA   -    MD0100PA00X+024716Y+068045X0200Y    R180 S0      
317GND              VIA   -    MD0100PA00X+025445Y+069205X0200Y    R180 S0      
317GND              VIA   -    MD0100PA00X+024716Y+067785X0200Y    R180 S0      
317GND              VIA   -    MD0100PA00X+024456Y+068045X0200Y    R180 S0      
317GND              VIA   -    MD0100PA00X+023944Y+069102X0200Y    R180 S0      
317GND              VIA   -    MD0100PA00X+024254Y+069112X0200Y    R180 S0      
317GND              VIA   -    MD0100PA00X+024456Y+067785X0200Y    R180 S0      
317GND              VIA   -    M      A01X+023349Y+067691X0200Y         S2      
017GND              VIA   -    M      A18X+023349Y+067691X0260Y         S2      
017GND                    -    MD0100PA00X+023349Y+067691                       
317GND              VIA   -    MD0100PA00X+032740Y+071164X0193Y    R180 S0      
317GND              VIA   -    MD0100PA00X+032984Y+071724X0193Y    R180 S0      
317GND              VIA   -    MD0100PA00X+032388Y+072104X0193Y    R180 S0      
317GND              VIA   -    MD0100PA00X+032648Y+072104X0193Y    R180 S0      
317GND              VIA   -    MD0100PA00X+032498Y+071164X0193Y    R180 S0      
317GND              VIA   -    MD0100PA00X+032984Y+071164X0193Y    R180 S0      
317GND              VIA   -    MD0100PA00X+030366Y+070282X0193Y    R180 S0      
317GND              VIA   -    MD0100PA00X+029631Y+070695X0193Y    R180 S0      
317GND              VIA   -    MD0100PA00X+029631Y+070384X0193Y    R180 S0      
317GND              VIA   -    MD0100PA00X+029891Y+070695X0193Y    R180 S0      
317GND              VIA   -    MD0100PA00X+029891Y+070384X0193Y    R180 S0      
317GND              VIA   -    MD0100PA00X+029706Y+069709X0193Y    R180 S0      
317GND              VIA   -    MD0100PA00X+028851Y+070695X0193Y    R180 S0      
317GND              VIA   -    MD0100PA00X+029111Y+070695X0193Y    R180 S0      
317GND              VIA   -    MD0100PA00X+029111Y+070384X0193Y    R180 S0      
317GND              VIA   -    MD0100PA00X+029371Y+070695X0193Y    R180 S0      
317GND              VIA   -    MD0100PA00X+029371Y+070384X0193Y    R180 S0      
317GND              VIA   -    MD0100PA00X+029111Y+070088X0193Y    R180 S0      
317GND              VIA   -    MD0100PA00X+029371Y+070088X0193Y    R180 S0      
317GND              VIA   -    MD0100PA00X+029464Y+069149X0193Y    R180 S0      
317GND              VIA   -    MD0100PA00X+029706Y+069149X0193Y    R180 S0      
317GND              VIA   -    MD0100PA00X+029220Y+069149X0193Y    R180 S0      
317GND              VIA   -    MD0100PA00X+027990Y+071469X0200Y    R180 S0      
317GND              VIA   -    MD0100PA00X+027990Y+071209X0200Y    R180 S0      
317GND              VIA   -    MD0100PA00X+027854Y+070699X0200Y    R180 S0      
317GND              VIA   -    MD0100PA00X+028601Y+070695X0193Y    R180 S0      
317GND              VIA   -    MD0100PA00X+028356Y+070693X0193Y    R180 S0      
317GND              VIA   -    MD0100PA00X+027990Y+070949X0200Y    R180 S0      
317GND              VIA   -    MD0100PA00X+038998Y+072084X0193Y    R180 S0      
317GND              VIA   -    MD0100PA00X+039108Y+071144X0193Y    R180 S0      
317GND              VIA   -    MD0100PA00X+035694Y+072077X0193Y    R180 S0      
317GND              VIA   -    MD0100PA00X+035954Y+072077X0193Y    R180 S0      
317GND              VIA   -    MD0100PA00X+035804Y+071137X0193Y    R180 S0      
317GND              VIA   -    MD0100PA00X+036290Y+071137X0193Y    R180 S0      
317GND              VIA   -    MD0100PA00X+036046Y+071137X0193Y    R180 S0      
317GND              VIA   -    MD0100PA00X+036290Y+071697X0193Y    R180 S0      
317GND              VIA   -    MD0100PA00X+044784Y+068448X0193Y    R180 S0      
317GND              VIA   -    MD0100PA00X+044324Y+068464X0200Y    R180 S0      
317GND              VIA   -    MD0100PA00X+043613Y+068328X0200Y    R180 S0      
317GND              VIA   -    MD0100PA00X+044156Y+068704X0200Y    R180 S0      
317GND              VIA   -    MD0100PA00X+044156Y+068964X0200Y    R180 S0      
317GND              VIA   -    MD0100PA00X+044156Y+069224X0200Y    R180 S0      
317GND              VIA   -    MD0100PA00X+044416Y+068704X0200Y    R180 S0      
317GND              VIA   -    MD0100PA00X+044416Y+069224X0200Y    R180 S0      
317GND              VIA   -    MD0100PA00X+044416Y+068964X0200Y    R180 S0      
317GND              VIA   -    MD0100PA00X+044059Y+068452X0200Y    R180 S0      
317GND              VIA   -    MD0100PA00X+044399Y+071944X0200Y    R180 S0      
317GND              VIA   -    MD0100PA00X+044399Y+071684X0200Y    R180 S0      
317GND              VIA   -    MD0100PA00X+044659Y+071944X0200Y    R180 S0      
317GND              VIA   -    MD0100PA00X+044659Y+071684X0200Y    R180 S0      
317GND              VIA   -    MD0100PA00X+043546Y+070492X0193Y    R180 S0      
317GND              VIA   -    MD0100PA00X+044172Y+070245X0200Y    R180 S0      
317GND              VIA   -    MD0100PA00X+044432Y+070245X0200Y    R180 S0      
317GND              VIA   -    MD0100PA00X+042298Y+070599X0193Y    R180 S0      
317GND              VIA   -    MD0100PA00X+042558Y+070599X0193Y    R180 S0      
317GND              VIA   -    MD0100PA00X+042298Y+070304X0193Y    R180 S0      
317GND              VIA   -    MD0100PA00X+042558Y+070304X0193Y    R180 S0      
317GND              VIA   -    MD0100PA00X+042818Y+070599X0193Y    R180 S0      
317GND              VIA   -    MD0100PA00X+042038Y+070910X0193Y    R180 S0      
317GND              VIA   -    MD0100PA00X+042298Y+070910X0193Y    R180 S0      
317GND              VIA   -    MD0100PA00X+042558Y+070910X0193Y    R180 S0      
317GND              VIA   -    MD0100PA00X+042818Y+070910X0193Y    R180 S0      
317GND              VIA   -    MD0100PA00X+042894Y+069924X0193Y    R180 S0      
317GND              VIA   -    MD0100PA00X+041788Y+070910X0193Y    R180 S0      
317GND              VIA   -    MD0100PA00X+041544Y+070908X0193Y    R180 S0      
317GND              VIA   -    MD0100PA00X+043078Y+070599X0193Y    R180 S0      
317GND              VIA   -    MD0100PA00X+043078Y+070910X0193Y    R180 S0      
317GND              VIA   -    MD0100PA00X+042408Y+069364X0193Y    R180 S0      
317GND              VIA   -    MD0100PA00X+042894Y+069364X0193Y    R180 S0      
317GND              VIA   -    MD0100PA00X+042650Y+069364X0193Y    R180 S0      
317GND              VIA   -    MD0100PA00X+040916Y+071684X0200Y    R180 S0      
317GND              VIA   -    MD0100PA00X+040916Y+071424X0200Y    R180 S0      
317GND              VIA   -    MD0100PA00X+040916Y+071164X0200Y    R180 S0      
317GND              VIA   -    MD0100PA00X+041176Y+071684X0200Y    R180 S0      
317GND              VIA   -    MD0100PA00X+041176Y+071424X0200Y    R180 S0      
317GND              VIA   -    MD0100PA00X+041176Y+071164X0200Y    R180 S0      
317GND              VIA   -    MD0100PA00X+041042Y+070914X0200Y    R180 S0      
317GND              VIA   -    MD0100PA00X+039258Y+072084X0193Y    R180 S0      
317GND              VIA   -    MD0100PA00X+039350Y+071144X0193Y    R180 S0      
317GND              VIA   -    MD0100PA00X+039594Y+071144X0193Y    R180 S0      
317GND              VIA   -    MD0100PA00X+039594Y+071704X0193Y    R180 S0      
317GND              VIA   -    MD0100PA00X+046318Y+068139X0193Y    R180 S0      
317GND              VIA   -    MD0100PA00X+046318Y+068450X0193Y    R180 S0      
317GND              VIA   -    MD0100PA00X+046796Y+068032X0193Y    R180 S0      
317GND              VIA   -    MD0100PA00X+045538Y+068139X0193Y    R180 S0      
317GND              VIA   -    MD0100PA00X+045278Y+068450X0193Y    R180 S0      
317GND              VIA   -    MD0100PA00X+045538Y+068450X0193Y    R180 S0      
317GND              VIA   -    MD0100PA00X+045798Y+068139X0193Y    R180 S0      
317GND              VIA   -    MD0100PA00X+046058Y+068139X0193Y    R180 S0      
317GND              VIA   -    MD0100PA00X+045798Y+068450X0193Y    R180 S0      
317GND              VIA   -    MD0100PA00X+046058Y+068450X0193Y    R180 S0      
317GND              VIA   -    MD0100PA00X+045028Y+068450X0193Y    R180 S0      
317GND              VIA   -    MD0100PA00X+045538Y+067844X0193Y    R180 S0      
317GND              VIA   -    MD0100PA00X+045798Y+067844X0193Y    R180 S0      
327GND              PC345_-2          A01X+053196Y+059556X0198Y0197R270 S1      
327GND              PR214 -1          A01X+052492Y+059575X0198Y0197     S1      
317GND              VIA   -    MD0100PA00X+053447Y+059599X0200Y    R180 S0      
317GND              VIA   -    MD0100PA00X+052233Y+059602X0200Y    R180 S0      
317GND              VIA   -    MD0100PA00X+038544Y+059728X0200Y    R180 S0      
327GND              PR437 -2          A18X+038944Y+059488X0198Y0197R270 S2      
327GND              PR530 -2          A18X+038144Y+059488X0198Y0197R270 S2      
327GND              PR436 -2   M      A18X+038544Y+059488X0198Y0197R270 S2      
327GND              PR150 -2          A18X+034558Y+059134X0198Y0197     S2      
317GND              VIA   -    MD0100PA00X+034318Y+059134X0200Y    R180 S0      
317GND              VIA   -    MD0100PA00X+034318Y+058642X0200Y    R180 S0      
327GND              PC253 -2          A18X+040073Y+056942X0198Y0197R180 S2      
317GND              VIA   -    MD0100PA00X+040316Y+056942X0200Y    R180 S0      
327GND              PC247 -2          A18X+035358Y+057042X0198Y0197     S2      
317GND              VIA   -    MD0100PA00X+035116Y+057442X0200Y         S0      
327GND              PU3   -2          A01X+027028Y+059422X0070Y0320R180 S1      
327GND              PR8   -2   M      A01X+026940Y+058196X0198Y0197R270 S1      
327GND              PR398 -1   M      A01X+027307Y+058200X0198Y0197R090 S1      
327GND              C675  -2          A01X+029270Y+058288X0198Y0197R270 S1      
327GND              PC22  -2   M      A01X+026247Y+059508X0198Y0197R270 S1      
327GND              PU3   -11_1       A01X+027609Y+060436X0315Y1240R090 S1      
327GND              PC20  -2          A01X+027099Y+061117X0198Y0197     S1      
317GND              VIA   -    M      A01X+026510Y+059508X0200Y         S2      
017GND              VIA   -    M      A18X+026510Y+059508X0260Y         S2      
017GND                    -    MD0100PA00X+026510Y+059508                       
317GND              VIA   -    MD0100PA00X+026660Y+058658X0200Y    R180 S0      
317GND              VIA   -    MD0100PA00X+027420Y+057948X0200Y    R270 S0      
317GND              VIA   -    MD0100PA00X+029270Y+058028X0200Y    R180 S0      
317GND              VIA   -    MD0100PA00X+020375Y+059517X0200Y    R090 S0      
317GND              VIA   -    MD0100PA00X+020075Y+060327X0200Y    R090 S0      
317GND              VIA   -    MD0100PA00X+020375Y+060327X0200Y    R090 S0      
317GND              VIA   -    M      A01X+020075Y+059517X0200Y    R090 S2      
017GND              VIA   -    M      A18X+020075Y+059517X0260Y    R090 S2      
017GND                    -    MD0100PA00X+020075Y+059517                       
317GND              VIA   -    MD0100PA00X+020360Y+063238X0200Y         S0      
317GND              VIA   -    MD0100PA00X+020680Y+063238X0200Y         S0      
317GND              VIA   -    M      A01X+020040Y+063238X0200Y         S2      
017GND              VIA   -    M      A18X+020040Y+063238X0260Y         S2      
017GND                    -    MD0100PA00X+020040Y+063238                       
317GND              VIA   -    MD0100PA00X+020040Y+062238X0200Y         S0      
317GND              VIA   -    MD0100PA00X+020360Y+062238X0200Y         S0      
317GND              VIA   -    MD0100PA00X+020680Y+062238X0200Y         S0      
317GND              VIA   -    MD0100PA00X+023664Y+059356X0200Y         S0      
317GND              VIA   -    MD0100PA00X+023344Y+059356X0200Y         S0      
317GND              VIA   -    MD0100PA00X+028370Y+061148X0200Y         S0      
317GND              VIA   -    MD0100PA00X+028470Y+060548X0200Y         S0      
317GND              VIA   -    MD0100PA00X+028370Y+060848X0200Y         S0      
317GND              VIA   -    MD0100PA00X+028666Y+060947X0200Y         S0      
317GND              VIA   -    MD0100PA00X+028030Y+061148X0200Y         S0      
317GND              VIA   -    MD0100PA00X+027390Y+061148X0200Y         S0      
317GND              VIA   -    MD0100PA00X+027710Y+061148X0200Y         S0      
317GND              VIA   -    MD0100PA00X+028030Y+060848X0200Y         S0      
317GND              VIA   -    MD0100PA00X+027390Y+060848X0200Y         S0      
317GND              VIA   -    MD0100PA00X+027710Y+060848X0200Y         S0      
317GND              VIA   -    MD0100PA00X+027090Y+060848X0200Y         S0      
317GND              VIA   -    M      A01X+030445Y+060957X0200Y         S2      
017GND              VIA   -    M      A18X+030445Y+060957X0260Y         S2      
017GND                    -    MD0100PA00X+030445Y+060957                       
317GND              VIA   -    M      A01X+031135Y+060963X0200Y         S2      
017GND              VIA   -    M      A18X+031135Y+060963X0260Y         S2      
017GND                    -    MD0100PA00X+031135Y+060963                       
317GND              VIA   -    MD0100PA00X+030096Y+060957X0200Y         S0      
317GND              VIA   -    MD0100PA00X+030786Y+060957X0200Y         S0      
317GND              VIA   -    M      A01X+029086Y+060947X0200Y         S2      
017GND              VIA   -    M      A18X+029086Y+060947X0260Y         S2      
017GND                    -    MD0100PA00X+029086Y+060947                       
317GND              VIA   -    MD0100PA00X+029784Y+060958X0200Y         S0      
317GND              VIA   -    MD0100PA00X+029416Y+060957X0200Y         S0      
317GND              VIA   -    MD0100PA00X+040313Y+056542X0200Y    R180 S0      
327GND              PC250 -2   M      A18X+040073Y+056542X0198Y0197R180 S2      
327GND              PC243 -2   M      A18X+040073Y+056142X0198Y0197R180 S2      
327GND              PC6   -2          A18X+040073Y+055742X0198Y0197R180 S2      
317GND              VIA   -    MD0100PA00X+035116Y+056242X0200Y         S0      
327GND              PC252 -2          A18X+039966Y+054934X0198Y0197R090 S2      
317GND              VIA   -    M      A01X+039966Y+054692X0300Y         S1      
017GND              VIA   -    M      A18X+039966Y+054692X0200Y         S1      
017GND                    -    MD0100PA00X+039966Y+054692                       
327GND              PC11  -2          A18X+038766Y+054934X0198Y0197R090 S2      
317GND              VIA   -    MD0100PA00X+038766Y+054688X0200Y         S0      
327GND              PC251 -2          A18X+039166Y+054934X0198Y0197R090 S2      
317GND              VIA   -    MD0100PA00X+039166Y+054682X0200Y         S0      
327GND              PC10  -2          A18X+039566Y+054934X0198Y0197R090 S2      
317GND              VIA   -    MD0100PA00X+039566Y+054689X0200Y         S0      
317GND              VIA   -    MD0100PA00X+035685Y+054789X0200Y         S0      
327GND              C5012 -2          A18X+035673Y+055042X0198Y0197R180 S2      
317GND              VIA   -    MD0100PA00X+035082Y+055825X0200Y    R180 S0      
317GND              VIA   -    MD0100PA00X+035370Y+054789X0200Y         S0      
317GND              VIA   -    MD0100PA00X+034550Y+057442X0200Y         S0      
327GND              C5019 -1          A01X+034816Y+057442X0198Y0197R270 S1      
327GND              C224  -2          A01X+033180Y+056609X0198Y0197     S1      
327GND              PC153 -2          A01X+027680Y+057850X0198Y0197R270 S1      
327GND              PR602 -2          A01X+040295Y+055192X0198Y0197     S1      
327GND              C5003 -1          A01X+035603Y+055042X0198Y0197     S1      
317GND              VIA   -    MD0100PA00X+036910Y+057740X0200Y    R180 S0      
327GND              PU25  -TH  M      A18X+037666Y+056992X1740Y1740R270 S2      
327GND              PR159 -2          A01X+038738Y+057112X0198Y0197R180 S1      
317GND              VIA   -    MD0100PA00X+038430Y+057745X0200Y    R180 S0      
317GND              VIA   -    MD0100PA00X+036917Y+056238X0200Y    R180 S0      
317GND              VIA   -    MD0100PA00X+038426Y+056243X0200Y    R180 S0      
327GND              PC6007-2          A01X+048504Y+057857X0198Y0197     S1      
317GND              VIA   -    MD0100PA00X+033399Y+059063X0200Y         S0      
327GND              PC6002-2          A01X+033399Y+059373X0198Y0197R270 S1      
327GND              PR4   -2          A01X+038758Y+056592X0198Y0197R180 S1      
317GND              VIA   -    MD0100PA00X+028115Y+052180X0200Y    R090 S0      
317GND              VIA   -    MD0100PA00X+027224Y+052308X0200Y    R090 S0      
317GND              VIA   -    MD0100PA00X+025031Y+066718X0200Y    R180 S0      
317GND              VIA   -    MD0100PA00X+025031Y+067008X0200Y    R180 S0      
317GND              VIA   -    MD0100PA00X+026190Y+066284X0193Y    R180 S0      
317GND              VIA   -    MD0100PA00X+025948Y+066284X0193Y    R180 S0      
317GND              VIA   -    M      A01X+033474Y+056609X0200Y         S2      
017GND              VIA   -    M      A18X+033474Y+056609X0260Y         S2      
017GND                    -    MD0100PA00X+033474Y+056609                       
317GND              VIA   -    M      A01X+048840Y+057857X0200Y         S2      
017GND              VIA   -    M      A18X+048840Y+057857X0260Y         S2      
017GND                    -    MD0100PA00X+048840Y+057857                       
317GND              VIA   -    MD0100PA00X+036559Y+062162X0200Y         S0      
317GND              PC336 -2   MD0400PA00X+044347Y+059426X0600Y    R090 S3      
317GND              VIA   -    MD0100PA00X+007773Y+054446X0200Y    R090 S0      
327GND              R4079 -2          A01X+004863Y+054984X0198Y0197R090 S1      
317GND              VIA   -    MD0100PA00X+004863Y+055236X0200Y    R180 S0      
327GND              PC544_-2          A01X+151091Y+069876X0198Y0197R270 S1      
327GND              PC551_-2          A01X+151502Y+070220X0198Y0197R180 S1      
327GND              PC474_-2          A01X+147783Y+069876X0198Y0197R270 S1      
327GND              PC552_-2          A01X+148193Y+070220X0198Y0197R180 S1      
317GND              VIA   -    MD0100PA00X+151338Y+069775X0200Y         S0      
317GND              VIA   -    MD0100PA00X+151502Y+069967X0200Y         S0      
317GND              VIA   -    MD0100PA00X+148030Y+069775X0200Y         S0      
317GND              VIA   -    MD0100PA00X+148193Y+069967X0200Y         S0      
317GND              VIA   -    MD0100PA00X+149763Y+072710X0193Y    R180 S0      
317GND              VIA   -    MD0100PA00X+149513Y+072710X0193Y    R180 S0      
317GND              VIA   -    MD0100PA00X+149269Y+072708X0193Y    R180 S0      
317GND              VIA   -    MD0100PA00X+148767Y+072714X0200Y    R180 S0      
317GND              VIA   -    MD0100PA00X+149226Y+072411X0193Y    R180 S0      
317GND              VIA   -    MD0100PA00X+147495Y+072710X0193Y    R180 S0      
317GND              VIA   -    MD0100PA00X+146975Y+072710X0193Y    R180 S0      
317GND              VIA   -    MD0100PA00X+147235Y+072710X0193Y    R180 S0      
317GND              VIA   -    MD0100PA00X+147235Y+072399X0193Y    R180 S0      
317GND              VIA   -    MD0100PA00X+147495Y+072399X0193Y    R180 S0      
317GND              VIA   -    MD0100PA00X+146975Y+072399X0193Y    R180 S0      
317GND              VIA   -    M      A01X+147976Y+072286X0200Y    R180 S2      
017GND              VIA   -    M      A18X+147976Y+072286X0260Y    R180 S2      
017GND                    -    MD0100PA00X+147976Y+072286                       
317GND              VIA   -    MD0100PA00X+146715Y+072710X0193Y    R180 S0      
317GND              VIA   -    MD0100PA00X+146715Y+072399X0193Y    R180 S0      
317GND              VIA   -    MD0100PA00X+146455Y+072710X0193Y    R180 S0      
317GND              VIA   -    MD0100PA00X+146205Y+072710X0193Y    R180 S0      
317GND              VIA   -    MD0100PA00X+145960Y+072708X0193Y    R180 S0      
317GND              VIA   -    MD0100PA00X+145458Y+072714X0200Y    R180 S0      
317GND              VIA   -    MD0100PA00X+145594Y+073224X0200Y    R180 S0      
317GND              VIA   -    MD0100PA00X+145594Y+072964X0200Y    R180 S0      
317GND              VIA   -    MD0100PA00X+145860Y+072400X0193Y    R180 S0      
317GND              VIA   -    MD0100PA00X+145334Y+073224X0200Y    R180 S0      
317GND              VIA   -    MD0100PA00X+145334Y+072964X0200Y    R180 S0      
317GND              VIA   -    MD0100PA00X+142276Y+072360X0200Y    R180 S0      
317GND              VIA   -    MD0100PA00X+142276Y+072610X0200Y    R180 S0      
317GND              VIA   -    MD0100PA00X+157890Y+072384X0200Y    R180 S0      
317GND              VIA   -    MD0100PA00X+154556Y+072290X0193Y    R180 S0      
317GND              VIA   -    MD0100PA00X+155375Y+072384X0200Y    R180 S0      
317GND              VIA   -    MD0100PA00X+155125Y+072384X0200Y    R180 S0      
317GND              VIA   -    MD0100PA00X+153563Y+072710X0193Y    R180 S0      
317GND              VIA   -    MD0100PA00X+153303Y+072710X0193Y    R180 S0      
317GND              VIA   -    MD0100PA00X+153563Y+072399X0193Y    R180 S0      
317GND              VIA   -    MD0100PA00X+153303Y+072399X0193Y    R180 S0      
317GND              VIA   -    MD0100PA00X+153043Y+072710X0193Y    R180 S0      
317GND              VIA   -    MD0100PA00X+154083Y+072710X0193Y    R180 S0      
317GND              VIA   -    MD0100PA00X+153823Y+072710X0193Y    R180 S0      
317GND              VIA   -    MD0100PA00X+154083Y+072399X0193Y    R180 S0      
317GND              VIA   -    MD0100PA00X+153823Y+072399X0193Y    R180 S0      
317GND              VIA   -    MD0100PA00X+152047Y+072714X0200Y    R180 S0      
317GND              VIA   -    MD0100PA00X+151922Y+073224X0200Y    R180 S0      
317GND              VIA   -    MD0100PA00X+151922Y+072964X0200Y    R180 S0      
317GND              VIA   -    MD0100PA00X+152793Y+072710X0193Y    R180 S0      
317GND              VIA   -    MD0100PA00X+152549Y+072708X0193Y    R180 S0      
317GND              VIA   -    MD0100PA00X+152182Y+073224X0200Y    R180 S0      
317GND              VIA   -    MD0100PA00X+152182Y+072964X0200Y    R180 S0      
317GND              VIA   -    MD0100PA00X+152506Y+072411X0193Y    R180 S0      
317GND              VIA   -    MD0100PA00X+150803Y+072710X0193Y    R180 S0      
317GND              VIA   -    MD0100PA00X+150543Y+072710X0193Y    R180 S0      
317GND              VIA   -    MD0100PA00X+150283Y+072710X0193Y    R180 S0      
317GND              VIA   -    MD0100PA00X+150023Y+072710X0193Y    R180 S0      
317GND              VIA   -    MD0100PA00X+150803Y+072399X0193Y    R180 S0      
317GND              VIA   -    MD0100PA00X+150543Y+072399X0193Y    R180 S0      
317GND              VIA   -    MD0100PA00X+150283Y+072399X0193Y    R180 S0      
317GND              VIA   -    MD0100PA00X+150023Y+072399X0193Y    R180 S0      
317GND              VIA   -    M      A01X+151276Y+072290X0200Y    R180 S2      
017GND              VIA   -    M      A18X+151276Y+072290X0260Y    R180 S2      
017GND                    -    MD0100PA00X+151276Y+072290                       
317GND              VIA   -    MD0100PA00X+148902Y+073224X0200Y    R180 S0      
317GND              VIA   -    MD0100PA00X+148902Y+072969X0200Y    R180 S0      
317GND              VIA   -    MD0100PA00X+148642Y+073224X0200Y    R180 S0      
317GND              VIA   -    MD0100PA00X+148642Y+072964X0200Y    R180 S0      
317GND              VIA   -    MD0100PA00X+145376Y+074610X0200Y    R180 S0      
317GND              VIA   -    MD0100PA00X+145376Y+074360X0200Y    R180 S0      
317GND              VIA   -    MD0100PA00X+145334Y+073484X0200Y    R180 S0      
317GND              VIA   -    MD0100PA00X+145594Y+073484X0200Y    R180 S0      
317GND              VIA   -    MD0100PA00X+148166Y+074581X0200Y    R180 S0      
317GND              VIA   -    MD0100PA00X+148426Y+074581X0200Y    R180 S0      
317GND              VIA   -    MD0100PA00X+148902Y+073484X0200Y    R180 S0      
317GND              VIA   -    MD0100PA00X+148642Y+073484X0200Y    R180 S0      
317GND              VIA   -    MD0100PA00X+150850Y+074612X0200Y    R180 S0      
317GND              VIA   -    MD0100PA00X+150590Y+074612X0200Y    R180 S0      
317GND              VIA   -    MD0100PA00X+151850Y+074612X0200Y    R180 S0      
317GND              VIA   -    MD0100PA00X+151590Y+074612X0200Y    R180 S0      
317GND              VIA   -    MD0100PA00X+151922Y+073484X0200Y    R180 S0      
317GND              VIA   -    MD0100PA00X+152182Y+073484X0200Y    R180 S0      
317GND              VIA   -    MD0100PA00X+154357Y+076036X0200Y    R180 S0      
317GND              VIA   -    MD0100PA00X+154358Y+076292X0200Y    R180 S0      
317GND              VIA   -    MD0100PA00X+154356Y+075780X0200Y    R180 S0      
317GND              VIA   -    MD0100PA00X+154607Y+076036X0200Y    R180 S0      
317GND              VIA   -    MD0100PA00X+154608Y+076292X0200Y    R180 S0      
317GND              VIA   -    MD0100PA00X+154606Y+075780X0200Y    R180 S0      
317GND              VIA   -    MD0100PA00X+154562Y+075483X0200Y    R180 S0      
317GND              VIA   -    MD0100PA00X+154812Y+075483X0200Y    R180 S0      
317GND              VIA   -    MD0100PA00X+154562Y+075195X0200Y    R180 S0      
317GND              VIA   -    MD0100PA00X+154812Y+075195X0200Y    R180 S0      
317GND              VIA   -    MD0100PA00X+154695Y+074356X0200Y    R180 S0      
317GND              VIA   -    MD0100PA00X+154696Y+074612X0200Y    R180 S0      
317GND              VIA   -    MD0100PA00X+155404Y+073806X0200Y    R180 S0      
317GND              VIA   -    MD0100PA00X+155406Y+074062X0200Y    R180 S0      
317GND              VIA   -    MD0100PA00X+155654Y+073806X0200Y    R180 S0      
317GND              VIA   -    MD0100PA00X+155656Y+074062X0200Y    R180 S0      
317GND              VIA   -    MD0100PA00X+156300Y+078952X0200Y         S0      
327GND              R6134 -2   M      A18X+155962Y+078880X0198Y0197R090 S2      
327GND              R6133 -2          A18X+155043Y+078875X0198Y0197R090 S2      
327GND              R6135 -2   M      A18X+155560Y+078883X0198Y0197R090 S2      
327GND              PR499 -2          A01X+154758Y+072472X0198Y0197R270 S1      
327GND              PR498 -2          A01X+151478Y+072472X0198Y0197R270 S1      
327GND              PR496 -2          A01X+148170Y+072472X0198Y0197R270 S1      
327GND              PL60  -3          A01X+153264Y+076077X0540Y1780R090 S1      
317GND              VIA   -    MD0100PA00X+160864Y+064066X0200Y         S0      
317GND              VIA   -    MD0100PA00X+142626Y+070157X0193Y    R180 S0      
317GND              VIA   -    MD0100PA00X+142626Y+070453X0193Y    R180 S0      
317GND              VIA   -    MD0100PA00X+145860Y+072104X0193Y    R180 S0      
317GND              VIA   -    MD0100PA00X+149226Y+072115X0193Y    R180 S0      
317GND              VIA   -    MD0100PA00X+152506Y+072115X0193Y    R180 S0      
317GND              VIA   -    MD0100PA00X+155819Y+069921X0193Y    R180 S0      
317GND              VIA   -    MD0100PA00X+155819Y+070217X0193Y    R180 S0      
317GND              VIA   -    MD0100PA00X+159096Y+066544X0193Y    R180 S0      
317GND              VIA   -    MD0100PA00X+159096Y+066840X0193Y    R180 S0      
317GND              VIA   -    MD0100PA00X+162396Y+064644X0193Y    R180 S0      
317GND              VIA   -    MD0100PA00X+162396Y+064940X0193Y    R180 S0      
317GND              VIA   -    MD0100PA00X+136094Y+063604X0193Y    R180 S0      
317GND              VIA   -    MD0100PA00X+136094Y+063900X0193Y    R180 S0      
317GND              VIA   -    MD0100PA00X+139366Y+066899X0193Y    R180 S0      
317GND              VIA   -    MD0100PA00X+139366Y+067195X0193Y    R180 S0      
317GND              VIA   -    MD0100PA00X+163546Y+064253X0193Y    R180 S0      
317GND              VIA   -    MD0100PA00X+163303Y+064253X0193Y    R180 S0      
317GND              VIA   -    MD0100PA00X+160246Y+066153X0193Y    R180 S0      
317GND              VIA   -    MD0100PA00X+160003Y+066153X0193Y    R180 S0      
317GND              VIA   -    MD0100PA00X+156969Y+069530X0193Y    R180 S0      
317GND              VIA   -    MD0100PA00X+156726Y+069530X0193Y    R180 S0      
317GND              VIA   -    MD0100PA00X+153656Y+071724X0193Y    R180 S0      
317GND              VIA   -    MD0100PA00X+153413Y+071724X0193Y    R180 S0      
317GND              VIA   -    MD0100PA00X+150376Y+071740X0193Y    R180 S0      
317GND              VIA   -    MD0100PA00X+150133Y+071740X0193Y    R180 S0      
317GND              VIA   -    MD0100PA00X+147068Y+071724X0193Y    R180 S0      
317GND              VIA   -    MD0100PA00X+146824Y+071724X0193Y    R180 S0      
317GND              VIA   -    MD0100PA00X+143776Y+069766X0193Y    R180 S0      
317GND              VIA   -    MD0100PA00X+143533Y+069766X0193Y    R180 S0      
317GND              VIA   -    MD0100PA00X+140516Y+066508X0193Y    R180 S0      
317GND              VIA   -    MD0100PA00X+140273Y+066508X0193Y    R180 S0      
317GND              VIA   -    MD0100PA00X+137246Y+063218X0193Y    R180 S0      
317GND              VIA   -    MD0100PA00X+137003Y+063218X0193Y    R180 S0      
317GND              PJ1   -1   MD0410PA00X+155038Y+058135X0610Y0610R270 S3      
317GND              VIA   -    MD0100PA00X+130327Y+053041X0200Y    R270 S0      
317GND              VIA   -    MD0100PA00X+130327Y+053371X0200Y    R270 S0      
327GND              PC254 -2          A01X+130677Y+053211X0400Y0500     S1      
317GND              VIA   -    MD0100PA00X+129908Y+053002X0200Y         S0      
327GND              PC6001-2          A01X+129908Y+052742X0198Y0197R180 S1      
317GND              VIA   -    MD0100PA00X+134184Y+063772X0193Y    R180 S0      
317GND              VIA   -    MD0100PA00X+134444Y+063772X0193Y    R180 S0      
317GND              VIA   -    MD0100PA00X+133388Y+063772X0193Y    R180 S0      
317GND              VIA   -    MD0100PA00X+133924Y+063772X0193Y    R180 S0      
317GND              VIA   -    MD0100PA00X+133656Y+063772X0193Y    R180 S0      
317GND              VIA   -    MD0100PA00X+131727Y+059252X0200Y    R090 S0      
317GND              VIA   -    MD0100PA00X+131727Y+058952X0200Y    R270 S0      
317GND              VIA   -    MD0100PA00X+130870Y+059030X0200Y    R090 S0      
317GND              VIA   -    MD0100PA00X+130020Y+059060X0200Y    R270 S0      
317GND              VIA   -    MD0100PA00X+132537Y+059252X0200Y    R090 S0      
317GND              VIA   -    MD0100PA00X+132537Y+058952X0200Y    R270 S0      
327GND              PC579 -2          A01X+158074Y+068546X0198Y0197R270 S1      
327GND              C5018 -1          A01X+145868Y+056498X0198Y0197     S1      
317GND              VIA   -    MD0100PA00X+149437Y+059446X0200Y         S0      
327GND              PC583 -2          A01X+149156Y+059446X0198Y0197R270 S1      
317GND              VIA   -    MD0100PA00X+143923Y+059629X0200Y         S0      
327GND              PR347 -1          A01X+153667Y+069895X0198Y0197     S1      
327GND              PR441 -2          A18X+150254Y+058544X0198Y0197R270 S2      
327GND              PR440 -2   M      A18X+149854Y+058544X0198Y0197R270 S2      
327GND              PR531 -2          A18X+149454Y+058544X0198Y0197R270 S2      
317GND              VIA   -    MD0100PA00X+149854Y+058784X0200Y    R180 S0      
317GND              VIA   -    MD0100PA00X+153285Y+056026X0200Y    R180 S0      
327GND              C5017 -1          A01X+146583Y+053783X0198Y0197R180 S1      
327GND              C5011 -2          A18X+146583Y+053783X0198Y0197R090 S2      
327GND              R6089 -2          A18X+144595Y+053532X0198Y0197     S2      
317GND              VIA   -    MD0100PA00X+144355Y+053532X0200Y         S0      
327GND              C467  -2          A18X+146668Y+054898X0198Y0197     S2      
317GND              VIA   -    MD0100PA00X+146426Y+055298X0200Y         S0      
327GND              C468  -2   M      A18X+146668Y+055298X0198Y0197     S2      
317GND              VIA   -    MD0100PA00X+146583Y+053533X0200Y    R090 S0      
317GND              VIA   -    MD0100PA00X+131830Y+064900X0200Y    R270 S0      
317GND              VIA   -    MD0100PA00X+163298Y+062451X0200Y    R180 S0      
317GND              VIA   -    M      A01X+164512Y+062448X0200Y    R180 S2      
017GND              VIA   -    M      A18X+164512Y+062448X0260Y    R180 S2      
017GND                    -    MD0100PA00X+164512Y+062448                       
327GND              PR365 -1          A01X+163557Y+062424X0198Y0197     S1      
327GND              PC605_-2          A01X+164576Y+062721X0198Y0197     S1      
317GND              VIA   -    MD0100PA00X+136998Y+061416X0200Y    R180 S0      
317GND              VIA   -    M      A01X+138212Y+061413X0200Y    R180 S2      
017GND              VIA   -    M      A18X+138212Y+061413X0260Y    R180 S2      
017GND                    -    MD0100PA00X+138212Y+061413                       
327GND              PR431 -1          A01X+137257Y+061389X0198Y0197     S1      
327GND              PC150_-2          A01X+137961Y+061371X0198Y0197R270 S1      
317GND              VIA   -    MD0100PA00X+161315Y+068824X0200Y    R180 S0      
317GND              VIA   -    MD0100PA00X+161315Y+069074X0200Y    R180 S0      
317GND              VIA   -    MD0100PA00X+158772Y+067913X0200Y    R180 S0      
317GND              VIA   -    MD0100PA00X+158512Y+067913X0200Y    R180 S0      
317GND              VIA   -    MD0100PA00X+158607Y+069433X0200Y    R180 S0      
317GND              VIA   -    MD0100PA00X+158607Y+069683X0200Y    R180 S0      
317GND              VIA   -    MD0100PA00X+156726Y+068970X0193Y    R180 S0      
317GND              VIA   -    MD0100PA00X+157212Y+068970X0193Y    R180 S0      
317GND              VIA   -    MD0100PA00X+156969Y+068970X0193Y    R180 S0      
317GND              VIA   -    MD0100PA00X+156616Y+069910X0193Y    R180 S0      
317GND              VIA   -    MD0100PA00X+156616Y+070516X0193Y    R180 S0      
317GND              VIA   -    MD0100PA00X+156616Y+070205X0193Y    R180 S0      
317GND              VIA   -    MD0100PA00X+156876Y+069910X0193Y    R180 S0      
317GND              VIA   -    MD0100PA00X+157136Y+070516X0193Y    R180 S0      
317GND              VIA   -    MD0100PA00X+157136Y+070205X0193Y    R180 S0      
317GND              VIA   -    MD0100PA00X+156876Y+070516X0193Y    R180 S0      
317GND              VIA   -    MD0100PA00X+156876Y+070205X0193Y    R180 S0      
317GND              VIA   -    MD0100PA00X+157396Y+070516X0193Y    R180 S0      
317GND              VIA   -    MD0100PA00X+157396Y+070205X0193Y    R180 S0      
317GND              VIA   -    MD0100PA00X+157212Y+069530X0193Y    R180 S0      
317GND              VIA   -    MD0100PA00X+157876Y+070096X0193Y    R180 S0      
317GND              VIA   -    MD0100PA00X+157890Y+072134X0200Y    R180 S0      
317GND              VIA   -    MD0100PA00X+155862Y+070514X0193Y    R180 S0      
317GND              VIA   -    MD0100PA00X+156106Y+070516X0193Y    R180 S0      
317GND              VIA   -    MD0100PA00X+155360Y+070520X0200Y    R180 S0      
317GND              VIA   -    MD0100PA00X+155495Y+070770X0200Y    R180 S0      
317GND              VIA   -    MD0100PA00X+155495Y+071030X0200Y    R180 S0      
317GND              VIA   -    MD0100PA00X+155235Y+070770X0200Y    R180 S0      
317GND              VIA   -    MD0100PA00X+155235Y+071030X0200Y    R180 S0      
317GND              VIA   -    MD0100PA00X+155495Y+071290X0200Y    R180 S0      
317GND              VIA   -    MD0100PA00X+155235Y+071290X0200Y    R180 S0      
317GND              VIA   -    MD0100PA00X+156356Y+070516X0193Y    R180 S0      
317GND              VIA   -    MD0100PA00X+153899Y+071164X0193Y    R180 S0      
317GND              VIA   -    MD0100PA00X+153899Y+071724X0193Y    R180 S0      
317GND              VIA   -    MD0100PA00X+153303Y+072104X0193Y    R180 S0      
317GND              VIA   -    MD0100PA00X+153563Y+072104X0193Y    R180 S0      
317GND              VIA   -    MD0100PA00X+153413Y+071164X0193Y    R180 S0      
317GND              VIA   -    MD0100PA00X+153656Y+071164X0193Y    R180 S0      
317GND              VIA   -    MD0100PA00X+150023Y+072104X0193Y    R180 S0      
317GND              VIA   -    MD0100PA00X+150283Y+072104X0193Y    R180 S0      
317GND              VIA   -    MD0100PA00X+150376Y+071164X0193Y    R180 S0      
317GND              VIA   -    MD0100PA00X+150133Y+071164X0193Y    R180 S0      
317GND              VIA   -    MD0100PA00X+150619Y+071164X0193Y    R180 S0      
317GND              VIA   -    MD0100PA00X+150619Y+071724X0193Y    R180 S0      
317GND              VIA   -    MD0100PA00X+146715Y+072104X0193Y    R180 S0      
317GND              VIA   -    MD0100PA00X+146975Y+072104X0193Y    R180 S0      
317GND              VIA   -    MD0100PA00X+147310Y+071164X0193Y    R180 S0      
317GND              VIA   -    MD0100PA00X+147068Y+071164X0193Y    R180 S0      
317GND              VIA   -    MD0100PA00X+146824Y+071164X0193Y    R180 S0      
317GND              VIA   -    MD0100PA00X+147310Y+071724X0193Y    R180 S0      
317GND              VIA   -    MD0100PA00X+143423Y+070752X0193Y    R180 S0      
317GND              VIA   -    MD0100PA00X+143423Y+070442X0193Y    R180 S0      
317GND              VIA   -    MD0100PA00X+143423Y+070146X0193Y    R180 S0      
317GND              VIA   -    MD0100PA00X+142669Y+070751X0193Y    R180 S0      
317GND              VIA   -    MD0100PA00X+142913Y+070752X0193Y    R180 S0      
317GND              VIA   -    MD0100PA00X+143163Y+070752X0193Y    R180 S0      
317GND              VIA   -    MD0100PA00X+144019Y+069206X0193Y    R180 S0      
317GND              VIA   -    MD0100PA00X+143776Y+069206X0193Y    R180 S0      
317GND              VIA   -    MD0100PA00X+143533Y+069206X0193Y    R180 S0      
317GND              VIA   -    M      A01X+144676Y+070326X0200Y    R180 S2      
017GND              VIA   -    M      A18X+144676Y+070326X0260Y    R180 S2      
017GND                    -    MD0100PA00X+144676Y+070326                       
317GND              VIA   -    MD0100PA00X+143943Y+070752X0193Y    R180 S0      
317GND              VIA   -    MD0100PA00X+144203Y+070752X0193Y    R180 S0      
317GND              VIA   -    MD0100PA00X+144203Y+070442X0193Y    R180 S0      
317GND              VIA   -    MD0100PA00X+143943Y+070442X0193Y    R180 S0      
317GND              VIA   -    MD0100PA00X+143683Y+070752X0193Y    R180 S0      
317GND              VIA   -    MD0100PA00X+143683Y+070442X0193Y    R180 S0      
317GND              VIA   -    MD0100PA00X+143683Y+070146X0193Y    R180 S0      
317GND              VIA   -    MD0100PA00X+144019Y+069766X0193Y    R180 S0      
317GND              VIA   -    MD0100PA00X+142167Y+070756X0200Y    R180 S0      
317GND              VIA   -    MD0100PA00X+142302Y+071006X0200Y    R180 S0      
317GND              VIA   -    MD0100PA00X+142302Y+071526X0200Y    R180 S0      
317GND              VIA   -    MD0100PA00X+142302Y+071266X0200Y    R180 S0      
317GND              VIA   -    MD0100PA00X+138782Y+068268X0200Y    R180 S0      
317GND              VIA   -    MD0100PA00X+139042Y+068268X0200Y    R180 S0      
317GND              VIA   -    MD0100PA00X+138782Y+068008X0200Y    R180 S0      
317GND              VIA   -    MD0100PA00X+139042Y+068008X0200Y    R180 S0      
317GND              VIA   -    MD0100PA00X+138876Y+069090X0200Y    R180 S0      
317GND              VIA   -    MD0100PA00X+138876Y+069340X0200Y    R180 S0      
317GND              VIA   -    MD0100PA00X+141629Y+069763X0200Y    R180 S0      
317GND              VIA   -    MD0100PA00X+141624Y+070028X0200Y    R180 S0      
317GND              VIA   -    MD0100PA00X+142042Y+071006X0200Y    R180 S0      
317GND              VIA   -    MD0100PA00X+142042Y+071526X0200Y    R180 S0      
317GND              VIA   -    MD0100PA00X+142042Y+071266X0200Y    R180 S0      
317GND              VIA   -    MD0100PA00X+165352Y+065493X0200Y    R180 S0      
317GND              VIA   -    MD0100PA00X+165217Y+065243X0200Y    R180 S0      
317GND              VIA   -    MD0100PA00X+165694Y+065902X0193Y    R180 S0      
317GND              VIA   -    MD0100PA00X+165352Y+065753X0200Y    R180 S0      
317GND              VIA   -    MD0100PA00X+165352Y+066013X0200Y    R180 S0      
317GND              VIA   -    MD0100PA00X+165110Y+067177X0200Y    R180 S0      
317GND              VIA   -    MD0100PA00X+166230Y+065902X0193Y    R180 S0      
317GND              VIA   -    MD0100PA00X+166490Y+065902X0193Y    R180 S0      
317GND              VIA   -    MD0100PA00X+166750Y+065902X0193Y    R180 S0      
317GND              VIA   -    MD0100PA00X+165962Y+065902X0193Y    R180 S0      
317GND              VIA   -    MD0100PA00X+163303Y+063693X0193Y    R180 S0      
317GND              VIA   -    MD0100PA00X+163546Y+063693X0193Y    R180 S0      
317GND              VIA   -    MD0100PA00X+163789Y+063693X0193Y    R180 S0      
317GND              VIA   -    MD0100PA00X+162072Y+065493X0200Y    R180 S0      
317GND              VIA   -    MD0100PA00X+161937Y+065243X0200Y    R180 S0      
317GND              VIA   -    MD0100PA00X+162439Y+065237X0193Y    R180 S0      
317GND              VIA   -    MD0100PA00X+161812Y+065493X0200Y    R180 S0      
317GND              VIA   -    MD0100PA00X+163789Y+064253X0193Y    R180 S0      
317GND              VIA   -    MD0100PA00X+163193Y+064633X0193Y    R180 S0      
317GND              VIA   -    MD0100PA00X+163453Y+064633X0193Y    R180 S0      
317GND              VIA   -    MD0100PA00X+162933Y+065239X0193Y    R180 S0      
317GND              VIA   -    MD0100PA00X+162683Y+065239X0193Y    R180 S0      
317GND              VIA   -    MD0100PA00X+163193Y+064928X0193Y    R180 S0      
317GND              VIA   -    MD0100PA00X+163713Y+064928X0193Y    R180 S0      
317GND              VIA   -    MD0100PA00X+163453Y+064928X0193Y    R180 S0      
317GND              VIA   -    MD0100PA00X+163973Y+064928X0193Y    R180 S0      
317GND              VIA   -    MD0100PA00X+163193Y+065239X0193Y    R180 S0      
317GND              VIA   -    MD0100PA00X+163713Y+065239X0193Y    R180 S0      
317GND              VIA   -    MD0100PA00X+163453Y+065239X0193Y    R180 S0      
317GND              VIA   -    MD0100PA00X+163973Y+065239X0193Y    R180 S0      
317GND              VIA   -    MD0100PA00X+164446Y+064826X0193Y    R180 S0      
317GND              VIA   -    MD0100PA00X+165092Y+065493X0200Y    R180 S0      
317GND              VIA   -    MD0100PA00X+161812Y+066013X0200Y    R180 S0      
317GND              VIA   -    MD0100PA00X+162072Y+065753X0200Y    R180 S0      
317GND              VIA   -    MD0100PA00X+162072Y+066013X0200Y    R180 S0      
317GND              VIA   -    MD0100PA00X+161812Y+065753X0200Y    R180 S0      
317GND              VIA   -    MD0100PA00X+162355Y+067177X0200Y    R180 S0      
317GND              VIA   -    MD0100PA00X+162105Y+067177X0200Y    R180 S0      
317GND              VIA   -    MD0100PA00X+165092Y+066013X0200Y    R180 S0      
317GND              VIA   -    MD0100PA00X+165092Y+065753X0200Y    R180 S0      
317GND              VIA   -    MD0100PA00X+164860Y+067177X0200Y    R180 S0      
317GND              VIA   -    MD0100PA00X+160246Y+065593X0193Y    R180 S0      
317GND              VIA   -    MD0100PA00X+160003Y+065593X0193Y    R180 S0      
317GND              VIA   -    MD0100PA00X+160489Y+066153X0193Y    R180 S0      
317GND              VIA   -    MD0100PA00X+160489Y+065593X0193Y    R180 S0      
317GND              VIA   -    MD0100PA00X+159893Y+066533X0193Y    R180 S0      
317GND              VIA   -    MD0100PA00X+159893Y+066828X0193Y    R180 S0      
317GND              VIA   -    MD0100PA00X+159893Y+067139X0193Y    R180 S0      
317GND              VIA   -    MD0100PA00X+160153Y+066533X0193Y    R180 S0      
317GND              VIA   -    MD0100PA00X+160153Y+066828X0193Y    R180 S0      
317GND              VIA   -    MD0100PA00X+160153Y+067139X0193Y    R180 S0      
317GND              VIA   -    MD0100PA00X+160413Y+066828X0193Y    R180 S0      
317GND              VIA   -    MD0100PA00X+160413Y+067139X0193Y    R180 S0      
317GND              VIA   -    MD0100PA00X+160673Y+066828X0193Y    R180 S0      
317GND              VIA   -    MD0100PA00X+160673Y+067139X0193Y    R180 S0      
317GND              VIA   -    MD0100PA00X+161568Y+064849X0200Y    R180 S0      
317GND              VIA   -    MD0100PA00X+161156Y+066716X0193Y    R180 S0      
317GND              VIA   -    MD0100PA00X+159633Y+067139X0193Y    R180 S0      
317GND              VIA   -    MD0100PA00X+158512Y+067393X0200Y    R180 S0      
317GND              VIA   -    MD0100PA00X+158512Y+067653X0200Y    R180 S0      
317GND              VIA   -    MD0100PA00X+158772Y+067393X0200Y    R180 S0      
317GND              VIA   -    MD0100PA00X+158772Y+067653X0200Y    R180 S0      
317GND              VIA   -    MD0100PA00X+159383Y+067139X0193Y    R180 S0      
317GND              VIA   -    MD0100PA00X+159139Y+067137X0193Y    R180 S0      
317GND              VIA   -    MD0100PA00X+158637Y+067143X0200Y    R180 S0      
317GND              VIA   -    MD0100PA00X+157981Y+067127X0200Y    R180 S0      
317GND              VIA   -    MD0100PA00X+140273Y+065948X0193Y    R180 S0      
317GND              VIA   -    MD0100PA00X+140163Y+066888X0193Y    R180 S0      
317GND              VIA   -    MD0100PA00X+140163Y+067184X0193Y    R180 S0      
317GND              VIA   -    MD0100PA00X+140163Y+067494X0193Y    R180 S0      
317GND              VIA   -    MD0100PA00X+139903Y+067494X0193Y    R180 S0      
317GND              VIA   -    MD0100PA00X+139653Y+067494X0193Y    R180 S0      
317GND              VIA   -    MD0100PA00X+139409Y+067493X0193Y    R180 S0      
317GND              VIA   -    MD0100PA00X+138782Y+067748X0200Y    R180 S0      
317GND              VIA   -    MD0100PA00X+138907Y+067498X0200Y    R180 S0      
317GND              VIA   -    MD0100PA00X+139042Y+067748X0200Y    R180 S0      
317GND              VIA   -    MD0100PA00X+140759Y+065948X0193Y    R180 S0      
317GND              VIA   -    MD0100PA00X+140516Y+065948X0193Y    R180 S0      
317GND              VIA   -    M      A01X+141416Y+067066X0200Y    R180 S2      
017GND              VIA   -    M      A18X+141416Y+067066X0260Y    R180 S2      
017GND                    -    MD0100PA00X+141416Y+067066                       
317GND              VIA   -    MD0100PA00X+140759Y+066508X0193Y    R180 S0      
317GND              VIA   -    MD0100PA00X+140423Y+066888X0193Y    R180 S0      
317GND              VIA   -    MD0100PA00X+140943Y+067184X0193Y    R180 S0      
317GND              VIA   -    MD0100PA00X+140683Y+067184X0193Y    R180 S0      
317GND              VIA   -    MD0100PA00X+140423Y+067184X0193Y    R180 S0      
317GND              VIA   -    MD0100PA00X+140683Y+067494X0193Y    R180 S0      
317GND              VIA   -    MD0100PA00X+140943Y+067494X0193Y    R180 S0      
317GND              VIA   -    MD0100PA00X+140423Y+067494X0193Y    R180 S0      
317GND              VIA   -    MD0100PA00X+137003Y+062658X0193Y    R180 S0      
317GND              VIA   -    MD0100PA00X+136893Y+063598X0193Y    R180 S0      
317GND              VIA   -    MD0100PA00X+136893Y+064204X0193Y    R180 S0      
317GND              VIA   -    MD0100PA00X+136893Y+063894X0193Y    R180 S0      
317GND              VIA   -    MD0100PA00X+137246Y+062658X0193Y    R180 S0      
317GND              VIA   -    MD0100PA00X+137489Y+062658X0193Y    R180 S0      
317GND              VIA   -    MD0100PA00X+137413Y+064204X0193Y    R180 S0      
317GND              VIA   -    MD0100PA00X+137413Y+063894X0193Y    R180 S0      
317GND              VIA   -    MD0100PA00X+137489Y+063218X0193Y    R180 S0      
317GND              VIA   -    MD0100PA00X+138146Y+063786X0193Y    R180 S0      
317GND              VIA   -    MD0100PA00X+137153Y+063598X0193Y    R180 S0      
317GND              VIA   -    MD0100PA00X+137153Y+064204X0193Y    R180 S0      
317GND              VIA   -    MD0100PA00X+137153Y+063894X0193Y    R180 S0      
317GND              VIA   -    MD0100PA00X+137673Y+064204X0193Y    R180 S0      
317GND              VIA   -    MD0100PA00X+137673Y+063894X0193Y    R180 S0      
317GND              VIA   -    MD0100PA00X+137185Y+066133X0200Y    R180 S0      
317GND              VIA   -    MD0100PA00X+138026Y+066747X0200Y    R180 S0      
317GND              VIA   -    MD0100PA00X+138031Y+066482X0200Y    R180 S0      
317GND              VIA   -    MD0100PA00X+135253Y+063828X0200Y    R180 S0      
317GND              VIA   -    MD0100PA00X+135512Y+064458X0200Y    R180 S0      
317GND              VIA   -    MD0100PA00X+135637Y+064208X0200Y    R180 S0      
317GND              VIA   -    MD0100PA00X+135772Y+064458X0200Y    R180 S0      
317GND              VIA   -    MD0100PA00X+136139Y+064203X0193Y    R180 S0      
317GND              VIA   -    MD0100PA00X+136383Y+064204X0193Y    R180 S0      
317GND              VIA   -    MD0100PA00X+136633Y+064204X0193Y    R180 S0      
317GND              VIA   -    MD0100PA00X+135512Y+064718X0200Y    R180 S0      
317GND              VIA   -    MD0100PA00X+135512Y+064978X0200Y    R180 S0      
317GND              VIA   -    MD0100PA00X+135772Y+064978X0200Y    R180 S0      
317GND              VIA   -    MD0100PA00X+135772Y+064718X0200Y    R180 S0      
317GND              VIA   -    MD0100PA00X+135706Y+066133X0200Y    R180 S0      
317GND              VIA   -    MD0100PA00X+136432Y+066137X0200Y    R180 S0      
317GND              VIA   -    M      A01X+154626Y+070110X0200Y    R180 S2      
017GND              VIA   -    M      A18X+154626Y+070110X0260Y    R180 S2      
017GND                    -    MD0100PA00X+154626Y+070110                       
317GND              VIA   -    MD0100PA00X+153408Y+069922X0200Y    R180 S0      
317GND              VIA   -    MD0100PA00X+159998Y+064351X0200Y    R180 S0      
317GND              VIA   -    MD0100PA00X+156273Y+067518X0200Y    R270 S0      
317GND              VIA   -    MD0100PA00X+156601Y+067321X0200Y    R270 S0      
317GND              VIA   -    MD0100PA00X+156721Y+067728X0200Y    R180 S0      
317GND              VIA   -    M      A01X+157684Y+067442X0200Y    R180 S2      
017GND              VIA   -    M      A18X+157684Y+067442X0260Y    R180 S2      
017GND                    -    MD0100PA00X+157684Y+067442                       
327GND              PC153_-2          A01X+135026Y+063566X0198Y0197R090 S1      
327GND              PC154_-2          A01X+135460Y+063566X0198Y0197R090 S1      
327GND              PL50  -1          A01X+133922Y+064372X0790Y1660R090 S1      
327GND              PU10  -40  M      A01X+137245Y+062939X0690Y0770R180 S1      
327GND              PU10  -7_9-M      A01X+136901Y+063894X0827Y2126R270 S1      
327GND              PC152_-2          A01X+138351Y+063599X0198Y0197R090 S1      
327GND              PR500 -2          A01X+138348Y+063966X0198Y0197R270 S1      
327GND              PU10  -5          A01X+137846Y+063254X0090Y0240R270 S1      
327GND              PU10  -2   M      A01X+137846Y+062722X0090Y0240R270 S1      
327GND              PC608_-2          A01X+161760Y+064600X0198Y0197R090 S1      
327GND              PC609_-2          A01X+161360Y+064600X0198Y0197R090 S1      
327GND              PU51  -40  M      A01X+163545Y+063974X0690Y0770R180 S1      
327GND              PU51  -7_9-M      A01X+163201Y+064928X0827Y2126R270 S1      
327GND              PU51  -5          A01X+164146Y+064288X0090Y0240R270 S1      
327GND              PU51  -2   M      A01X+164146Y+063757X0090Y0240R270 S1      
327GND              PC607_-2          A01X+164651Y+064634X0198Y0197R090 S1      
327GND              PC569_-2          A01X+138730Y+066856X0198Y0197R090 S1      
327GND              PR501 -2          A01X+141618Y+067256X0198Y0197R270 S1      
327GND              PU48  -40  M      A01X+140515Y+066229X0690Y0770R180 S1      
327GND              PU48  -7_9-M      A01X+140171Y+067184X0827Y2126R270 S1      
327GND              PU48  -5          A01X+141116Y+066544X0090Y0240R270 S1      
327GND              PU48  -2   M      A01X+141116Y+066012X0090Y0240R270 S1      
327GND              PC568_-2          A01X+141621Y+066889X0198Y0197R090 S1      
327GND              PU6   -7_9-M      A01X+143431Y+070442X0827Y2126R270 S1      
327GND              PC481_-2          A01X+142001Y+070081X0198Y0197R090 S1      
327GND              PU6   -40  M      A01X+143775Y+069487X0690Y0770R180 S1      
327GND              PU6   -5          A01X+144376Y+069802X0090Y0240R270 S1      
327GND              PU6   -2   M      A01X+144376Y+069270X0090Y0240R270 S1      
327GND              PC477_-2          A01X+144881Y+070147X0198Y0197R090 S1      
327GND              PC583_-2          A01X+154783Y+069860X0198Y0197R090 S1      
327GND              PC585_-2          A01X+155183Y+069860X0198Y0197R090 S1      
327GND              PU49  -40  M      A01X+156968Y+069250X0690Y0770R180 S1      
327GND              PU49  -7_9-M      A01X+156624Y+070205X0827Y2126R270 S1      
327GND              PU49  -5          A01X+157569Y+069565X0090Y0240R270 S1      
327GND              PU49  -2   M      A01X+157569Y+069034X0090Y0240R270 S1      
327GND              PU50  -7_9-M      A01X+159901Y+066828X0827Y2126R270 S1      
327GND              PC584_-2          A01X+158460Y+066500X0198Y0197R090 S1      
327GND              PC586_-2          A01X+158060Y+066500X0198Y0197R090 S1      
327GND              PR502 -2          A01X+158071Y+070278X0198Y0197R270 S1      
327GND              PC581_-2          A01X+158074Y+069911X0198Y0197R090 S1      
327GND              PR503 -2          A01X+161348Y+066901X0198Y0197R270 S1      
327GND              PU50  -40  M      A01X+160245Y+065874X0690Y0770R180 S1      
327GND              PU50  -5          A01X+160846Y+066188X0090Y0240R270 S1      
327GND              PU50  -2   M      A01X+160846Y+065657X0090Y0240R270 S1      
327GND              PC582_-2          A01X+161351Y+066534X0198Y0197R090 S1      
327GND              PR505 -2          A01X+164648Y+065001X0198Y0197R270 S1      
327GND              PL62  -1          A01X+166413Y+066508X0790Y1660R090 S1      
327GND              PR495 -2          A01X+144878Y+070514X0198Y0197R270 S1      
327GND              PC480_-2          A01X+145276Y+072048X0198Y0197R090 S1      
327GND              PU43  -40  M      A01X+147067Y+071444X0690Y0770R180 S1      
327GND              PU43  -7_9-M      A01X+146722Y+072399X0827Y2126R270 S1      
327GND              PU43  -5          A01X+147667Y+071759X0090Y0240R270 S1      
327GND              PU43  -2   M      A01X+147667Y+071228X0090Y0240R270 S1      
327GND              PC478_-2          A01X+148172Y+072105X0198Y0197R090 S1      
327GND              PU46  -40  M      A01X+150375Y+071461X0690Y0770R180 S1      
327GND              PU46  -7_9-M      A01X+150031Y+072416X0827Y2126R270 S1      
327GND              PU46  -5          A01X+150976Y+071776X0090Y0240R270 S1      
327GND              PU46  -2   M      A01X+150976Y+071245X0090Y0240R270 S1      
327GND              PC550_-2          A01X+148590Y+072071X0198Y0197R090 S1      
327GND              PC553_-2          A01X+151870Y+072071X0198Y0197R090 S1      
327GND              PC548_-2          A01X+151481Y+072105X0198Y0197R090 S1      
327GND              PU47  -40  M      A01X+153655Y+071444X0690Y0770R180 S1      
327GND              PU47  -7_9-M      A01X+153311Y+072399X0827Y2126R270 S1      
327GND              PU47  -5          A01X+154256Y+071759X0090Y0240R270 S1      
327GND              PU47  -2   M      A01X+154256Y+071228X0090Y0240R270 S1      
327GND              PC549_-2          A01X+154761Y+072105X0198Y0197R090 S1      
327GND              PL63  -3          A01X+156711Y+073883X0540Y1780R090 S1      
327GND              PR359 -1          A01X+160257Y+064324X0198Y0197     S1      
327GND              PC578_-2          A01X+160961Y+064306X0198Y0197R270 S1      
327GND              PC580 -2          A01X+161351Y+065169X0198Y0197R270 S1      
327GND              PC545_-2          A01X+154371Y+069876X0198Y0197R270 S1      
327GND              PC547 -2          A01X+154761Y+070740X0198Y0197R270 S1      
327GND              PR358 -1          A01X+156980Y+067701X0198Y0197     S1      
327GND              PC577_-2          A01X+157684Y+067682X0198Y0197R270 S1      
327GND              PC546 -2          A01X+151481Y+070740X0198Y0197R270 S1      
327GND              PC476 -2          A01X+148172Y+070740X0198Y0197R270 S1      
327GND              PC475 -2          A01X+144881Y+068782X0198Y0197R270 S1      
327GND              PC567 -2          A01X+141621Y+065524X0198Y0197R270 S1      
327GND              PC151 -2          A01X+138351Y+062234X0198Y0197R270 S1      
317GND              VIA   -    MD0100PA00X+140245Y+064282X0200Y         S0      
327GND              PC570_-2          A01X+139983Y+064276X0198Y0197     S1      
317GND              VIA   -    MD0100PA00X+140268Y+064706X0200Y    R180 S0      
317GND              VIA   -    M      A01X+141482Y+064703X0200Y    R180 S2      
017GND              VIA   -    M      A18X+141482Y+064703X0260Y    R180 S2      
017GND                    -    MD0100PA00X+141482Y+064703                       
327GND              PR353 -1          A01X+140527Y+064679X0198Y0197     S1      
327GND              PC566_-2          A01X+141231Y+064661X0198Y0197R270 S1      
327GND              PR295 -2          A01X+134634Y+067444X0198Y0197     S1      
327GND              PC497 -2   M      A01X+135077Y+067459X0198Y0197R270 S1      
317GND              VIA   -    MD0100PA00X+135426Y+067576X0200Y         S0      
327GND              PC479_-2          A01X+143383Y+067576X0198Y0197     S1      
327GND              PR320 -1          A01X+143787Y+067937X0198Y0197     S1      
327GND              PC473_-2          A01X+144491Y+067919X0198Y0197R270 S1      
317GND              VIA   -    MD0100PA00X+143626Y+067626X0200Y    R180 S0      
317GND              VIA   -    MD0100PA00X+143528Y+067964X0200Y    R180 S0      
317GND              VIA   -    M      A01X+144742Y+067961X0200Y    R180 S2      
017GND              VIA   -    M      A18X+144742Y+067961X0260Y    R180 S2      
017GND                    -    MD0100PA00X+144742Y+067961                       
317GND              VIA   -    MD0100PA00X+146820Y+069922X0200Y    R180 S0      
317GND              VIA   -    MD0100PA00X+146826Y+069626X0200Y         S0      
327GND              PC482_-2          A01X+146533Y+069526X0198Y0197     S1      
327GND              PR321 -1          A01X+147079Y+069895X0198Y0197     S1      
317GND              VIA   -    MD0100PA00X+150128Y+069922X0200Y    R180 S0      
327GND              PR346 -1          A01X+150387Y+069895X0198Y0197     S1      
327GND              PC571_-2          A18X+139692Y+064898X0400Y0500R270 S2      
327GND              PC157_-2          A18X+136403Y+061609X0400Y0500R270 S2      
327GND              PC554_-2          A18X+149562Y+070114X0400Y0500R270 S2      
327GND              PC483_-2          A18X+142948Y+068161X0400Y0500R270 S2      
327GND              PC484_-2          A18X+146319Y+070120X0400Y0500R270 S2      
317GND              H53   -1   MD1470PA00X+166489Y+064297X2440Y         S3      
317GND              H38   -1   MD1470PA00X+153355Y+068234X2440Y         S3      
317GND              VIA   -    MD0100PA00X+145628Y+058098X0200Y    R180 S0      
327GND              PR283 -2          A18X+145868Y+058098X0198Y0197     S2      
317GND              VIA   -    MD0100PA00X+145628Y+057698X0200Y    R180 S0      
327GND              C298  -2          A18X+145868Y+057698X0198Y0197     S2      
327GND              R8286 -2          A01X+145868Y+057698X0198Y0197R180 S1      
317GND              VIA   -    MD0100PA00X+145628Y+057298X0200Y    R180 S0      
327GND              C302  -2          A18X+145868Y+057298X0198Y0197     S2      
327GND              C223  -2          A01X+154270Y+056516X0198Y0197R090 S1      
317GND              VIA   -    MD0100PA00X+154596Y+056516X0200Y         S0      
317GND              VIA   -    MD0100PA00X+151626Y+055998X0200Y    R180 S0      
327GND              PC472 -2          A18X+151383Y+055998X0198Y0197R180 S2      
317GND              VIA   -    MD0100PA00X+151636Y+055532X0200Y    R180 S0      
327GND              PC469 -2   M      A18X+151383Y+055598X0198Y0197R180 S2      
327GND              PC462 -2   M      A18X+151383Y+055198X0198Y0197R180 S2      
327GND              PC7   -2          A18X+151383Y+054798X0198Y0197R180 S2      
317GND              VIA   -    MD0100PA00X+146426Y+056498X0200Y         S0      
327GND              PC466 -2          A18X+146668Y+056098X0198Y0197     S2      
327GND              C465  -2   M      A18X+146668Y+056498X0198Y0197     S2      
317GND              VIA   -    MD0100PA00X+145628Y+056898X0200Y    R180 S0      
327GND              C299  -2          A18X+145868Y+056898X0198Y0197     S2      
327GND              U29   -2          A01X+154268Y+054734X0140Y0440     S1      
317GND              VIA   -    MD0100PA00X+154290Y+054364X0200Y         S0      
317GND              VIA   -    MD0100PA00X+151993Y+054347X0200Y    R180 S0      
327GND              PR599 -2          A01X+151383Y+054398X0198Y0197     S1      
317GND              VIA   -    MD0100PA00X+148226Y+056798X0200Y         S0      
317GND              VIA   -    MD0100PA00X+149726Y+056798X0200Y         S0      
317GND              VIA   -    MD0100PA00X+148976Y+056798X0200Y         S0      
317GND              VIA   -    MD0100PA00X+148226Y+056048X0200Y         S0      
317GND              VIA   -    MD0100PA00X+148226Y+055298X0200Y         S0      
317GND              VIA   -    MD0100PA00X+149726Y+056048X0200Y         S0      
317GND              VIA   -    MD0100PA00X+149726Y+055298X0200Y         S0      
317GND              VIA   -    MD0100PA00X+148976Y+055298X0200Y         S0      
327GND              PU42  -TH  M      A18X+148976Y+056048X1740Y1740R270 S2      
327GND              PR5   -2          A01X+150068Y+055648X0198Y0197R180 S1      
327GND              PR292 -2          A01X+150078Y+056168X0198Y0197R180 S1      
327GND              R702  -2          A01X+153969Y+053804X0198Y0197R270 S1      
317GND              VIA   -    MD0100PA00X+153969Y+053521X0200Y         S0      
317GND              VIA   -    MD0100PA00X+151276Y+053748X0200Y         S0      
327GND              PC471 -2          A18X+151276Y+053990X0198Y0197R090 S2      
317GND              VIA   -    MD0100PA00X+150876Y+053746X0200Y         S0      
327GND              PC12  -2          A18X+150876Y+053990X0198Y0197R090 S2      
317GND              VIA   -    MD0100PA00X+150476Y+053738X0200Y         S0      
327GND              PC470 -2          A18X+150476Y+053990X0198Y0197R090 S2      
317GND              VIA   -    MD0100PA00X+150076Y+053744X0200Y         S0      
327GND              PC13  -2          A18X+150076Y+053990X0198Y0197R090 S2      
317GND              VIA   -    MD0100PA00X+144355Y+053932X0200Y         S0      
327GND              PQ17  -S          A18X+144349Y+054599X0400Y0560     S2      
327GND              C461  -2   M      A18X+144595Y+053932X0198Y0197     S2      
317GND              VIA   -    MD0100PA00X+165196Y+068980X0200Y    R180 S0      
327GND              PC599 -2   M      A01X+165196Y+069267X0198Y0197R270 S1      
327GND              PR297 -2          A01X+165657Y+069233X0198Y0197R180 S1      
317GND              J16   -G1  MD0480PA00X+163157Y+073459X0680Y1370R090 S3      
327GND              PC111 -2          A01X+132701Y+053348X0400Y0500R180 S1      
327GND              PC81  -2          A01X+132701Y+052658X0400Y0500R180 S1      
317GND              VIA   -    MD0100PA00X+133076Y+053545X0200Y    R270 S0      
317GND              VIA   -    MD0100PA00X+133077Y+053178X0200Y    R270 S0      
317GND              VIA   -    M      A01X+133082Y+052516X0200Y    R270 S2      
017GND              VIA   -    M      A18X+133082Y+052516X0260Y    R270 S2      
017GND                    -    MD0100PA00X+133082Y+052516                       
317GND              VIA   -    MD0100PA00X+133076Y+052865X0200Y    R270 S0      
327GND              PU57  -11_1       A01X+132555Y+055353X0315Y1240     S1      
327GND              PC227 -2          A01X+132701Y+054038X0400Y0500R180 S1      
317GND              VIA   -    MD0100PA00X+133267Y+054931X0200Y    R270 S0      
317GND              VIA   -    MD0100PA00X+133267Y+054591X0200Y    R270 S0      
317GND              VIA   -    MD0100PA00X+133066Y+054295X0200Y    R270 S0      
317GND              VIA   -    MD0100PA00X+132967Y+054931X0200Y    R270 S0      
317GND              VIA   -    MD0100PA00X+132967Y+054591X0200Y    R270 S0      
317GND              VIA   -    MD0100PA00X+132667Y+054491X0200Y    R270 S0      
317GND              VIA   -    M      A01X+133066Y+053875X0200Y    R270 S2      
017GND              VIA   -    M      A18X+133066Y+053875X0260Y    R270 S2      
017GND                    -    MD0100PA00X+133066Y+053875                       
327GND              PC212 -2          A01X+133236Y+055862X0198Y0197R270 S1      
317GND              VIA   -    MD0100PA00X+133267Y+055251X0200Y    R270 S0      
317GND              VIA   -    MD0100PA00X+133267Y+055571X0200Y    R270 S0      
317GND              VIA   -    MD0100PA00X+132967Y+055251X0200Y    R270 S0      
317GND              VIA   -    MD0100PA00X+132967Y+055571X0200Y    R270 S0      
317GND              VIA   -    MD0100PA00X+132967Y+055871X0200Y    R270 S0      
317GND              VIA   -    MD0100PA00X+129553Y+053951X0200Y    R180 S0      
327GND              C674  -2          A01X+129716Y+054163X0198Y0197R180 S1      
327GND              PR448 -2   M      A01X+130415Y+056021X0198Y0197R180 S1      
317GND              VIA   -    MD0100PA00X+130167Y+055541X0200Y    R180 S0      
317GND              VIA   -    MD0100PA00X+130777Y+056301X0200Y    R090 S0      
327GND              PC258 -2          A01X+130069Y+055281X0198Y0197R180 S1      
327GND              PU57  -2          A01X+131541Y+055933X0070Y0320R090 S1      
327GND              PR417 -1   M      A01X+130418Y+055654X0198Y0197     S1      
317GND              VIA   -    M      A01X+131627Y+056451X0200Y    R270 S2      
017GND              VIA   -    M      A18X+131627Y+056451X0260Y    R270 S2      
017GND                    -    MD0100PA00X+131627Y+056451                       
327GND              PC237 -2   M      A01X+131627Y+056715X0198Y0197R180 S1      
317GND              VIA   -    MD0100PA00X+129749Y+059061X0200Y         S0      
317GND              H54   -1   MD1470PA00X+137028Y+058230X2440Y         S3      
317GND              PC492 -2   MD0400PA00X+142553Y+060123X0600Y    R090 S3      
317GND              PC491 -2   MD0400PA00X+148768Y+064999X0600Y    R180 S3      
317GND              PC596 -2   MD0400PA00X+152444Y+065021X0600Y    R180 S3      
317GND              J69   -G1  MD0480PA00X+166127Y+073459X0680Y1370R090 S3      
317GND              VIA   -    MD0100PA00X+104010Y+052951X0200Y    R180 S0      
327GND              C1105 -2          A01X+102020Y+053820X0198Y0197R270 S1      
317GND              VIA   -    MD0100PA00X+102269Y+053820X0200Y    R270 S0      
327GND              C1103 -2          A01X+103484Y+053820X0198Y0197R270 S1      
317GND              VIA   -    MD0100PA00X+103235Y+053820X0200Y    R270 S0      
327GND              U53   -10         A01X+100863Y+052994X0140Y0630R090 S1      
317GND              VIA   -    MD0100PA00X+101331Y+052894X0200Y    R270 S0      
327GND              C1104 -2          A18X+101331Y+052372X0198Y0197R270 S2      
317GND              VIA   -    MD0100PA00X+101331Y+052615X0200Y    R090 S0      
317GND              VIA   -    MD0100PA00X+099903Y+052857X0200Y    R180 S0      
317GND              VIA   -    MD0100PA00X+099103Y+052857X0200Y    R180 S0      
317GND              VIA   -    MD0100PA00X+084513Y+053014X0200Y         S0      
317GND              VIA   -    MD0100PA00X+084913Y+053014X0200Y         S0      
327GND              Q64   -S          A01X+085518Y+053084X0400Y0560R270 S1      
327GND              C345  -2          A01X+084876Y+052756X0198Y0197R090 S1      
317GND              VIA   -    MD0100PA00X+076050Y+053435X0200Y    R180 S0      
317GND              VIA   -    MD0100PA00X+076450Y+053442X0200Y    R180 S0      
317GND              VIA   -    MD0100PA00X+074764Y+053487X0200Y    R180 S0      
317GND              VIA   -    MD0100PA00X+073250Y+053386X0200Y    R180 S0      
317GND              VIA   -    MD0100PA00X+073650Y+053386X0200Y    R180 S0      
317GND              VIA   -    MD0100PA00X+072850Y+053386X0200Y    R180 S0      
327GND              R16   -2          A18X+070016Y+052470X0198Y0197     S2      
327GND              R17   -2          A01X+069650Y+052744X0198Y0197R090 S1      
317GND              VIA   -    MD0100PA00X+069650Y+052986X0200Y         S0      
327GND              C242  -2          A01X+037594Y+053412X0198Y0197R270 S1      
317GND              VIA   -    MD0100PA00X+037594Y+052490X0200Y         S0      
327GND              R6087 -2          A01X+038077Y+053406X0198Y0197R270 S1      
317GND              VIA   -    MD0100PA00X+038077Y+052490X0200Y         S0      
327GND              R4514 -2          A01X+014457Y+052700X0198Y0197     S1      
317GND              VIA   -    M      A01X+014698Y+052700X0200Y    R090 S2      
017GND              VIA   -    M      A18X+014698Y+052700X0260Y    R090 S2      
017GND                    -    MD0100PA00X+014698Y+052700                       
327GND              U248  -3          A01X+013081Y+052948X0400Y0150R180 S1      
317GND              VIA   -    M      A01X+013481Y+053096X0200Y         S2      
017GND              VIA   -    M      A18X+013481Y+053096X0260Y         S2      
017GND                    -    MD0100PA00X+013481Y+053096                       
317GND              VIA   -    MD0100PA00X+007779Y+053781X0200Y    R090 S0      
317GND              VIA   -    MD0100PA00X+007773Y+052676X0200Y    R090 S0      
327GND              C1883 -2          A18X+003936Y+053928X0400Y0500R180 S2      
317GND              VIA   -    MD0100PA00X+003640Y+052868X0200Y    R270 S0      
317GND              VIA   -    MD0100PA00X+137786Y+051105X0200Y         S0      
317GND              VIA   -    MD0100PA00X+103721Y+051094X0200Y    R090 S0      
317GND              VIA   -    MD0100PA00X+104125Y+052387X0200Y         S0      
327GND              R6098 -1          A01X+104283Y+052107X0198Y0197R180 S1      
317GND              VIA   -    MD0100PA00X+104525Y+052107X0200Y    R090 S0      
327GND              C1102 -2          A01X+101178Y+051030X0198Y0197     S1      
317GND              VIA   -    MD0100PA00X+101421Y+051030X0200Y    R090 S0      
317GND              VIA   -    MD0100PA00X+099806Y+052387X0200Y    R180 S0      
317GND              VIA   -    MD0100PA00X+099806Y+051821X0200Y    R180 S0      
327GND              PQ15  -S          A01X+038744Y+053240X0400Y0560R270 S1      
317GND              VIA   -    M      A01X+038744Y+052515X0200Y         S2      
017GND              VIA   -    M      A18X+038744Y+052515X0260Y         S2      
017GND                    -    MD0100PA00X+038744Y+052515                       
317GND              VIA   -    MD0100PA00X+022669Y+052245X0200Y         S0      
317GND              VIA   -    MD0100PA00X+022069Y+052245X0200Y         S0      
317GND              VIA   -    MD0100PA00X+012089Y+052122X0200Y    R270 S0      
327GND              C1882 -2          A01X+011841Y+052122X0198Y0197R270 S1      
317GND              VIA   -    MD0100PA00X+007779Y+052011X0200Y    R090 S0      
327GND              R4082 -2          A01X+001876Y+051695X0198Y0197R180 S1      
317GND              VIA   -    MD0100PA00X+001634Y+051695X0200Y    R270 S0      
327GND              C95   -2          A18X+005374Y+053169X0198Y0197R090 S2      
327GND              C97   -2          A18X+005765Y+052820X0198Y0197     S2      
327GND              C94   -2   M      A01X+003277Y+052580X0198Y0197R270 S1      
327GND              C1884 -2          A18X+006082Y+052122X0198Y0197R090 S2      
317GND              VIA   -    MD0100PA00X+005672Y+053112X0200Y         S0      
317GND              VIA   -    MD0100PA00X+005680Y+052422X0200Y         S0      
317GND              VIA   -    MD0100PA00X+004989Y+053115X0200Y         S0      
317GND              VIA   -    MD0100PA00X+004985Y+052421X0200Y         S0      
327GND              C2257 -2          A18X+004906Y+053398X0198Y0197R180 S2      
327GND              C1889 -2          A18X+004892Y+052830X0198Y0197R180 S2      
327GND              C1886 -2          A18X+004610Y+052345X0198Y0197R270 S2      
317GND              VIA   -    MD0100PA00X+002689Y+054180X0200Y    R270 S0      
317GND              VIA   -    MD0100PA00X+003326Y+054037X0200Y    R270 S0      
317GND              VIA   -    MD0100PA00X+001651Y+053316X0200Y    R270 S0      
317GND              VIA   -    MD0100PA00X+003318Y+052328X0200Y    R270 S0      
317GND              VIA   -    MD0100PA00X+002059Y+052397X0200Y    R270 S0      
327GND              C71   -2   M      A01X+003285Y+053762X0198Y0197R090 S1      
317GND              VIA   -    MD0100PA00X+108873Y+050936X0200Y         S0      
327GND              C10   -2          A01X+083074Y+049791X0198Y0197     S1      
317GND              VIA   -    MD0100PA00X+083074Y+050074X0200Y         S0      
327GND              R6143 -2          A01X+067246Y+048694X0198Y0197R180 S1      
327GND              R6144 -2   M      A01X+067271Y+049508X0198Y0197R180 S1      
317GND              VIA   -    MD0100PA00X+066996Y+049547X0200Y         S0      
327GND              R1441 -2          A01X+041598Y+050460X0198Y0197R090 S1      
317GND              VIA   -    MD0100PA00X+041598Y+050702X0200Y    R180 S0      
327GND              R1443 -2          A01X+040218Y+050468X0198Y0197R090 S1      
317GND              VIA   -    MD0100PA00X+040218Y+050710X0200Y    R180 S0      
317GND              VIA   -    MD0100PA00X+146840Y+048758X0200Y         S0      
317GND              VIA   -    MD0100PA00X+137786Y+048555X0200Y         S0      
317GND              VIA   -    MD0100PA00X+118954Y+048169X0200Y         S0      
317GND              VIA   -    MD0100PA00X+116311Y+048169X0200Y         S0      
327GND              R317  -2          A01X+116071Y+048169X0198Y0197     S1      
317GND              VIA   -    MD0100PA00X+114781Y+049232X0200Y         S0      
327GND              C106  -2          A01X+114781Y+048982X0198Y0197     S1      
327GND              R587  -2          A01X+109887Y+048939X0198Y0197R180 S1      
317GND              VIA   -    M      A01X+109647Y+048939X0200Y         S2      
017GND              VIA   -    M      A18X+109647Y+048939X0260Y         S2      
017GND                    -    MD0100PA00X+109647Y+048939                       
327GND              R319  -2          A01X+109887Y+048439X0198Y0197R180 S1      
317GND              VIA   -    M      A01X+109647Y+048439X0200Y         S2      
017GND              VIA   -    M      A18X+109647Y+048439X0260Y         S2      
017GND                    -    MD0100PA00X+109647Y+048439                       
317GND              VIA   -    MD0100PA00X+105906Y+049254X0200Y    R270 S0      
327GND              C2056 -2          A01X+105906Y+049004X0198Y0197     S1      
317GND              VIA   -    MD0100PA00X+100879Y+049366X0200Y         S0      
327GND              R3709 -2          A01X+101119Y+049366X0198Y0197R180 S1      
317GND              VIA   -    MD0100PA00X+100879Y+048864X0200Y         S0      
327GND              R3707 -2          A01X+101119Y+048864X0198Y0197R180 S1      
317GND              VIA   -    MD0100PA00X+099204Y+048537X0200Y         S0      
327GND              U75   -3          A01X+082159Y+048650X0140Y0490R090 S1      
317GND              VIA   -    MD0100PA00X+081743Y+048723X0200Y         S0      
327GND              R6115 -2          A18X+077853Y+049164X0198Y0197R180 S2      
317GND              VIA   -    MD0100PA00X+078124Y+048957X0200Y    R180 S0      
327GND              U18   -AB22       A01X+076347Y+048604X0160Y    R090 S1      
317GND              VIA   -    MD0100PA00X+076501Y+048757X0180Y    R090 S0      
327GND              U18   -V21        A01X+075087Y+048288X0160Y    R090 S1      
317GND              VIA   -    MD0100PA00X+075241Y+048442X0180Y    R090 S0      
327GND              U18   -K21        A01X+072568Y+048288X0160Y    R090 S1      
317GND              VIA   -    MD0100PA00X+072414Y+048442X0180Y    R090 S0      
327GND              U18   -N21        A01X+073513Y+048288X0160Y    R090 S1      
317GND              VIA   -    MD0100PA00X+073666Y+048442X0180Y    R090 S0      
327GND              U18   -F21        A01X+071308Y+048288X0160Y    R090 S1      
317GND              VIA   -    MD0100PA00X+071154Y+048442X0180Y    R090 S0      
327GND              U18   -A22        A01X+069733Y+048604X0160Y    R090 S1      
317GND              VIA   -    MD0100PA00X+069580Y+048757X0180Y    R090 S0      
317GND              VIA   -    MD0100PA00X+062131Y+048335X0200Y         S0      
327GND              U325  -S          A01X+061622Y+048335X0400Y0560R090 S1      
317GND              VIA   -    MD0100PA00X+043234Y+049430X0200Y    R270 S0      
327GND              Q27   -1          A01X+043234Y+049032X0120Y0490     S1      
327GND              Q19   -1          A01X+041854Y+049040X0120Y0490     S1      
317GND              VIA   -    MD0100PA00X+041854Y+049437X0200Y    R270 S0      
327GND              Q18   -1          A01X+040474Y+049048X0120Y0490     S1      
317GND              VIA   -    MD0100PA00X+040474Y+049445X0200Y    R270 S0      
327GND              U38   -2          A01X+038718Y+049106X0160Y0360     S1      
317GND              VIA   -    MD0100PA00X+038718Y+049438X0200Y    R270 S0      
317GND              VIA   -    MD0100PA00X+014164Y+049143X0200Y    R180 S0      
327GND              R710  -2          A01X+125802Y+046437X0198Y0197     S1      
317GND              VIA   -    M      A01X+125702Y+046725X0200Y         S2      
017GND              VIA   -    M      A18X+125702Y+046725X0260Y         S2      
017GND                    -    MD0100PA00X+125702Y+046725                       
327GND              C629  -2          A01X+124890Y+046815X0198Y0197     S1      
317GND              VIA   -    M      A01X+124890Y+047073X0200Y         S2      
017GND              VIA   -    M      A18X+124890Y+047073X0260Y         S2      
017GND                    -    MD0100PA00X+124890Y+047073                       
327GND              R722  -2          A01X+118847Y+047039X0198Y0197R180 S1      
317GND              VIA   -    MD0100PA00X+118571Y+047039X0200Y         S0      
317GND              VIA   -    MD0100PA00X+108700Y+047750X0200Y         S0      
317GND              VIA   -    MD0100PA00X+108113Y+046152X0200Y         S0      
317GND              VIA   -    MD0100PA00X+107124Y+047966X0200Y         S0      
327GND              R3704 -2          A01X+106884Y+047966X0198Y0197     S1      
317GND              VIA   -    MD0100PA00X+088856Y+046953X0200Y         S0      
327GND              R804  -2          A01X+079273Y+047134X0198Y0197     S1      
317GND              VIA   -    MD0100PA00X+079725Y+047134X0200Y         S0      
327GND              U18   -Y16        A01X+075717Y+046714X0160Y    R090 S1      
317GND              VIA   -    MD0100PA00X+075871Y+046867X0180Y    R090 S0      
327GND              U18   -L18        A01X+072883Y+047344X0160Y    R090 S1      
317GND              VIA   -    MD0100PA00X+072729Y+047497X0180Y    R090 S0      
327GND              U18   -B16        A01X+070048Y+046714X0160Y    R090 S1      
317GND              VIA   -    MD0100PA00X+069895Y+046867X0180Y    R090 S0      
327GND              U18   -E18        A01X+070993Y+047344X0160Y    R090 S1      
317GND              VIA   -    MD0100PA00X+070840Y+047497X0180Y    R090 S0      
327GND              R891  -2          A18X+067242Y+046586X0198Y0197     S2      
317GND              VIA   -    MD0100PA00X+067000Y+046584X0200Y    R270 S0      
327GND              C1209 -2          A18X+064749Y+047914X0198Y0197R180 S2      
317GND              VIA   -    MD0100PA00X+065027Y+047914X0200Y         S0      
317GND              VIA   -    MD0100PA00X+063300Y+047831X0200Y         S0      
327GND              R2227 -2          A01X+063300Y+047402X0198Y0197     S1      
317GND              VIA   -    MD0100PA00X+062192Y+046509X0200Y         S0      
327GND              U206  -2          A01X+061720Y+046509X0250Y0480R270 S1      
317GND              VIA   -    MD0100PA00X+058781Y+047435X0200Y         S0      
327GND              R2222 -2          A01X+059043Y+047435X0198Y0197R180 S1      
317GND              VIA   -    MD0100PA00X+042722Y+047896X0200Y    R090 S0      
327GND              Q27   -4          A01X+042722Y+048294X0120Y0490     S1      
327GND              Q19   -4          A01X+041342Y+048302X0120Y0490     S1      
317GND              VIA   -    MD0100PA00X+041342Y+047904X0200Y    R090 S0      
327GND              Q18   -4          A01X+039962Y+048309X0120Y0490     S1      
317GND              VIA   -    MD0100PA00X+039962Y+047912X0200Y    R090 S0      
327GND              C347  -2          A01X+038718Y+047292X0198Y0197R270 S1      
317GND              VIA   -    MD0100PA00X+038718Y+047050X0200Y         S0      
327GND              C5014 -2          A01X+038218Y+047193X0198Y0197R090 S1      
317GND              VIA   -    MD0100PA00X+038467Y+047193X0200Y    R090 S0      
317GND              VIA   -    MD0100PA00X+145968Y+045037X0200Y         S0      
317GND              VIA   -    MD0100PA00X+141400Y+046036X0200Y         S0      
317GND              VIA   -    MD0100PA00X+140350Y+045838X0200Y         S0      
327GND              U64   -4          A01X+121787Y+045538X0350Y0500R270 S1      
317GND              VIA   -    M      A01X+121387Y+045538X0200Y         S2      
017GND              VIA   -    M      A18X+121387Y+045538X0260Y         S2      
017GND                    -    MD0100PA00X+121387Y+045538                       
327GND              R714  -2          A01X+118835Y+046020X0198Y0197R180 S1      
317GND              VIA   -    MD0100PA00X+118571Y+046020X0200Y         S0      
327GND              R718  -2          A01X+118841Y+046527X0198Y0197R180 S1      
317GND              VIA   -    M      A01X+118571Y+046527X0200Y         S2      
017GND              VIA   -    M      A18X+118571Y+046527X0260Y         S2      
017GND                    -    MD0100PA00X+118571Y+046527                       
327GND              U36   -12         A01X+111861Y+045524X0120Y0630R270 S1      
317GND              VIA   -    MD0100PA00X+111394Y+045206X0200Y         S0      
327GND              U39   -12         A01X+102904Y+045524X0120Y0630R270 S1      
317GND              VIA   -    MD0100PA00X+102776Y+045183X0200Y         S0      
317GND              VIA   -    MD0100PA00X+087388Y+045338X0200Y         S0      
327GND              R136  -2          A01X+083698Y+045958X0198Y0197R180 S1      
317GND              VIA   -    MD0100PA00X+083425Y+045958X0200Y         S0      
327GND              R6114 -2          A01X+080636Y+045534X0198Y0197R180 S1      
327GND              R3    -2          A18X+079340Y+046052X0198Y0197R180 S2      
327GND              R800  -2          A01X+079273Y+045934X0198Y0197     S1      
317GND              VIA   -    MD0100PA00X+079725Y+045934X0200Y         S0      
327GND              U18   -W12        A01X+075402Y+045454X0160Y    R090 S1      
317GND              VIA   -    MD0100PA00X+075556Y+045607X0180Y    R090 S0      
327GND              U18   -C11        A01X+070363Y+045139X0160Y    R090 S1      
317GND              VIA   -    MD0100PA00X+070210Y+044985X0180Y    R090 S0      
327GND              R889  -2          A18X+067242Y+045786X0198Y0197     S2      
317GND              VIA   -    MD0100PA00X+067000Y+045784X0200Y         S0      
327GND              R6141 -2   M      A01X+064294Y+045775X0198Y0197R180 S1      
327GND              R6142 -2          A01X+064305Y+046185X0198Y0197R180 S1      
317GND              VIA   -    MD0100PA00X+063750Y+045435X0200Y         S0      
327GND              R6145 -2          A18X+064553Y+044494X0198Y0197     S2      
317GND              VIA   -    MD0100PA00X+059443Y+046360X0200Y         S0      
327GND              C1561 -2          A01X+059692Y+046435X0198Y0197R180 S1      
327GND              C1    -2          A01X+124003Y+044726X0198Y0197     S1      
317GND              VIA   -    MD0100PA00X+124243Y+044726X0200Y    R180 S0      
327GND              R44   -2          A01X+124003Y+044326X0198Y0197     S1      
317GND              VIA   -    M      A01X+124243Y+044326X0200Y    R180 S2      
017GND              VIA   -    M      A18X+124243Y+044326X0260Y    R180 S2      
017GND                    -    MD0100PA00X+124243Y+044326                       
327GND              R69   -2          A01X+118835Y+044820X0198Y0197R180 S1      
317GND              VIA   -    M      A01X+118595Y+044820X0200Y         S2      
017GND              VIA   -    M      A18X+118595Y+044820X0260Y         S2      
017GND                    -    MD0100PA00X+118595Y+044820                       
327GND              R62   -2          A01X+118835Y+044020X0198Y0197R180 S1      
317GND              VIA   -    M      A01X+118595Y+044020X0200Y         S2      
017GND              VIA   -    M      A18X+118595Y+044020X0260Y         S2      
017GND                    -    MD0100PA00X+118595Y+044020                       
317GND              VIA   -    MD0100PA00X+104502Y+044440X0200Y         S0      
317GND              VIA   -    M      A01X+079633Y+043934X0200Y    R180 S2      
017GND              VIA   -    M      A18X+079633Y+043934X0260Y    R180 S2      
017GND                    -    MD0100PA00X+079633Y+043934                       
327GND              C5001 -2          A01X+079273Y+043934X0198Y0197     S1      
327GND              U18   -Y7         A01X+075717Y+043879X0160Y    R090 S1      
317GND              VIA   -    MD0100PA00X+075871Y+043726X0180Y    R090 S0      
327GND              U18   -R8         A01X+074143Y+044194X0160Y    R090 S1      
327GND              U18   -P10        A01X+073828Y+044824X0160Y    R090 S1      
327GND              U18   -P9         A01X+073828Y+044509X0160Y    R090 S1      
327GND              U18   -P14        A01X+073828Y+046084X0160Y    R090 S1      
327GND              U18   -P13        A01X+073828Y+045769X0160Y    R090 S1      
327GND              U18   -P12        A01X+073828Y+045454X0160Y    R090 S1      
327GND              U18   -P11        A01X+073828Y+045139X0160Y    R090 S1      
327GND              U18   -R15        A01X+074143Y+046399X0160Y    R090 S1      
327GND              U18   -K9         A01X+072568Y+044509X0160Y    R090 S1      
327GND              U18   -L9         A01X+072883Y+044509X0160Y    R090 S1      
327GND              C359  -2   M      A18X+072572Y+044513X0164Y0164R090 S2      
327GND              U18   -L10        A01X+072883Y+044824X0160Y    R090 S1      
327GND              U18   -M9         A01X+073198Y+044509X0160Y    R090 S1      
327GND              C358  -2   M      A18X+073509Y+044513X0164Y0164R090 S2      
327GND              U18   -M10        A01X+073198Y+044824X0160Y    R090 S1      
327GND              C1175 -2   M      A18X+073824Y+044198X0164Y0164R180 S2      
327GND              U18   -N9         A01X+073513Y+044509X0160Y    R090 S1      
327GND              U18   -N14        A01X+073513Y+046084X0160Y    R090 S1      
327GND              U18   -M14        A01X+073198Y+046084X0160Y    R090 S1      
327GND              C1174 -2   M      A18X+072572Y+046080X0164Y0164R270 S2      
327GND              U18   -L13        A01X+072883Y+045769X0160Y    R090 S1      
327GND              U18   -M13        A01X+073198Y+045769X0160Y    R090 S1      
327GND              U18   -L14        A01X+072883Y+046084X0160Y    R090 S1      
327GND              U18   -K14        A01X+072568Y+046084X0160Y    R090 S1      
327GND              C1172 -2   M      A18X+071942Y+045765X0164Y0164R180 S2      
327GND              U18   -H13        A01X+071938Y+045769X0160Y    R090 S1      
327GND              U18   -J12        A01X+072253Y+045454X0160Y    R090 S1      
327GND              U18   -J13        A01X+072253Y+045769X0160Y    R090 S1      
327GND              U18   -J14        A01X+072253Y+046084X0160Y    R090 S1      
327GND              C1129 -2   M      A18X+071942Y+046395X0164Y0164     S2      
327GND              U18   -J11        A01X+072253Y+045139X0160Y    R090 S1      
327GND              U18   -H15        A01X+071938Y+046399X0160Y    R090 S1      
327GND              C1127 -2   M      A18X+071942Y+044198X0164Y0164R270 S2      
327GND              U18   -H8         A01X+071938Y+044194X0160Y    R090 S1      
327GND              C357  -2   M      A18X+071942Y+044828X0164Y0164R180 S2      
327GND              U18   -H10        A01X+071938Y+044824X0160Y    R090 S1      
327GND              U18   -J10        A01X+072253Y+044824X0160Y    R090 S1      
327GND              U18   -J9         A01X+072253Y+044509X0160Y    R090 S1      
317GND              VIA   -    MD0100PA00X+074296Y+046552X0180Y    R090 S0      
317GND              VIA   -    MD0100PA00X+074296Y+044040X0180Y    R090 S0      
317GND              VIA   -    MD0100PA00X+073981Y+044670X0180Y    R090 S0      
317GND              VIA   -    MD0100PA00X+073981Y+044356X0180Y    R090 S0      
317GND              VIA   -    MD0100PA00X+073981Y+046237X0180Y    R090 S0      
317GND              VIA   -    MD0100PA00X+073981Y+045922X0180Y    R090 S0      
317GND              VIA   -    MD0100PA00X+073981Y+045607X0180Y    R090 S0      
317GND              VIA   -    MD0100PA00X+073981Y+044985X0180Y    R090 S0      
317GND              VIA   -    MD0100PA00X+072414Y+044356X0180Y    R090 S0      
317GND              VIA   -    MD0100PA00X+072729Y+044356X0180Y    R090 S0      
317GND              VIA   -    MD0100PA00X+072729Y+044670X0180Y    R090 S0      
317GND              VIA   -    MD0100PA00X+073351Y+044356X0180Y    R090 S0      
317GND              VIA   -    MD0100PA00X+073351Y+044670X0180Y    R090 S0      
317GND              VIA   -    MD0100PA00X+073666Y+044356X0180Y    R090 S0      
317GND              VIA   -    MD0100PA00X+073666Y+046237X0180Y    R090 S0      
317GND              VIA   -    MD0100PA00X+073351Y+046237X0180Y    R090 S0      
317GND              VIA   -    MD0100PA00X+072729Y+045922X0180Y    R090 S0      
317GND              VIA   -    MD0100PA00X+073351Y+045922X0180Y    R090 S0      
317GND              VIA   -    MD0100PA00X+072729Y+046237X0180Y    R090 S0      
317GND              VIA   -    MD0100PA00X+072414Y+046237X0180Y    R090 S0      
317GND              VIA   -    MD0100PA00X+071784Y+045922X0180Y    R090 S0      
317GND              VIA   -    MD0100PA00X+072099Y+045607X0180Y    R090 S0      
317GND              VIA   -    MD0100PA00X+072099Y+045922X0180Y    R090 S0      
317GND              VIA   -    MD0100PA00X+072099Y+046237X0180Y    R090 S0      
317GND              VIA   -    MD0100PA00X+072099Y+044985X0180Y    R090 S0      
317GND              VIA   -    MD0100PA00X+071784Y+046552X0180Y    R090 S0      
317GND              VIA   -    MD0100PA00X+071784Y+044040X0180Y    R090 S0      
317GND              VIA   -    MD0100PA00X+071784Y+044670X0180Y    R090 S0      
317GND              VIA   -    MD0100PA00X+072099Y+044670X0180Y    R090 S0      
317GND              VIA   -    MD0100PA00X+072099Y+044356X0180Y    R090 S0      
327GND              U18   -B7         A01X+070048Y+043879X0160Y    R090 S1      
317GND              VIA   -    MD0100PA00X+069895Y+043726X0180Y    R090 S0      
317GND              VIA   -    MD0100PA00X+061508Y+044300X0200Y    R090 S0      
317GND              VIA   -    MD0100PA00X+006836Y+044368X0200Y         S0      
327GND              C5236 -2          A18X+006550Y+044368X0198Y0197R180 S2      
327GND              U5201 -10         A18X+005070Y+044299X0070Y0240R270 S2      
317GND              VIA   -    MD0100PA00X+005476Y+044499X0200Y         S0      
317GND              VIA   -    MD0100PA00X+005380Y+043545X0200Y         S0      
327GND              C5229 -2          A18X+005672Y+043545X0198Y0197R090 S2      
317GND              VIA   -    MD0100PA00X+005000Y+044911X0200Y    R180 S0      
317GND              VIA   -    MD0100PA00X+004502Y+044911X0200Y    R180 S0      
317GND              VIA   -    MD0100PA00X+003068Y+043814X0200Y         S0      
327GND              C5232 -2   M      A18X+003068Y+044113X0198Y0197     S2      
327GND              R5238 -2          A18X+003068Y+044552X0198Y0197     S2      
317GND              VIA   -    M      A01X+181887Y+042393X0200Y         S2      
017GND              VIA   -    M      A18X+181887Y+042393X0260Y         S2      
017GND                    -    MD0100PA00X+181887Y+042393                       
327GND              C592  -2          A01X+181887Y+042143X0198Y0197     S1      
317GND              VIA   -    MD0100PA00X+179547Y+042133X0200Y         S0      
327GND              U211  -2          A01X+179817Y+042133X0170Y0240R270 S1      
327GND              U1    -4          A01X+120518Y+043188X0350Y0500R270 S1      
317GND              VIA   -    M      A01X+120116Y+043188X0200Y         S2      
017GND              VIA   -    M      A18X+120116Y+043188X0260Y         S2      
017GND                    -    MD0100PA00X+120116Y+043188                       
327GND              R54   -2          A01X+118835Y+043220X0198Y0197R180 S1      
317GND              VIA   -    M      A01X+118595Y+043220X0200Y         S2      
017GND              VIA   -    M      A18X+118595Y+043220X0260Y         S2      
017GND                    -    MD0100PA00X+118595Y+043220                       
317GND              VIA   -    MD0100PA00X+109372Y+042796X0200Y         S0      
317GND              VIA   -    MD0100PA00X+107742Y+042192X0200Y         S0      
327GND              U148  -10         A01X+104042Y+042706X0140Y0630R090 S1      
317GND              VIA   -    MD0100PA00X+104510Y+042706X0200Y         S0      
327GND              C1823 -2          A01X+101028Y+043343X0198Y0197     S1      
317GND              VIA   -    MD0100PA00X+101336Y+043343X0200Y         S0      
327GND              U218  -3          A01X+099268Y+042089X0220Y0320R270 S1      
317GND              VIA   -    MD0100PA00X+099623Y+042444X0200Y         S0      
317GND              VIA   -    MD0100PA00X+081318Y+042269X0200Y         S0      
327GND              C5016 -2          A01X+080965Y+042269X0198Y0197     S1      
327GND              U18   -V2         A01X+075087Y+042304X0160Y    R090 S1      
317GND              VIA   -    MD0100PA00X+075241Y+042151X0180Y    R090 S0      
327GND              U18   -L2         A01X+072883Y+042304X0160Y    R090 S1      
317GND              VIA   -    MD0100PA00X+072729Y+042151X0180Y    R090 S0      
327GND              U18   -M4         A01X+073198Y+042934X0160Y    R090 S1      
317GND              VIA   -    MD0100PA00X+073351Y+042781X0180Y    R090 S0      
327GND              U18   -F2         A01X+071308Y+042304X0160Y    R090 S1      
317GND              VIA   -    MD0100PA00X+071154Y+042151X0180Y    R090 S0      
327GND              C352  -2          A18X+070880Y+041854X0198Y0197R090 S2      
327GND              U18   -C2         A01X+070363Y+042304X0160Y    R090 S1      
317GND              VIA   -    MD0100PA00X+070210Y+042151X0180Y    R090 S0      
327GND              U18   -E5         A01X+070993Y+043249X0160Y    R090 S1      
317GND              VIA   -    MD0100PA00X+070840Y+043096X0180Y    R090 S0      
317GND              VIA   -    MD0100PA00X+064467Y+042582X0200Y         S0      
327GND              R25   -2          A18X+064672Y+042786X0198Y0197R090 S2      
317GND              VIA   -    MD0100PA00X+059916Y+043221X0200Y    R090 S0      
327GND              U92   -3          A01X+059485Y+043221X0220Y0530R270 S1      
327GND              Q37   -1          A01X+057339Y+042139X0170Y0200R270 S1      
317GND              VIA   -    MD0100PA00X+057592Y+042139X0200Y         S0      
317GND              VIA   -    MD0100PA00X+058872Y+042395X0200Y    R090 S0      
327GND              R334  -2          A01X+058620Y+042395X0198Y0197     S1      
327GND              Q37   -4          A01X+056591Y+042651X0170Y0200R270 S1      
317GND              VIA   -    MD0100PA00X+056323Y+042651X0200Y         S0      
327GND              C5234 -2          A18X+006076Y+043538X0198Y0197R090 S2      
317GND              VIA   -    MD0100PA00X+006415Y+043497X0200Y         S0      
317GND              VIA   -    MD0100PA00X+006039Y+042781X0200Y    R180 S0      
317GND              VIA   -    MD0100PA00X+006538Y+042781X0200Y    R180 S0      
317GND              VIA   -    MD0100PA00X+004762Y+042166X0200Y    R090 S0      
317GND              VIA   -    MD0100PA00X+004518Y+042581X0200Y    R180 S0      
317GND              VIA   -    MD0100PA00X+005014Y+042581X0200Y    R180 S0      
317GND              VIA   -    M      A01X+181937Y+041043X0200Y         S2      
017GND              VIA   -    M      A18X+181937Y+041043X0260Y         S2      
017GND                    -    MD0100PA00X+181937Y+041043                       
327GND              C593  -2          A01X+181937Y+040793X0198Y0197     S1      
317GND              VIA   -    MD0100PA00X+179548Y+040806X0200Y         S0      
327GND              U8    -2          A01X+179818Y+040806X0170Y0240R270 S1      
317GND              VIA   -    MD0100PA00X+107742Y+041676X0200Y         S0      
317GND              VIA   -    MD0100PA00X+107742Y+041132X0200Y         S0      
327GND              C1506 -2          A01X+105809Y+040656X0198Y0197     S1      
317GND              VIA   -    MD0100PA00X+106146Y+040656X0200Y         S0      
327GND              C1509 -2          A01X+106932Y+040412X0198Y0197R090 S1      
327GND              C1508 -2          A01X+104367Y+040659X0198Y0197R180 S1      
317GND              VIA   -    MD0100PA00X+104089Y+040659X0200Y         S0      
317GND              VIA   -    MD0100PA00X+078081Y+041986X0200Y         S0      
327GND              C5002 -2          A01X+077824Y+041946X0198Y0197     S1      
327GND              U18   -AB1        A01X+076347Y+041989X0160Y    R090 S1      
317GND              VIA   -    MD0100PA00X+076501Y+041836X0180Y    R090 S0      
327GND              U18   -A1         A01X+069733Y+041989X0160Y    R090 S1      
317GND              VIA   -    MD0100PA00X+069580Y+041836X0180Y    R090 S0      
317GND              VIA   -    MD0100PA00X+067986Y+040932X0200Y         S0      
327GND              R12   -2          A01X+067562Y+040932X0198Y0197     S1      
327GND              R6150 -2          A18X+067560Y+040922X0198Y0197R180 S2      
327GND              R10   -2          A01X+068750Y+039644X0198Y0197R090 S1      
317GND              VIA   -    MD0100PA00X+068825Y+040563X0200Y         S0      
317GND              VIA   -    MD0100PA00X+066088Y+041259X0200Y         S0      
327GND              R6185 -2          A01X+066688Y+040833X0198Y0197R090 S1      
317GND              VIA   -    MD0100PA00X+063457Y+040785X0200Y    R090 S0      
317GND              VIA   -    MD0100PA00X+061094Y+041000X0200Y    R090 S0      
327GND              C1873 -2          A01X+061538Y+041000X0198Y0197R090 S1      
317GND              VIA   -    MD0100PA00X+060328Y+041974X0200Y    R180 S0      
317GND              VIA   -    MD0100PA00X+056843Y+041585X0200Y    R090 S0      
327GND              Q95   -1          A01X+056591Y+041585X0170Y0200R090 S1      
327GND              R4483 -2   M      A01X+006868Y+042375X0198Y0197     S1      
317GND              VIA   -    M      A01X+007177Y+042175X0200Y         S2      
017GND              VIA   -    M      A18X+007177Y+042175X0260Y         S2      
017GND                    -    MD0100PA00X+007177Y+042175                       
327GND              R4420 -2          A01X+006952Y+041708X0198Y0197R090 S1      
317GND              VIA   -    MD0100PA00X+006281Y+041868X0200Y    R180 S0      
317GND              VIA   -    MD0100PA00X+006283Y+040960X0200Y    R180 S0      
327GND              R4482 -2   M      A01X+005703Y+042375X0198Y0197R180 S1      
317GND              VIA   -    M      A01X+005382Y+042175X0200Y         S2      
017GND              VIA   -    M      A18X+005382Y+042175X0260Y         S2      
017GND                    -    MD0100PA00X+005382Y+042175                       
327GND              R4419 -2          A01X+005616Y+041708X0198Y0197R090 S1      
317GND              VIA   -    MD0100PA00X+004762Y+041261X0200Y    R090 S0      
317GND              VIA   -    M      A01X+182014Y+039805X0200Y         S2      
017GND              VIA   -    M      A18X+182014Y+039805X0260Y         S2      
017GND                    -    MD0100PA00X+182014Y+039805                       
327GND              C639  -2          A01X+182014Y+039555X0198Y0197     S1      
317GND              VIA   -    MD0100PA00X+112747Y+040479X0200Y         S0      
327GND              C1515 -2          A01X+112748Y+039802X0198Y0197     S1      
327GND              U151  -10         A01X+109711Y+039082X0140Y0630R090 S1      
317GND              VIA   -    MD0100PA00X+110194Y+039536X0200Y         S0      
317GND              VIA   -    MD0100PA00X+108358Y+039520X0200Y         S0      
327GND              C1507 -2          A01X+106924Y+039388X0198Y0197R270 S1      
317GND              VIA   -    MD0100PA00X+107480Y+039126X0200Y         S0      
327GND              U149  -10         A01X+104004Y+039136X0140Y0630R090 S1      
317GND              VIA   -    MD0100PA00X+103052Y+039136X0200Y         S0      
327GND              C1512 -2          A01X+102453Y+039773X0198Y0197     S1      
317GND              VIA   -    MD0100PA00X+102772Y+039773X0200Y         S0      
327GND              C1514 -2          A01X+100962Y+039899X0198Y0197R270 S1      
317GND              VIA   -    MD0100PA00X+100962Y+039612X0200Y         S0      
317GND              VIA   -    MD0100PA00X+067175Y+039794X0200Y         S0      
327GND              R6027 -2          A18X+067050Y+038794X0198Y0197R270 S2      
327GND              R6187 -2          A01X+066695Y+039811X0198Y0197R270 S1      
317GND              VIA   -    MD0100PA00X+064032Y+039108X0200Y    R090 S0      
317GND              VIA   -    MD0100PA00X+061798Y+039038X0200Y    R090 S0      
327GND              C1877 -2          A01X+061538Y+039038X0198Y0197R090 S1      
317GND              VIA   -    MD0100PA00X+061798Y+039858X0200Y    R090 S0      
327GND              R3297 -2          A01X+061538Y+039858X0198Y0197R270 S1      
317GND              VIA   -    MD0100PA00X+060052Y+040173X0200Y    R270 S0      
327GND              U239  -3          A01X+060324Y+040173X0170Y0240R270 S1      
317GND              VIA   -    MD0100PA00X+058198Y+040431X0200Y    R090 S0      
327GND              C2007 -2          A01X+057938Y+040431X0198Y0197R090 S1      
327GND              C1880 -2          A01X+057938Y+039038X0198Y0197R090 S1      
317GND              VIA   -    MD0100PA00X+058198Y+039038X0200Y    R090 S0      
317GND              VIA   -    MD0100PA00X+056221Y+040116X0200Y    R090 S0      
327GND              U259  -2          A01X+056591Y+040116X0140Y0440R270 S1      
327GND              R1289 -2          A01X+182308Y+038805X0198Y0197R180 S1      
317GND              VIA   -    M      A01X+182066Y+038805X0200Y         S2      
017GND              VIA   -    M      A18X+182066Y+038805X0260Y         S2      
017GND                    -    MD0100PA00X+182066Y+038805                       
317GND              VIA   -    M      A01X+180293Y+038529X0200Y         S2      
017GND              VIA   -    M      A18X+180293Y+038529X0260Y         S2      
017GND                    -    MD0100PA00X+180293Y+038529                       
327GND              U66   -3          A01X+180563Y+038529X0170Y0240R270 S1      
317GND              VIA   -    MD0100PA00X+113920Y+038570X0200Y         S0      
327GND              C1511 -2          A01X+113648Y+038570X0198Y0197     S1      
317GND              VIA   -    MD0100PA00X+113920Y+038053X0200Y         S0      
327GND              C1510 -2          A01X+113648Y+038053X0198Y0197     S1      
317GND              VIA   -    MD0100PA00X+107320Y+038342X0200Y    R090 S0      
317GND              VIA   -    MD0100PA00X+106883Y+038973X0200Y         S0      
317GND              VIA   -    MD0100PA00X+106814Y+038369X0200Y    R090 S0      
317GND              VIA   -    MD0100PA00X+105593Y+038549X0200Y    R090 S0      
327GND              U150  -10         A01X+098923Y+037900X0140Y0630R180 S1      
317GND              VIA   -    MD0100PA00X+098923Y+038931X0200Y         S0      
317GND              VIA   -    MD0100PA00X+083684Y+038200X0200Y         S0      
317GND              VIA   -    MD0100PA00X+069155Y+038683X0200Y         S0      
317GND              VIA   -    MD0100PA00X+061798Y+037958X0200Y    R090 S0      
327GND              C1878 -2          A01X+061538Y+037958X0198Y0197R090 S1      
317GND              VIA   -    MD0100PA00X+059821Y+037643X0200Y    R090 S0      
327GND              U244  -2          A01X+060191Y+037643X0140Y0440R270 S1      
317GND              VIA   -    MD0100PA00X+059821Y+038723X0200Y    R090 S0      
327GND              U243  -2          A01X+060191Y+038723X0140Y0440R270 S1      
327GND              C1879 -2          A01X+057938Y+037958X0198Y0197R090 S1      
317GND              VIA   -    MD0100PA00X+058198Y+037958X0200Y    R090 S0      
317GND              VIA   -    MD0100PA00X+056221Y+037643X0200Y    R090 S0      
327GND              U245  -2          A01X+056591Y+037643X0140Y0440R270 S1      
317GND              VIA   -    MD0100PA00X+056221Y+038723X0200Y    R090 S0      
327GND              U246  -2          A01X+056591Y+038723X0140Y0440R270 S1      
317GND              VIA   -    MD0100PA00X+055120Y+037765X0200Y    R180 S0      
317GND              VIA   -    M      A01X+008752Y+038650X0200Y         S2      
017GND              VIA   -    M      A18X+008752Y+038650X0260Y         S2      
017GND                    -    MD0100PA00X+008752Y+038650                       
327GND              R3665 -2          A01X+008495Y+038650X0198Y0197     S1      
327GND              U268  -TH  M      A01X+005537Y+039030X1400Y1400R270 S1      
317GND              VIA   -    MD0100PA00X+006134Y+038436X0200Y    R090 S0      
317GND              VIA   -    MD0100PA00X+006125Y+039614X0200Y    R090 S0      
317GND              VIA   -    MD0100PA00X+004925Y+039633X0200Y    R090 S0      
317GND              VIA   -    MD0100PA00X+004940Y+038439X0200Y    R090 S0      
327GND              C2034 -2          A18X+004867Y+038699X0198Y0197R180 S2      
327GND              C2032 -2          A18X+006224Y+038846X0198Y0197     S2      
327GND              C2039 -2          A18X+006540Y+038155X0198Y0197R090 S2      
327GND              C2040 -2          A18X+007000Y+038166X0198Y0197R090 S2      
327GND              C2033 -2          A18X+004883Y+039341X0198Y0197R180 S2      
327GND              C2038 -2          A18X+006224Y+039308X0198Y0197     S2      
327GND              C2031 -2          A18X+005374Y+039690X0198Y0197R090 S2      
327GND              C2035 -2          A18X+005754Y+039692X0198Y0197R090 S2      
317GND              VIA   -    MD0100PA00X+003369Y+038394X0200Y         S0      
317GND              VIA   -    MD0100PA00X+002677Y+039881X0200Y         S0      
317GND              VIA   -    MD0100PA00X+002134Y+038776X0200Y         S0      
317GND              VIA   -    MD0100PA00X+003652Y+039801X0200Y         S0      
317GND              VIA   -    M      A01X+002996Y+040100X0200Y         S2      
017GND              VIA   -    M      A18X+002996Y+040100X0260Y         S2      
017GND                    -    MD0100PA00X+002996Y+040100                       
327GND              C2029 -2   M      A01X+003652Y+039535X0198Y0197R090 S1      
317GND              VIA   -    MD0100PA00X+003923Y+039535X0200Y         S0      
327GND              C2030 -2   M      A01X+003660Y+038498X0198Y0197R270 S1      
317GND              VIA   -    MD0100PA00X+003941Y+038458X0200Y         S0      
327GND              R3653 -2   M      A01X+003291Y+040100X0198Y0197R180 S1      
327GND              R3232 -2          A01X+182731Y+036736X0198Y0197     S1      
317GND              VIA   -    MD0100PA00X+182973Y+036736X0200Y    R180 S0      
317GND              VIA   -    M      A01X+182031Y+037383X0200Y         S2      
017GND              VIA   -    M      A18X+182031Y+037383X0260Y         S2      
017GND                    -    MD0100PA00X+182031Y+037383                       
327GND              C1840 -2          A01X+182031Y+037133X0198Y0197     S1      
327GND              PD103 -A          A01X+165600Y+038560X0670Y0990R090 S1      
317GND              VIA   -    MD0100PA00X+165961Y+039473X0200Y         S0      
317GND              VIA   -    MD0100PA00X+165261Y+039473X0200Y         S0      
327GND              PC2157-2          A01X+165961Y+039713X0198Y0197R270 S1      
327GND              PR3846-1          A01X+165261Y+039713X0198Y0197R090 S1      
317GND              VIA   -    MD0100PA00X+166361Y+039473X0200Y         S0      
327GND              PR3844-2          A01X+166361Y+039713X0198Y0197R270 S1      
317GND              VIA   -    M      A01X+164214Y+041420X0200Y         S2      
017GND              VIA   -    M      A18X+164214Y+041420X0260Y         S2      
017GND                    -    MD0100PA00X+164214Y+041420                       
327GND              PC2159-2          A01X+164454Y+041420X0198Y0197R180 S1      
327GND              PU205 -3          A01X+165364Y+041026X0100Y0280     S1      
317GND              VIA   -    MD0100PA00X+165281Y+040740X0200Y         S0      
317GND              VIA   -    MD0100PA00X+170744Y+040704X0200Y    R270 S0      
317GND              VIA   -    MD0100PA00X+170444Y+040704X0200Y    R270 S0      
327GND              PU202 -B7         A01X+170110Y+040877X0090Y    R270 S1      
327GND              PU202 -A7         A01X+170307Y+040877X0090Y    R270 S1      
327GND              PC2089-2          A01X+171043Y+040759X0198Y0197R270 S1      
317GND              VIA   -    M      A01X+164711Y+043418X0200Y         S2      
017GND              VIA   -    M      A18X+164711Y+043418X0260Y         S2      
017GND                    -    MD0100PA00X+164711Y+043418                       
317GND              VIA   -    M      A01X+166111Y+043418X0200Y         S2      
017GND              VIA   -    M      A18X+166111Y+043418X0260Y         S2      
017GND                    -    MD0100PA00X+166111Y+043418                       
327GND              PC2162-2          A01X+166111Y+043178X0198Y0197R090 S1      
317GND              VIA   -    MD0100PA00X+168615Y+043416X0200Y    R270 S0      
327GND              PR3791-2   M      A01X+168615Y+043176X0198Y0197R090 S1      
317GND              VIA   -    MD0100PA00X+170462Y+043365X0200Y    R270 S0      
317GND              VIA   -    MD0100PA00X+169721Y+043366X0200Y    R270 S0      
317GND              VIA   -    MD0100PA00X+170112Y+043365X0200Y    R270 S0      
317GND              VIA   -    MD0100PA00X+169801Y+042406X0200Y    R270 S0      
317GND              VIA   -    MD0100PA00X+169791Y+042716X0200Y    R270 S0      
317GND              VIA   -    MD0100PA00X+171114Y+042594X0200Y    R270 S0      
317GND              VIA   -    MD0100PA00X+163680Y+043298X0200Y         S0      
317GND              VIA   -    MD0100PA00X+163980Y+043298X0200Y         S0      
317GND              VIA   -    MD0100PA00X+163680Y+042998X0200Y         S0      
317GND              VIA   -    MD0100PA00X+163980Y+042998X0200Y         S0      
317GND              VIA   -    MD0100PA00X+163680Y+042698X0200Y         S0      
317GND              VIA   -    MD0100PA00X+163980Y+042698X0200Y         S0      
317GND              VIA   -    MD0100PA00X+163680Y+043898X0200Y         S0      
317GND              VIA   -    MD0100PA00X+163980Y+043898X0200Y         S0      
317GND              VIA   -    MD0100PA00X+163680Y+043598X0200Y         S0      
317GND              VIA   -    MD0100PA00X+163980Y+043598X0200Y         S0      
317GND              VIA   -    MD0100PA00X+172550Y+038366X0200Y         S0      
327GND              C2015 -2          A01X+172550Y+038094X0198Y0197R090 S1      
317GND              VIA   -    MD0100PA00X+177052Y+036815X0200Y         S0      
327GND              R3617 -1          A01X+176800Y+036815X0198Y0197R180 S1      
317GND              VIA   -    M      A01X+177052Y+036415X0200Y         S2      
017GND              VIA   -    M      A18X+177052Y+036415X0260Y         S2      
017GND                    -    MD0100PA00X+177052Y+036415                       
327GND              R3616 -1          A01X+176800Y+036415X0198Y0197R180 S1      
317GND              VIA   -    MD0100PA00X+173266Y+037269X0200Y         S0      
327GND              U266  -TH  M      A01X+173499Y+037038X0670Y0670R180 S1      
317GND              VIA   -    MD0100PA00X+173726Y+036813X0200Y         S0      
317GND              VIA   -    MD0100PA00X+172540Y+037206X0200Y         S0      
327GND              U266  -10         A01X+172948Y+037137X0090Y0240R090 S1      
317GND              VIA   -    MD0100PA00X+172140Y+037446X0200Y         S0      
327GND              C2024 -2          A01X+172250Y+037194X0198Y0197R090 S1      
327GND              PU202 -C2         A01X+169913Y+041861X0090Y    R270 S1      
327GND              PU202 -B2         A01X+170110Y+041861X0090Y    R270 S1      
327GND              PC2091-2          A01X+167387Y+043122X0198Y0197R090 S1      
327GND              PC2163-2          A01X+166757Y+042133X0400Y0500R270 S1      
327GND              PC2081-2          A01X+167985Y+043517X0400Y0500R270 S1      
327GND              PC2093-1          A01X+169431Y+043173X0198Y0197R270 S1      
327GND              PR5481-2          A01X+170462Y+043125X0198Y0197R090 S1      
327GND              PR3780-2          A01X+170112Y+043125X0198Y0197R090 S1      
327GND              PU202 -C1         A01X+169913Y+042058X0090Y    R270 S1      
327GND              PC2086-2          A01X+171041Y+042352X0198Y0197R090 S1      
327GND              PC5328-2          A01X+171495Y+042434X0198Y0197R180 S1      
327GND              C1516 -2          A01X+100446Y+036346X0198Y0197R270 S1      
317GND              VIA   -    MD0100PA00X+100708Y+036346X0200Y         S0      
317GND              VIA   -    MD0100PA00X+071950Y+036086X0200Y         S0      
327GND              R6151 -2          A01X+071933Y+036329X0198Y0197R270 S1      
317GND              VIA   -    MD0100PA00X+071150Y+036086X0200Y         S0      
327GND              R6149 -2          A01X+071146Y+036328X0198Y0197R270 S1      
317GND              VIA   -    M      A01X+008765Y+037603X0200Y         S2      
017GND              VIA   -    M      A18X+008765Y+037603X0260Y         S2      
017GND                    -    MD0100PA00X+008765Y+037603                       
327GND              R3664 -2          A01X+008497Y+037603X0198Y0197     S1      
317GND              VIA   -    MD0100PA00X+004683Y+036086X0200Y         S0      
327GND              C2041 -2          A01X+004683Y+036334X0198Y0197R270 S1      
327GND              U224  -3          A01X+180507Y+036605X0170Y0240R270 S1      
317GND              VIA   -    M      A01X+180313Y+036229X0200Y         S2      
017GND              VIA   -    M      A18X+180313Y+036229X0260Y         S2      
017GND                    -    MD0100PA00X+180313Y+036229                       
317GND              VIA   -    MD0100PA00X+099846Y+035472X0200Y    R270 S0      
317GND              VIA   -    MD0100PA00X+099346Y+035472X0200Y    R270 S0      
317GND              VIA   -    MD0100PA00X+098846Y+035472X0200Y    R270 S0      
317GND              VIA   -    MD0100PA00X+060787Y+035926X0200Y    R180 S0      
317GND              VIA   -    MD0100PA00X+061546Y+034752X0200Y    R180 S0      
317GND              VIA   -    MD0100PA00X+048808Y+035042X0200Y    R180 S0      
317GND              VIA   -    MD0100PA00X+046764Y+035342X0200Y    R180 S0      
327GND              R3661 -1          A01X+004281Y+036334X0198Y0197R090 S1      
317GND              VIA   -    M      A01X+004281Y+036086X0200Y         S2      
017GND              VIA   -    M      A18X+004281Y+036086X0260Y         S2      
017GND                    -    MD0100PA00X+004281Y+036086                       
327GND              R3666 -2          A01X+005519Y+036334X0198Y0197R270 S1      
317GND              VIA   -    M      A01X+005519Y+036086X0200Y         S2      
017GND              VIA   -    M      A18X+005519Y+036086X0260Y         S2      
017GND                    -    MD0100PA00X+005519Y+036086                       
317GND              VIA   -    MD0100PA00X+086138Y+034467X0200Y    R270 S0      
317GND              VIA   -    MD0100PA00X+086015Y+033332X0200Y    R270 S0      
317GND              VIA   -    MD0100PA00X+086513Y+033332X0200Y    R270 S0      
317GND              VIA   -    MD0100PA00X+086138Y+033975X0200Y    R090 S0      
317GND              VIA   -    MD0100PA00X+084628Y+033558X0200Y         S0      
317GND              VIA   -    MD0100PA00X+085640Y+034467X0200Y    R270 S0      
317GND              VIA   -    MD0100PA00X+085640Y+033975X0200Y    R090 S0      
317GND              VIA   -    MD0100PA00X+083269Y+033103X0200Y         S0      
317GND              VIA   -    MD0100PA00X+080840Y+034167X0200Y         S0      
317GND              VIA   -    MD0100PA00X+075396Y+034379X0200Y         S0      
317GND              VIA   -    MD0100PA00X+072033Y+034482X0200Y         S0      
317GND              VIA   -    MD0100PA00X+069740Y+034576X0200Y    R180 S0      
317GND              VIA   -    MD0100PA00X+086513Y+032840X0200Y    R090 S0      
317GND              VIA   -    MD0100PA00X+086015Y+032840X0200Y    R090 S0      
317GND              VIA   -    MD0100PA00X+080326Y+033010X0200Y         S0      
327GND              C640  -2          A18X+075704Y+031734X0198Y0197R270 S2      
317GND              VIA   -    MD0100PA00X+075896Y+031960X0200Y         S0      
327GND              R1313 -2          A01X+012002Y+031821X0198Y0197R090 S1      
317GND              VIA   -    M      A01X+012002Y+032063X0200Y    R090 S2      
017GND              VIA   -    M      A18X+012002Y+032063X0260Y    R090 S2      
017GND                    -    MD0100PA00X+012002Y+032063                       
327GND              C1862 -2          A01X+161740Y+030675X0198Y0197R090 S1      
317GND              VIA   -    MD0100PA00X+161991Y+030675X0200Y    R090 S0      
317GND              VIA   -    MD0100PA00X+158629Y+030675X0200Y    R270 S0      
327GND              C1860 -2          A01X+158880Y+030675X0198Y0197R090 S1      
327GND              Q144  -4          A18X+124332Y+030528X0170Y0200R090 S2      
317GND              VIA   -    MD0100PA00X+124582Y+030528X0200Y         S0      
317GND              VIA   -    MD0100PA00X+122609Y+030522X0200Y    R090 S0      
317GND              VIA   -    MD0100PA00X+123009Y+031422X0200Y    R090 S0      
317GND              VIA   -    MD0100PA00X+079862Y+031277X0200Y         S0      
327GND              C1826 -2          A18X+080110Y+031277X0198Y0197     S2      
317GND              VIA   -    MD0100PA00X+077394Y+031259X0200Y         S0      
327GND              R79   -2          A01X+077295Y+030341X0198Y0197R180 S1      
327GND              R80   -2   M      A01X+077287Y+030876X0198Y0197R180 S1      
317GND              VIA   -    MD0100PA00X+077912Y+030616X0200Y         S0      
327GND              Q4    -1          A01X+063630Y+030229X0170Y0200R090 S1      
317GND              VIA   -    MD0100PA00X+063380Y+030229X0200Y    R270 S0      
317GND              VIA   -    MD0100PA00X+044132Y+031017X0200Y         S0      
317GND              VIA   -    MD0100PA00X+044132Y+030417X0200Y         S0      
327GND              C1809 -2          A01X+006293Y+031036X0198Y0197     S1      
317GND              VIA   -    M      A01X+006293Y+031287X0200Y    R180 S2      
017GND              VIA   -    M      A18X+006293Y+031287X0260Y    R180 S2      
017GND                    -    MD0100PA00X+006293Y+031287                       
317GND              VIA   -    MD0100PA00X+005050Y+031110X0200Y    R270 S0      
327GND              U236  -4          A01X+159454Y+029533X0240Y0460R090 S1      
317GND              VIA   -    M      A01X+159984Y+029533X0200Y    R180 S2      
017GND              VIA   -    M      A18X+159984Y+029533X0260Y    R180 S2      
017GND                    -    MD0100PA00X+159984Y+029533                       
327GND              Q86   -1          A18X+136866Y+029207X0170Y0200R270 S2      
317GND              VIA   -    MD0100PA00X+136616Y+029207X0200Y         S0      
327GND              Q86   -4          A18X+136118Y+028695X0170Y0200R270 S2      
317GND              VIA   -    MD0100PA00X+135809Y+028695X0200Y         S0      
327GND              Q85   -1          A18X+135266Y+029207X0170Y0200R270 S2      
317GND              VIA   -    MD0100PA00X+135016Y+029207X0200Y         S0      
327GND              Q85   -4          A18X+134518Y+028695X0170Y0200R270 S2      
317GND              VIA   -    MD0100PA00X+134209Y+028695X0200Y         S0      
327GND              Q84   -4          A18X+132918Y+028695X0170Y0200R270 S2      
317GND              VIA   -    MD0100PA00X+132609Y+028695X0200Y         S0      
327GND              Q84   -1          A18X+133666Y+029207X0170Y0200R270 S2      
317GND              VIA   -    MD0100PA00X+133416Y+029207X0200Y         S0      
327GND              Q81   -1          A18X+131266Y+029207X0170Y0200R270 S2      
317GND              VIA   -    MD0100PA00X+131016Y+029207X0200Y         S0      
327GND              Q80   -1          A18X+129666Y+029207X0170Y0200R270 S2      
317GND              VIA   -    MD0100PA00X+129416Y+029207X0200Y         S0      
327GND              Q81   -4          A18X+130518Y+028695X0170Y0200R270 S2      
317GND              VIA   -    MD0100PA00X+130209Y+028695X0200Y         S0      
327GND              Q83   -1          A18X+130459Y+029807X0170Y0200R090 S2      
317GND              VIA   -    MD0100PA00X+130209Y+029807X0200Y         S0      
327GND              Q79   -1          A18X+128066Y+029207X0170Y0200R270 S2      
317GND              VIA   -    MD0100PA00X+127816Y+029207X0200Y         S0      
327GND              Q80   -4          A18X+128918Y+028695X0170Y0200R270 S2      
317GND              VIA   -    MD0100PA00X+128609Y+028695X0200Y         S0      
327GND              Q78   -1          A18X+126466Y+029207X0170Y0200R270 S2      
317GND              VIA   -    MD0100PA00X+126216Y+029207X0200Y         S0      
327GND              Q79   -4          A18X+127318Y+028695X0170Y0200R270 S2      
317GND              VIA   -    MD0100PA00X+127009Y+028695X0200Y         S0      
327GND              Q78   -4          A18X+125718Y+028695X0170Y0200R270 S2      
317GND              VIA   -    MD0100PA00X+125409Y+028695X0200Y         S0      
327GND              Q144  -1          A18X+123584Y+030016X0170Y0200R090 S2      
317GND              VIA   -    MD0100PA00X+123334Y+030016X0200Y    R180 S0      
327GND              Q87   -4          A18X+122518Y+028695X0170Y0200R270 S2      
317GND              VIA   -    MD0100PA00X+122209Y+028695X0200Y         S0      
327GND              Q87   -1          A18X+123266Y+029207X0170Y0200R270 S2      
317GND              VIA   -    MD0100PA00X+123016Y+029207X0200Y         S0      
317GND              VIA   -    MD0100PA00X+122609Y+029707X0200Y    R270 S0      
317GND              VIA   -    MD0100PA00X+121416Y+029207X0200Y         S0      
327GND              Q6000 -1          A18X+121666Y+029207X0170Y0200R270 S2      
317GND              VIA   -    MD0100PA00X+101787Y+029439X0200Y         S0      
327GND              C1592 -2          A01X+101533Y+029439X0198Y0197R090 S1      
317GND              VIA   -    MD0100PA00X+064628Y+029717X0200Y    R090 S0      
327GND              Q4    -4          A01X+064378Y+029717X0170Y0200R090 S1      
327GND              PC6021-2          A01X+059815Y+028972X0198Y0197R180 S1      
327GND              PC384 -2          A01X+056722Y+029747X0198Y0197R180 S1      
327GND              PC6020-2          A01X+053857Y+029227X0198Y0197R180 S1      
327GND              PC6010-2          A01X+055604Y+031271X0198Y0197R090 S1      
327GND              PC6008-2          A01X+056323Y+031881X0198Y0197R180 S1      
327GND              PR6010-2          A01X+056350Y+029757X0198Y0197R360 S1      
327GND              PR6003-2          A01X+055270Y+029448X0198Y0197R270 S1      
327GND              PR6006-1          A01X+057106Y+032055X0198Y0197R270 S1      
327GND              PU6000-7          A01X+056579Y+030251X0098Y0276     S1      
327GND              PU6000-14         A01X+056383Y+031393X0098Y0276R180 S1      
327GND              PU6000-1          A01X+056107Y+031216X0098Y0276R270 S1      
327GND              PC6014-2          A01X+055075Y+031560X0400Y0500R270 S1      
327GND              PC6012-2          A01X+054387Y+031566X0400Y0500R270 S1      
317GND              VIA   -    MD0100PA00X+059722Y+029804X0200Y    R270 S0      
317GND              VIA   -    MD0100PA00X+059470Y+029804X0200Y    R270 S0      
317GND              VIA   -    MD0100PA00X+059572Y+028972X0200Y    R270 S0      
317GND              VIA   -    MD0100PA00X+059722Y+030609X0200Y    R270 S0      
317GND              VIA   -    MD0100PA00X+059470Y+030609X0200Y    R270 S0      
317GND              VIA   -    MD0100PA00X+059722Y+031414X0200Y    R270 S0      
317GND              VIA   -    MD0100PA00X+059470Y+031414X0200Y    R270 S0      
317GND              VIA   -    MD0100PA00X+059470Y+032220X0200Y    R270 S0      
317GND              VIA   -    MD0100PA00X+059722Y+032220X0200Y    R270 S0      
317GND              VIA   -    MD0100PA00X+056732Y+030002X0200Y    R270 S0      
317GND              VIA   -    MD0100PA00X+056857Y+032199X0200Y    R270 S0      
317GND              VIA   -    MD0100PA00X+055270Y+029183X0200Y    R270 S0      
317GND              VIA   -    MD0100PA00X+055874Y+031392X0200Y    R270 S0      
317GND              VIA   -    MD0100PA00X+056169Y+031507X0200Y    R270 S0      
317GND              VIA   -    MD0100PA00X+055795Y+031764X0200Y    R270 S0      
317GND              VIA   -    MD0100PA00X+055489Y+031764X0200Y    R270 S0      
317GND              VIA   -    MD0100PA00X+055215Y+031912X0200Y    R270 S0      
317GND              VIA   -    MD0100PA00X+055494Y+032056X0200Y    R270 S0      
317GND              VIA   -    MD0100PA00X+055800Y+032056X0200Y    R270 S0      
317GND              VIA   -    MD0100PA00X+054909Y+031912X0200Y    R270 S0      
317GND              VIA   -    MD0100PA00X+056064Y+031768X0200Y    R270 S0      
317GND              VIA   -    MD0100PA00X+055632Y+031527X0200Y    R270 S0      
317GND              VIA   -    MD0100PA00X+053857Y+029478X0200Y    R270 S0      
317GND              VIA   -    MD0100PA00X+054281Y+031917X0200Y    R270 S0      
317GND              VIA   -    MD0100PA00X+054587Y+031917X0200Y    R270 S0      
317GND              VIA   -    MD0100PA00X+044132Y+029817X0200Y    R180 S0      
327GND              R1318 -2          A01X+012002Y+029777X0198Y0197R090 S1      
317GND              VIA   -    M      A01X+012002Y+030065X0200Y    R090 S2      
017GND              VIA   -    M      A18X+012002Y+030065X0260Y    R090 S2      
017GND                    -    MD0100PA00X+012002Y+030065                       
327GND              C1876 -2          A01X+006378Y+030136X0198Y0197R090 S1      
317GND              VIA   -    M      A01X+006629Y+030136X0200Y    R090 S2      
017GND              VIA   -    M      A18X+006629Y+030136X0260Y    R090 S2      
017GND                    -    MD0100PA00X+006629Y+030136                       
327GND              U242  -4          A01X+004469Y+029014X0200Y0340R270 S1      
317GND              VIA   -    M      A01X+004789Y+029014X0200Y    R090 S2      
017GND              VIA   -    M      A18X+004789Y+029014X0260Y    R090 S2      
017GND                    -    MD0100PA00X+004789Y+029014                       
327GND              C1875 -2          A01X+003318Y+030136X0198Y0197R090 S1      
317GND              VIA   -    M      A01X+003569Y+030136X0200Y    R090 S2      
017GND              VIA   -    M      A18X+003569Y+030136X0260Y    R090 S2      
017GND                    -    MD0100PA00X+003569Y+030136                       
327GND              U241  -4          A01X+001409Y+029014X0200Y0340R270 S1      
317GND              VIA   -    M      A01X+001729Y+029014X0200Y    R090 S2      
017GND              VIA   -    M      A18X+001729Y+029014X0260Y    R090 S2      
017GND                    -    MD0100PA00X+001729Y+029014                       
327GND              D99   -C          A01X+124609Y+027785X0240Y0280R090 S1      
317GND              VIA   -    MD0100PA00X+124609Y+028057X0200Y    R180 S0      
327GND              D98   -C          A01X+123809Y+027785X0240Y0280R090 S1      
317GND              VIA   -    MD0100PA00X+123809Y+028057X0200Y    R180 S0      
327GND              U134  -2          A01X+099769Y+029308X0170Y0240R270 S1      
317GND              VIA   -    MD0100PA00X+099292Y+028039X0200Y         S0      
317GND              VIA   -    MD0100PA00X+099519Y+027400X0200Y         S0      
327GND              Q126  -1          A01X+099769Y+027400X0170Y0200R090 S1      
317GND              VIA   -    MD0100PA00X+098246Y+027544X0200Y         S0      
327GND              R6049 -2          A01X+098488Y+027544X0198Y0197R180 S1      
317GND              VIA   -    MD0100PA00X+094278Y+027773X0200Y    R090 S0      
327GND              R999  -2          A01X+094526Y+027773X0198Y0197R090 S1      
317GND              VIA   -    MD0100PA00X+094276Y+027234X0200Y    R270 S0      
327GND              U44   -3          A01X+093879Y+027234X0140Y0490R270 S1      
317GND              VIA   -    MD0100PA00X+091627Y+027786X0200Y    R270 S0      
327GND              R1000 -2          A01X+091627Y+027543X0198Y0197R090 S1      
317GND              J57   -7   MD0460PA00X+054902Y+027427X0660Y    R180 S3      
327GND              C6083 -2          A01X+045248Y+027091X0198Y0197     S1      
317GND              VIA   -    MD0100PA00X+045248Y+027342X0200Y    R180 S0      
327GND              PC6022-2          A01X+051115Y+028072X0198Y0197R180 S1      
327GND              PC6016-2          A01X+048022Y+028847X0198Y0197R180 S1      
327GND              PC6023-2          A01X+045128Y+028332X0198Y0197R180 S1      
327GND              PC6011-2          A01X+046904Y+030371X0198Y0197R090 S1      
327GND              PC6009-2          A01X+047623Y+030981X0198Y0197R180 S1      
327GND              PR6004-2          A01X+046570Y+028548X0198Y0197R270 S1      
327GND              PR6011-2          A01X+047650Y+028857X0198Y0197R360 S1      
327GND              PR6005-1          A01X+048406Y+031155X0198Y0197R270 S1      
317GND              VIA   -    MD0100PA00X+048406Y+031396X0200Y    R270 S0      
317GND              VIA   -    MD0100PA00X+050808Y+031412X0200Y    R270 S0      
317GND              VIA   -    MD0100PA00X+051061Y+031412X0200Y    R270 S0      
317GND              VIA   -    MD0100PA00X+045581Y+031017X0200Y    R270 S0      
317GND              VIA   -    MD0100PA00X+045887Y+031017X0200Y    R270 S0      
317GND              VIA   -    MD0100PA00X+044885Y+028332X0200Y    R270 S0      
317GND              VIA   -    MD0100PA00X+047095Y+030864X0200Y    R270 S0      
317GND              VIA   -    MD0100PA00X+046789Y+030864X0200Y    R270 S0      
317GND              VIA   -    MD0100PA00X+046515Y+031012X0200Y    R270 S0      
317GND              VIA   -    MD0100PA00X+046794Y+031156X0200Y    R270 S0      
317GND              VIA   -    MD0100PA00X+047100Y+031156X0200Y    R270 S0      
317GND              VIA   -    MD0100PA00X+046209Y+031012X0200Y    R270 S0      
317GND              VIA   -    MD0100PA00X+047364Y+030868X0200Y    R270 S0      
317GND              VIA   -    MD0100PA00X+046932Y+030627X0200Y    R270 S0      
317GND              VIA   -    MD0100PA00X+047174Y+030492X0200Y    R270 S0      
317GND              VIA   -    MD0100PA00X+047469Y+030607X0200Y    R270 S0      
317GND              VIA   -    MD0100PA00X+046570Y+028283X0200Y    R270 S0      
317GND              VIA   -    MD0100PA00X+048032Y+029102X0200Y    R270 S0      
317GND              VIA   -    MD0100PA00X+051022Y+029709X0200Y    R270 S0      
317GND              VIA   -    MD0100PA00X+050770Y+029709X0200Y    R270 S0      
317GND              VIA   -    MD0100PA00X+051022Y+030514X0200Y    R270 S0      
317GND              VIA   -    MD0100PA00X+050770Y+030514X0200Y    R270 S0      
317GND              VIA   -    MD0100PA00X+050872Y+028072X0200Y    R270 S0      
317GND              VIA   -    MD0100PA00X+050770Y+028904X0200Y    R270 S0      
317GND              VIA   -    MD0100PA00X+051022Y+028904X0200Y    R270 S0      
327GND              PC6015-2          A01X+045687Y+030666X0400Y0500R270 S1      
327GND              PC6013-2          A01X+046375Y+030660X0400Y0500R270 S1      
327GND              PU6001-1          A01X+047407Y+030316X0098Y0276R270 S1      
327GND              PU6001-14         A01X+047683Y+030493X0098Y0276R180 S1      
327GND              PU6001-7          A01X+047879Y+029351X0098Y0276     S1      
327GND              C1810 -2          A01X+006293Y+028036X0198Y0197     S1      
317GND              VIA   -    M      A01X+006293Y+028287X0200Y    R180 S2      
017GND              VIA   -    M      A18X+006293Y+028287X0260Y    R180 S2      
017GND                    -    MD0100PA00X+006293Y+028287                       
317GND              VIA   -    MD0100PA00X+004460Y+028036X0200Y    R270 S0      
327GND              U59   -2          A01X+004730Y+028036X0170Y0240R270 S1      
317GND              VIA   -    MD0100PA00X+100767Y+025822X0200Y    R180 S0      
327GND              Q127  -4          A01X+100517Y+025822X0170Y0200R090 S1      
317GND              VIA   -    MD0100PA00X+100767Y+026888X0200Y    R180 S0      
327GND              Q126  -4          A01X+100517Y+026888X0170Y0200R090 S1      
317GND              VIA   -    MD0100PA00X+099519Y+026334X0200Y         S0      
327GND              Q127  -1          A01X+099769Y+026334X0170Y0200R090 S1      
317GND              VIA   -    MD0100PA00X+098246Y+026478X0200Y         S0      
327GND              R4073 -2          A01X+098488Y+026478X0198Y0197R180 S1      
317GND              VIA   -    MD0100PA00X+092822Y+026407X0200Y    R270 S0      
327GND              C508  -2          A01X+092547Y+026407X0198Y0197R270 S1      
317GND              VIA   -    MD0100PA00X+060472Y+025756X0200Y    R090 S0      
327GND              C20   -2          A01X+060582Y+026001X0198Y0197R180 S1      
327GND              R8    -1          A01X+057795Y+026117X0198Y0197     S1      
317GND              VIA   -    MD0100PA00X+057552Y+026117X0200Y    R270 S0      
327GND              Q62   -S          A01X+058810Y+025369X0400Y0560R270 S1      
317GND              VIA   -    MD0100PA00X+058714Y+025763X0200Y    R270 S0      
327GND              R6090 -2          A18X+054303Y+025369X0198Y0197R270 S2      
317GND              VIA   -    MD0100PA00X+054680Y+026280X0200Y         S0      
317GND              VIA   -    MD0100PA00X+048380Y+027044X0200Y    R180 S0      
327GND              R6217 -2          A01X+041514Y+027016X0198Y0197R180 S1      
317GND              VIA   -    MD0100PA00X+041272Y+027016X0200Y    R270 S0      
317GND              VIA   -    MD0100PA00X+041272Y+026216X0200Y    R270 S0      
327GND              R6219 -2          A01X+041514Y+026216X0198Y0197R180 S1      
327GND              J54   -17         A01X+156420Y+024925X0340Y0960R090 S1      
317GND              VIA   -    MD0100PA00X+157455Y+025129X0200Y         S0      
317GND              VIA   -    MD0100PA00X+151490Y+025184X0200Y         S0      
327GND              C87   -2          A01X+151364Y+024950X0198Y0197R090 S1      
317GND              VIA   -    MD0100PA00X+151645Y+024972X0200Y         S0      
327GND              R1629 -2          A01X+151894Y+024925X0198Y0197R180 S1      
327GND              C551  -2          A01X+151335Y+025646X0198Y0197R270 S1      
317GND              VIA   -    MD0100PA00X+151335Y+025395X0200Y         S0      
317GND              VIA   -    MD0100PA00X+133526Y+025159X0200Y    R270 S0      
327GND              J5    -8          A01X+134154Y+025159X0300Y0950R090 S1      
317GND              VIA   -    MD0100PA00X+133526Y+024159X0200Y    R270 S0      
327GND              J5    -4          A01X+134154Y+024159X0300Y0950R090 S1      
317GND              VIA   -    MD0100PA00X+133526Y+024659X0200Y    R270 S0      
327GND              J5    -6          A01X+134154Y+024659X0300Y0950R090 S1      
327GND              J48   -2          A01X+127146Y+025159X0300Y0950R270 S1      
317GND              VIA   -    MD0100PA00X+127773Y+025159X0200Y    R090 S0      
327GND              J48   -6          A01X+127146Y+024159X0300Y0950R270 S1      
317GND              VIA   -    MD0100PA00X+127773Y+024159X0200Y    R090 S0      
327GND              J48   -4          A01X+127146Y+024659X0300Y0950R270 S1      
317GND              VIA   -    MD0100PA00X+127773Y+024659X0200Y    R090 S0      
317GND              VIA   -    MD0100PA00X+101222Y+024364X0200Y    R180 S0      
317GND              VIA   -    MD0100PA00X+102122Y+024364X0200Y    R180 S0      
317GND              J90   -G2  MD0440PA00X+092244Y+024380X0640Y1370R090 S3      
327GND              C194  -2          A01X+053618Y+024678X0198Y0197R090 S1      
317GND              VIA   -    MD0100PA00X+053310Y+024678X0200Y         S0      
327GND              R1748 -2          A01X+046582Y+024376X0198Y0197R180 S1      
317GND              VIA   -    MD0100PA00X+046270Y+024234X0200Y    R180 S0      
327GND              C1554 -2          A01X+045812Y+024410X0198Y0197R090 S1      
317GND              VIA   -    MD0100PA00X+046062Y+024410X0200Y         S0      
317GND              VIA   -    MD0100PA00X+044340Y+024788X0200Y    R270 S0      
317GND              VIA   -    MD0100PA00X+042373Y+024957X0200Y    R270 S0      
317GND              VIA   -    MD0100PA00X+041272Y+025416X0200Y    R270 S0      
327GND              R6221 -2          A01X+041514Y+025416X0198Y0197R180 S1      
317GND              VIA   -    MD0100PA00X+042029Y+024418X0200Y    R180 S0      
317GND              VIA   -    MD0100PA00X+168494Y+023400X0200Y    R090 S0      
317GND              VIA   -    MD0100PA00X+165442Y+023306X0200Y    R090 S0      
327GND              C1874 -2          A01X+165191Y+023306X0198Y0197R090 S1      
317GND              VIA   -    MD0100PA00X+133526Y+023659X0200Y    R270 S0      
327GND              J5    -2          A01X+134154Y+023659X0300Y0950R090 S1      
327GND              J48   -8          A01X+127146Y+023659X0300Y0950R270 S1      
317GND              VIA   -    MD0100PA00X+127773Y+023659X0200Y    R090 S0      
317GND              VIA   -    MD0100PA00X+093550Y+023136X0200Y    R180 S0      
327GND              J90   -B28        A01X+093150Y+023136X0150Y0500R090 S1      
317GND              VIA   -    MD0100PA00X+090932Y+023136X0200Y         S0      
327GND              J90   -A28        A01X+091339Y+023136X0150Y0500R090 S1      
317GND              VIA   -    MD0100PA00X+062360Y+022878X0200Y         S0      
327GND              C2018 -2          A01X+062360Y+022628X0198Y0197     S1      
317GND              VIA   -    MD0100PA00X+057817Y+023139X0200Y    R270 S0      
327GND              U147  -1          A01X+057667Y+022806X0079Y0354R180 S1      
317GND              VIA   -    MD0100PA00X+058855Y+022928X0200Y         S0      
327GND              R3610 -1          A01X+059095Y+022928X0198Y0197     S1      
327GND              U147  -3          A01X+057234Y+022707X0070Y0320R270 S1      
317GND              VIA   -    MD0100PA00X+056900Y+022857X0200Y         S0      
317GND              VIA   -    MD0100PA00X+055310Y+022770X0200Y    R180 S0      
317GND              VIA   -    MD0100PA00X+051117Y+022788X0200Y         S0      
327GND              C1504 -2          A01X+048475Y+022653X0198Y0197R090 S1      
317GND              VIA   -    MD0100PA00X+048754Y+022653X0200Y    R180 S0      
327GND              R1735 -2          A01X+046897Y+023176X0198Y0197     S1      
317GND              VIA   -    MD0100PA00X+047137Y+023176X0200Y         S0      
317GND              VIA   -    MD0100PA00X+046365Y+023739X0200Y    R180 S0      
317GND              VIA   -    MD0100PA00X+045773Y+023759X0200Y    R180 S0      
317GND              VIA   -    MD0100PA00X+046340Y+022997X0200Y    R180 S0      
317GND              VIA   -    MD0100PA00X+043442Y+023993X0200Y    R225 S0      
327GND              R6223 -2          A18X+043371Y+024259X0198Y0197R090 S2      
317GND              VIA   -    MD0100PA00X+044003Y+024038X0200Y    R225 S0      
317GND              VIA   -    MD0100PA00X+042294Y+023279X0200Y    R180 S0      
317GND              VIA   -    MD0100PA00X+042294Y+022815X0200Y    R180 S0      
327GND              U124  -3          A01X+166861Y+022086X0220Y0530R270 S1      
317GND              VIA   -    MD0100PA00X+167322Y+022086X0200Y    R090 S0      
327GND              U240  -4          A01X+163282Y+022184X0200Y0340R270 S1      
317GND              VIA   -    M      A01X+162960Y+022184X0200Y    R090 S2      
017GND              VIA   -    M      A18X+162960Y+022184X0260Y    R090 S2      
017GND                    -    MD0100PA00X+162960Y+022184                       
327GND              C85   -2          A01X+159903Y+022525X0198Y0197     S1      
317GND              VIA   -    MD0100PA00X+160227Y+022953X0200Y    R090 S0      
317GND              VIA   -    MD0100PA00X+155548Y+021833X0200Y         S0      
327GND              J54   -5          A01X+156420Y+021925X0340Y0960R090 S1      
327GND              J54   -7          A01X+156420Y+022425X0340Y0960R090 S1      
317GND              VIA   -    MD0100PA00X+155298Y+022083X0200Y         S0      
327GND              C605  -2          A01X+151364Y+022210X0198Y0197R270 S1      
317GND              VIA   -    M      A01X+151458Y+021973X0200Y         S2      
017GND              VIA   -    M      A18X+151458Y+021973X0260Y         S2      
017GND                    -    MD0100PA00X+151458Y+021973                       
317GND              J6    -6   MD0440PA00X+119386Y+021720X0640Y    R090 S3      
317GND              J6    -2   MD0440PA00X+117386Y+021720X0640Y    R090 S3      
317GND              J6    -4   MD0440PA00X+118386Y+021720X0640Y    R090 S3      
317GND              VIA   -    MD0100PA00X+099155Y+021681X0200Y    R270 S0      
327GND              PC2205-2          A01X+098823Y+021723X0280Y0320     S1      
327GND              PR3954-2          A01X+099434Y+021723X0198Y0197R180 S1      
317GND              VIA   -    MD0100PA00X+096869Y+021959X0200Y         S0      
327GND              PC2219-2          A01X+096939Y+021609X0400Y0500R270 S1      
327GND              PC2280-2          A18X+096858Y+021580X0400Y0500R090 S2      
317GND              VIA   -    MD0100PA00X+097119Y+021959X0200Y         S0      
317GND              VIA   -    MD0100PA00X+093550Y+021718X0200Y    R180 S0      
327GND              J90   -B22        A01X+093150Y+021718X0150Y0500R090 S1      
317GND              VIA   -    MD0100PA00X+093550Y+022427X0200Y    R180 S0      
327GND              J90   -B25        A01X+093150Y+022427X0150Y0500R090 S1      
327GND              J90   -A25        A01X+091339Y+022427X0150Y0500R090 S1      
317GND              VIA   -    MD0100PA00X+090932Y+022427X0200Y         S0      
327GND              J90   -A22        A01X+091339Y+021718X0150Y0500R090 S1      
317GND              VIA   -    MD0100PA00X+090932Y+021718X0200Y         S0      
327GND              PC2210-2          A01X+086447Y+028931X0198Y0197R180 S1      
327GND              PC2208-2          A01X+086357Y+029381X0198Y0197R270 S1      
327GND              PU295 -B2         A01X+086938Y+028000X0090Y         S1      
327GND              PU295 -C1         A01X+086741Y+027803X0090Y         S1      
327GND              PU295 -C2         A01X+086938Y+027803X0090Y         S1      
327GND              PR3969-2          A01X+085674Y+028003X0198Y0197R180 S1      
327GND              PR3971-2          A01X+085674Y+028353X0198Y0197R180 S1      
327GND              PC2212-1          A01X+085626Y+027322X0198Y0197     S1      
327GND              PD113 -A          A01X+084635Y+027252X0670Y0990     S1      
317GND              VIA   -    MD0100PA00X+085670Y+030486X0200Y         S0      
317GND              VIA   -    MD0100PA00X+085320Y+029746X0200Y         S0      
327GND              C641  -2          A18X+082615Y+028806X0198Y0197R180 S2      
317GND              VIA   -    MD0100PA00X+082917Y+028806X0200Y         S0      
317GND              VIA   -    MD0100PA00X+084029Y+028759X0200Y         S0      
327GND              U222  -7          A18X+083550Y+029651X0140Y0590R090 S2      
317GND              VIA   -    MD0100PA00X+082957Y+029651X0200Y         S0      
317GND              VIA   -    MD0100PA00X+079567Y+029880X0200Y         S0      
317GND              VIA   -    MD0100PA00X+078062Y+029634X0200Y         S0      
327GND              U67   -7          A18X+078798Y+029623X0140Y0590R090 S2      
327GND              R77   -2          A01X+078062Y+029928X0198Y0197     S1      
317GND              VIA   -    MD0100PA00X+077322Y+029626X0200Y         S0      
317GND              VIA   -    MD0100PA00X+075746Y+028409X0200Y         S0      
327GND              C1827 -2          A18X+075746Y+028663X0198Y0197     S2      
317GND              VIA   -    MD0100PA00X+075534Y+029559X0200Y         S0      
317GND              VIA   -    MD0100PA00X+088094Y+028335X0200Y         S0      
327GND              PU295 -B7         A01X+087922Y+028000X0090Y         S1      
327GND              PU295 -A7         A01X+087922Y+028197X0090Y         S1      
317GND              VIA   -    MD0100PA00X+088094Y+028635X0200Y         S0      
327GND              PC2216-2          A01X+088099Y+028944X0198Y0197     S1      
317GND              VIA   -    MD0100PA00X+083616Y+027936X0200Y    R270 S0      
317GND              VIA   -    MD0100PA00X+081632Y+028437X0200Y         S0      
317GND              VIA   -    MD0100PA00X+079744Y+027147X0200Y         S0      
327GND              U223  -7          A18X+079290Y+027147X0140Y0590R090 S2      
317GND              VIA   -    MD0100PA00X+079759Y+028223X0200Y         S0      
327GND              PC2200-2          A01X+077377Y+028440X0198Y0197R090 S1      
317GND              VIA   -    MD0100PA00X+077448Y+028688X0200Y    R270 S0      
327GND              PU293 -3          A01X+076983Y+027529X0100Y0280R270 S1      
317GND              VIA   -    MD0100PA00X+076528Y+027637X0200Y    R270 S0      
327GND              PR3947-1          A01X+075669Y+027632X0198Y0197     S1      
317GND              VIA   -    MD0100PA00X+075669Y+027894X0200Y    R270 S0      
327GND              R83   -2          A18X+085853Y+026481X0198Y0197R090 S2      
317GND              VIA   -    MD0100PA00X+085853Y+026238X0200Y         S0      
317GND              VIA   -    MD0100PA00X+085733Y+027612X0200Y         S0      
317GND              VIA   -    MD0100PA00X+085422Y+028353X0200Y         S0      
317GND              VIA   -    MD0100PA00X+085422Y+028003X0200Y         S0      
317GND              VIA   -    MD0100PA00X+085433Y+027612X0200Y         S0      
317GND              VIA   -    MD0100PA00X+086393Y+027692X0200Y         S0      
317GND              VIA   -    MD0100PA00X+086083Y+027682X0200Y         S0      
317GND              VIA   -    MD0100PA00X+085280Y+028856X0200Y         S0      
317GND              VIA   -    MD0100PA00X+086204Y+029005X0200Y         S0      
317GND              VIA   -    MD0100PA00X+085278Y+029156X0200Y         S0      
327GND              R84   -2          A18X+085006Y+029156X0198Y0197R180 S2      
327GND              U7    -7          A18X+084158Y+026606X0140Y0590R090 S2      
317GND              VIA   -    MD0100PA00X+084794Y+026509X0200Y         S0      
317GND              VIA   -    MD0100PA00X+085380Y+026506X0200Y         S0      
327GND              PR3965-2          A01X+085623Y+026506X0198Y0197R180 S1      
317GND              VIA   -    MD0100PA00X+083252Y+026858X0200Y         S0      
317GND              VIA   -    MD0100PA00X+080698Y+026565X0200Y         S0      
317GND              VIA   -    MD0100PA00X+079134Y+026485X0200Y    R270 S0      
327GND              PC2203-2          A01X+079134Y+026782X0198Y0197     S1      
317GND              VIA   -    MD0100PA00X+075429Y+026932X0200Y    R270 S0      
327GND              PC2197-2          A01X+075669Y+026932X0198Y0197R180 S1      
317GND              VIA   -    MD0100PA00X+075429Y+026632X0200Y    R270 S0      
327GND              PR3945-2          A01X+075669Y+026532X0198Y0197R180 S1      
317GND              VIA   -    MD0100PA00X+077346Y+024979X0200Y    R270 S0      
327GND              PC2204-2          A01X+077346Y+025329X0400Y0500R090 S1      
317GND              VIA   -    MD0100PA00X+085221Y+022988X0200Y    R180 S0      
317GND              VIA   -    MD0100PA00X+085471Y+022988X0200Y    R180 S0      
327GND              PC2220-2          A01X+085558Y+023407X0400Y0500     S1      
327GND              PC2218-2          A01X+085802Y+024044X0198Y0197R180 S1      
317GND              VIA   -    MD0100PA00X+083034Y+022814X0200Y         S0      
327GND              R3763 -1          A01X+083372Y+022814X0198Y0197R270 S1      
317GND              VIA   -    MD0100PA00X+084522Y+021653X0200Y    R180 S0      
317GND              VIA   -    MD0100PA00X+084971Y+021206X0200Y    R180 S0      
327GND              U276  -10         A01X+085299Y+021341X0090Y0240R270 S1      
327GND              U276  -TH  M      A01X+084748Y+021439X0670Y0670     S1      
327GND              R3764 -1          A18X+084580Y+022036X0198Y0197     S2      
327GND              C2067 -2          A18X+084964Y+020936X0198Y0197     S2      
327GND              C2069 -2          A18X+084954Y+021636X0198Y0197     S2      
317GND              VIA   -    MD0100PA00X+071920Y+021320X0200Y    R270 S0      
317GND              VIA   -    MD0100PA00X+071420Y+021320X0200Y    R270 S0      
327GND              J59   -3          A01X+069728Y+021968X0110Y0630R270 S1      
317GND              VIA   -    MD0100PA00X+070193Y+021968X0200Y         S0      
327GND              J59   -9          A01X+069728Y+021378X0110Y0630R270 S1      
317GND              VIA   -    MD0100PA00X+070193Y+021378X0200Y         S0      
317GND              VIA   -    MD0100PA00X+068226Y+022412X0200Y         S0      
327GND              J59   -G1         A01X+069423Y+022598X0490Y1100R270 S1      
317GND              VIA   -    MD0100PA00X+062360Y+021928X0200Y         S0      
327GND              C2013 -2          A01X+062360Y+022178X0198Y0197     S1      
317GND              VIA   -    MD0100PA00X+061241Y+022704X0200Y         S0      
327GND              U264  -TH  M      A01X+061023Y+022488X0670Y0670     S1      
317GND              VIA   -    MD0100PA00X+060783Y+022261X0200Y         S0      
327GND              U264  -10         A01X+061574Y+022389X0090Y0240R270 S1      
327GND              C1503 -2          A01X+057786Y+021462X0198Y0197R270 S1      
317GND              VIA   -    MD0100PA00X+057786Y+021220X0200Y         S0      
317GND              VIA   -    MD0100PA00X+058530Y+022295X0200Y    R180 S0      
317GND              VIA   -    MD0100PA00X+058855Y+022128X0200Y         S0      
327GND              R3611 -1          A01X+059095Y+022128X0198Y0197     S1      
327GND              C1505 -2          A01X+057391Y+021462X0198Y0197R270 S1      
317GND              VIA   -    MD0100PA00X+057391Y+021220X0200Y         S0      
327GND              R1658 -2          A01X+054341Y+022244X0198Y0197R180 S1      
317GND              VIA   -    MD0100PA00X+054101Y+022244X0200Y    R180 S0      
317GND              VIA   -    MD0100PA00X+051797Y+021200X0200Y    R180 S0      
327GND              U152  -1          A01X+051464Y+021250X0079Y0354R090 S1      
317GND              VIA   -    MD0100PA00X+051515Y+022017X0200Y    R270 S0      
327GND              U152  -3          A01X+051365Y+021683X0070Y0320R180 S1      
317GND              VIA   -    MD0100PA00X+051117Y+022493X0200Y         S0      
317GND              VIA   -    MD0100PA00X+050027Y+022507X0200Y    R270 S0      
317GND              VIA   -    MD0100PA00X+049878Y+021328X0200Y    R270 S0      
327GND              C1518 -2          A01X+050120Y+021328X0198Y0197R180 S1      
317GND              VIA   -    MD0100PA00X+049164Y+021258X0200Y    R180 S0      
327GND              U146  -3          A01X+048830Y+021408X0070Y0320R090 S1      
327GND              R1729 -2          A01X+045793Y+021510X0198Y0197R270 S1      
317GND              VIA   -    MD0100PA00X+045793Y+021270X0200Y    R270 S0      
317GND              VIA   -    MD0100PA00X+045378Y+021765X0200Y         S0      
327GND              R6302 -2          A01X+045130Y+021765X0198Y0197R090 S1      
317GND              VIA   -    MD0100PA00X+043930Y+022005X0200Y    R090 S0      
327GND              R6309 -2          A01X+043930Y+021765X0198Y0197R090 S1      
317GND              VIA   -    MD0100PA00X+043312Y+022520X0200Y         S0      
317GND              VIA   -    MD0100PA00X+043312Y+022225X0200Y         S0      
317GND              VIA   -    MD0100PA00X+041180Y+022020X0200Y    R090 S0      
327GND              R6319 -2          A01X+041130Y+021765X0198Y0197R090 S1      
317GND              VIA   -    MD0100PA00X+039698Y+021668X0200Y    R090 S0      
327GND              R6321 -2          A01X+039930Y+021765X0198Y0197R090 S1      
327GND              PU200 -C1         A01X+036595Y+023064X0090Y    R180 S1      
327GND              PR3822-2          A01X+037662Y+022864X0198Y0197     S1      
327GND              PC2147-1          A01X+037710Y+023546X0198Y0197R180 S1      
327GND              PU200 -B2         A01X+036398Y+022867X0090Y    R180 S1      
327GND              PU200 -C2         A01X+036398Y+023064X0090Y    R180 S1      
327GND              PR3824-2          A01X+037662Y+022514X0198Y0197     S1      
327GND              C39   -2          A01X+036889Y+021936X0198Y0197     S1      
327GND              PC2140-2          A01X+036889Y+021136X0198Y0197     S1      
327GND              C6088 -2          A01X+039215Y+021670X0400Y0500R270 S1      
317GND              VIA   -    MD0100PA00X+038460Y+022180X0200Y         S0      
327GND              PC1321-2          A01X+038416Y+029437X0198Y0197     S1      
317GND              VIA   -    MD0100PA00X+037920Y+029877X0200Y         S0      
317GND              VIA   -    MD0100PA00X+035583Y+029786X0200Y         S0      
327GND              PR3856-1          A01X+035583Y+029496X0198Y0197R270 S1      
317GND              VIA   -    MD0100PA00X+036043Y+029403X0200Y         S0      
327GND              PC2169-2          A01X+036283Y+029403X0198Y0197R180 S1      
317GND              VIA   -    MD0100PA00X+035973Y+028877X0200Y         S0      
327GND              PU207 -3          A01X+036265Y+028784X0100Y0280R270 S1      
327GND              PC1322-2          A01X+038416Y+028037X0198Y0197     S1      
317GND              VIA   -    MD0100PA00X+038656Y+028037X0200Y         S0      
327GND              PC2173-2          A01X+035941Y+027497X0400Y0500     S1      
317GND              VIA   -    MD0100PA00X+035573Y+027506X0200Y    R180 S0      
327GND              PC2142-2          A01X+035262Y+027131X0400Y0500R270 S1      
317GND              VIA   -    MD0100PA00X+034970Y+028671X0200Y    R270 S0      
317GND              VIA   -    MD0100PA00X+034968Y+027671X0200Y    R270 S0      
327GND              PR3855-2          A01X+035261Y+027676X0198Y0197R270 S1      
327GND              PC2168-2          A01X+035263Y+028686X0198Y0197R090 S1      
327GND              PD109 -A          A01X+038544Y+027181X0670Y0990     S1      
317GND              VIA   -    MD0100PA00X+039046Y+026769X0200Y    R270 S0      
317GND              VIA   -    MD0100PA00X+039046Y+027069X0200Y    R270 S0      
317GND              VIA   -    MD0100PA00X+039046Y+027519X0200Y    R270 S0      
327GND              PC2137-2          A01X+037141Y+027515X0198Y0197R090 S1      
327GND              PR3812-2          A01X+037713Y+024362X0198Y0197     S1      
317GND              VIA   -    MD0100PA00X+038001Y+024362X0200Y         S0      
317GND              VIA   -    MD0100PA00X+038018Y+023667X0200Y    R270 S0      
317GND              VIA   -    MD0100PA00X+037132Y+021863X0200Y    R180 S0      
317GND              VIA   -    MD0100PA00X+037253Y+023186X0200Y    R180 S0      
317GND              VIA   -    MD0100PA00X+036943Y+023176X0200Y    R180 S0      
317GND              VIA   -    MD0100PA00X+037903Y+023256X0200Y    R180 S0      
317GND              VIA   -    MD0100PA00X+037902Y+022865X0200Y    R180 S0      
317GND              VIA   -    MD0100PA00X+037902Y+022515X0200Y    R180 S0      
327GND              PU200 -A7         A01X+035414Y+022670X0090Y    R180 S1      
327GND              PU200 -B7         A01X+035414Y+022867X0090Y    R180 S1      
327GND              PC2151-2          A01X+035236Y+021934X0198Y0197R180 S1      
317GND              VIA   -    MD0100PA00X+035242Y+022233X0200Y    R180 S0      
317GND              VIA   -    MD0100PA00X+035242Y+022533X0200Y    R180 S0      
317GND              VIA   -    MD0100PA00X+012837Y+021224X0200Y         S0      
327GND              J49   -2          A01X+012212Y+021224X0300Y0950R270 S1      
327GND              C604  -2          A01X+152689Y+020125X0198Y0197     S1      
317GND              VIA   -    M      A01X+152938Y+020124X0200Y         S2      
017GND              VIA   -    M      A18X+152938Y+020124X0260Y         S2      
017GND                    -    MD0100PA00X+152938Y+020124                       
327GND              PU292 -7          A01X+100497Y+020623X0100Y0320R090 S1      
327GND              PC2341-2          A18X+102191Y+020320X0198Y0197R270 S2      
327GND              PC2196-2          A01X+101680Y+019900X0198Y0197     S1      
317GND              VIA   -    MD0100PA00X+101994Y+021046X0200Y    R270 S0      
317GND              VIA   -    MD0100PA00X+101994Y+020733X0200Y    R270 S0      
327GND              PC2281-2          A01X+101677Y+020742X0198Y0197     S1      
327GND              PC2202-2          A01X+101677Y+021442X0198Y0197     S1      
327GND              PR3944-2          A01X+101670Y+020310X0198Y0197     S1      
317GND              VIA   -    MD0100PA00X+101980Y+021810X0200Y         S0      
327GND              PR3949-2          A01X+101677Y+021842X0198Y0197     S1      
317GND              VIA   -    MD0100PA00X+100807Y+019839X0200Y    R270 S0      
327GND              PU292 -3          A01X+100497Y+019836X0100Y0320R090 S1      
317GND              VIA   -    MD0100PA00X+093550Y+020301X0200Y    R180 S0      
327GND              J90   -B16        A01X+093150Y+020301X0150Y0500R090 S1      
317GND              VIA   -    MD0100PA00X+093550Y+021010X0200Y    R180 S0      
327GND              J90   -B19        A01X+093150Y+021010X0150Y0500R090 S1      
327GND              R10296-2          A18X+092835Y+020161X0198Y0197     S2      
317GND              VIA   -    MD0100PA00X+092532Y+020340X0200Y         S0      
327GND              J90   -A19        A01X+091339Y+021010X0150Y0500R090 S1      
317GND              VIA   -    MD0100PA00X+090932Y+021010X0200Y         S0      
327GND              J90   -A16        A01X+091339Y+020301X0150Y0500R090 S1      
317GND              VIA   -    MD0100PA00X+090916Y+020301X0200Y         S0      
317GND              VIA   -    MD0100PA00X+071420Y+020136X0200Y    R270 S0      
317GND              VIA   -    MD0100PA00X+071920Y+020136X0200Y    R270 S0      
317GND              VIA   -    MD0100PA00X+071920Y+020821X0200Y    R270 S0      
317GND              VIA   -    MD0100PA00X+071420Y+020821X0200Y    R270 S0      
327GND              J59   -15         A01X+069728Y+020787X0110Y0630R270 S1      
317GND              VIA   -    MD0100PA00X+070193Y+020787X0200Y         S0      
327GND              J59   -21         A01X+069728Y+020197X0110Y0630R270 S1      
317GND              VIA   -    MD0100PA00X+070193Y+020197X0200Y         S0      
327GND              C9922 -2          A18X+067267Y+019727X0280Y0320R270 S2      
327GND              C1925 -2          A18X+066956Y+020236X0198Y0197R180 S2      
327GND              C1924 -2          A18X+066956Y+020636X0198Y0197R180 S2      
327GND              C1923 -2          A18X+066956Y+021036X0198Y0197R180 S2      
317GND              VIA   -    MD0100PA00X+067330Y+021133X0200Y         S0      
317GND              VIA   -    MD0100PA00X+067369Y+020067X0200Y         S0      
317GND              VIA   -    MD0100PA00X+064301Y+019931X0200Y         S0      
317GND              VIA   -    MD0100PA00X+064301Y+020191X0200Y         S0      
327GND              C1920 -2          A01X+065161Y+020109X0280Y0320R180 S1      
327GND              C1921 -2          A01X+064618Y+020110X0280Y0320R180 S1      
317GND              VIA   -    MD0100PA00X+056460Y+020030X0200Y         S0      
317GND              VIA   -    MD0100PA00X+056460Y+019778X0200Y         S0      
327GND              C6027 -2          A01X+056108Y+019904X0400Y0500R180 S1      
327GND              C6028 -2          A01X+055915Y+019354X0198Y0197     S1      
317GND              VIA   -    MD0100PA00X+053128Y+021092X0200Y    R090 S0      
327GND              R1637 -2          A01X+052830Y+021092X0198Y0197R270 S1      
327GND              C1513 -2          A01X+052209Y+020744X0198Y0197R090 S1      
317GND              VIA   -    MD0100PA00X+051958Y+020744X0200Y    R270 S0      
317GND              VIA   -    MD0100PA00X+051177Y+019958X0200Y    R090 S0      
317GND              VIA   -    MD0100PA00X+049523Y+019752X0200Y    R180 S0      
327GND              R6214 -2          A01X+049766Y+019752X0198Y0197R180 S1      
317GND              VIA   -    MD0100PA00X+048660Y+020080X0200Y    R180 S0      
327GND              C2317 -2          A01X+048911Y+020152X0198Y0197R180 S1      
327GND              C86   -2          A01X+050120Y+020928X0198Y0197R180 S1      
317GND              VIA   -    MD0100PA00X+049878Y+020928X0200Y    R270 S0      
317GND              VIA   -    MD0100PA00X+048347Y+020976X0200Y    R090 S0      
327GND              U146  -1          A01X+048397Y+021309X0079Y0354     S1      
317GND              VIA   -    MD0100PA00X+043130Y+020414X0200Y    R270 S0      
327GND              R6307 -2          A01X+043130Y+020654X0198Y0197R270 S1      
317GND              VIA   -    MD0100PA00X+012837Y+019724X0200Y         S0      
327GND              J49   -8          A01X+012212Y+019724X0300Y0950R270 S1      
317GND              VIA   -    MD0100PA00X+012837Y+020724X0200Y         S0      
327GND              J49   -4          A01X+012212Y+020724X0300Y0950R270 S1      
317GND              VIA   -    MD0100PA00X+012837Y+020224X0200Y         S0      
327GND              J49   -6          A01X+012212Y+020224X0300Y0950R270 S1      
327GND              J7    -4          A01X+003917Y+020722X0300Y0950R270 S1      
317GND              VIA   -    M      A01X+004542Y+020722X0200Y         S2      
017GND              VIA   -    M      A18X+004542Y+020722X0260Y         S2      
017GND                    -    MD0100PA00X+004542Y+020722                       
327GND              J7    -6          A01X+003917Y+020222X0300Y0950R270 S1      
317GND              VIA   -    M      A01X+004542Y+020222X0200Y         S2      
017GND              VIA   -    M      A18X+004542Y+020222X0260Y         S2      
017GND                    -    MD0100PA00X+004542Y+020222                       
327GND              J7    -2          A01X+003917Y+021222X0300Y0950R270 S1      
317GND              VIA   -    M      A01X+004542Y+021222X0200Y         S2      
017GND              VIA   -    M      A18X+004542Y+021222X0260Y         S2      
017GND                    -    MD0100PA00X+004542Y+021222                       
327GND              R1800 -2          A01X+128968Y+018405X0198Y0197     S1      
317GND              VIA   -    MD0100PA00X+129208Y+018405X0200Y         S0      
327GND              C2046 -2          A01X+126118Y+018505X0198Y0197     S1      
317GND              VIA   -    MD0100PA00X+126358Y+018505X0200Y         S0      
317GND              VIA   -    MD0100PA00X+120001Y+018519X0200Y    R180 S0      
327GND              R3690 -2          A01X+120244Y+018519X0198Y0197R180 S1      
317GND              H114  -2   MD0220PA00X+105766Y+022047X0300Y         S3      
317GND              H114  -3   MD0220PA00X+104585Y+021457X0300Y         S3      
317GND              H114  -4   MD0220PA00X+104191Y+020472X0300Y         S3      
317GND              H114  -5   MD0220PA00X+104585Y+019488X0300Y         S3      
317GND              H114  -6   MD0220PA00X+105766Y+018898X0300Y         S3      
317GND              H114  -7   MD0220PA00X+106947Y+019488X0300Y         S3      
317GND              H114  -8   MD0220PA00X+107341Y+020472X0300Y         S3      
317GND              H114  -9   MD0220PA00X+106947Y+021457X0300Y         S3      
327GND              PU292 -2          A01X+100497Y+019639X0100Y0320R090 S1      
317GND              VIA   -    MD0100PA00X+101136Y+019532X0200Y    R270 S0      
327GND              PC2198-2          A01X+102322Y+018917X0198Y0197R090 S1      
317GND              VIA   -    M      A01X+102322Y+019157X0200Y         S2      
017GND              VIA   -    M      A18X+102322Y+019157X0260Y         S2      
017GND                    -    MD0100PA00X+102322Y+019157                       
317GND              VIA   -    MD0100PA00X+098859Y+018935X0200Y         S0      
317GND              VIA   -    MD0100PA00X+093550Y+019592X0200Y    R180 S0      
327GND              J90   -B13        A01X+093150Y+019592X0150Y0500R090 S1      
317GND              VIA   -    MD0100PA00X+092713Y+018939X0200Y         S0      
327GND              C1283 -2   M      A18X+093002Y+018939X0198Y0197     S2      
327GND              C1282 -2          A18X+093022Y+019339X0198Y0197     S2      
327GND              J90   -A13        A01X+091339Y+019592X0150Y0500R090 S1      
317GND              VIA   -    MD0100PA00X+090930Y+019592X0200Y         S0      
327GND              R2426 -2          A01X+088115Y+019206X0198Y0197R180 S1      
317GND              VIA   -    M      A01X+087822Y+019206X0200Y         S2      
017GND              VIA   -    M      A18X+087822Y+019206X0260Y         S2      
017GND                    -    MD0100PA00X+087822Y+019206                       
317GND              H113  -2   MD0220PA00X+080569Y+022047X0300Y         S3      
317GND              H113  -3   MD0220PA00X+079388Y+021457X0300Y         S3      
317GND              H113  -4   MD0220PA00X+078994Y+020472X0300Y         S3      
317GND              H113  -5   MD0220PA00X+079388Y+019488X0300Y         S3      
317GND              H113  -6   MD0220PA00X+080569Y+018898X0300Y         S3      
317GND              H113  -7   MD0220PA00X+081750Y+019488X0300Y         S3      
317GND              H113  -8   MD0220PA00X+082144Y+020472X0300Y         S3      
317GND              H113  -9   MD0220PA00X+081750Y+021457X0300Y         S3      
317GND              VIA   -    MD0100PA00X+076230Y+018891X0200Y    R180 S0      
317GND              VIA   -    MD0100PA00X+071420Y+018986X0200Y    R270 S0      
317GND              VIA   -    MD0100PA00X+071420Y+018487X0200Y    R270 S0      
317GND              VIA   -    MD0100PA00X+071920Y+018986X0200Y    R270 S0      
317GND              VIA   -    MD0100PA00X+071920Y+018487X0200Y    R270 S0      
317GND              VIA   -    MD0100PA00X+071420Y+019637X0200Y    R270 S0      
317GND              VIA   -    MD0100PA00X+071920Y+019637X0200Y    R270 S0      
327GND              J59   -33         A01X+069728Y+019016X0110Y0630R270 S1      
317GND              VIA   -    MD0100PA00X+070193Y+019016X0200Y         S0      
327GND              J59   -27         A01X+069728Y+019606X0110Y0630R270 S1      
317GND              VIA   -    MD0100PA00X+070193Y+019606X0200Y         S0      
327GND              J59   -39         A01X+069728Y+018425X0110Y0630R270 S1      
317GND              VIA   -    MD0100PA00X+070193Y+018425X0200Y         S0      
317GND              VIA   -    MD0100PA00X+064248Y+018486X0200Y         S0      
327GND              R1605 -2          A01X+064615Y+018486X0198Y0197R180 S1      
327GND              C1305 -2          A01X+061321Y+017972X0198Y0197R180 S1      
317GND              VIA   -    MD0100PA00X+061321Y+018223X0200Y    R180 S0      
317GND              VIA   -    MD0100PA00X+059030Y+019066X0200Y    R180 S0      
317GND              VIA   -    MD0100PA00X+059666Y+018878X0200Y    R180 S0      
317GND              VIA   -    MD0100PA00X+060079Y+019318X0200Y    R180 S0      
317GND              VIA   -    MD0100PA00X+054720Y+019526X0200Y         S0      
327GND              R6216 -2          A01X+054477Y+019526X0198Y0197     S1      
327GND              R6202 -1          A01X+049766Y+018952X0198Y0197     S1      
317GND              VIA   -    M      A01X+049523Y+018952X0200Y    R180 S2      
017GND              VIA   -    M      A18X+049523Y+018952X0260Y    R180 S2      
017GND                    -    MD0100PA00X+049523Y+018952                       
327GND              R4453 -2          A01X+048911Y+019752X0198Y0197R180 S1      
317GND              VIA   -    M      A01X+048668Y+019752X0200Y    R180 S2      
017GND              VIA   -    M      A18X+048668Y+019752X0260Y    R180 S2      
017GND                    -    MD0100PA00X+048668Y+019752                       
327GND              J7    -8          A01X+003917Y+019722X0300Y0950R270 S1      
317GND              VIA   -    M      A01X+004542Y+019722X0200Y         S2      
017GND              VIA   -    M      A18X+004542Y+019722X0260Y         S2      
017GND                    -    MD0100PA00X+004542Y+019722                       
317GND              VIA   -    MD0100PA00X+166510Y+016676X0200Y    R090 S0      
317GND              VIA   -    MD0100PA00X+162741Y+017201X0200Y         S0      
327GND              R1791 -2          A01X+128968Y+017155X0198Y0197     S1      
317GND              VIA   -    MD0100PA00X+129208Y+017155X0200Y         S0      
327GND              C2048 -2          A01X+126118Y+016805X0198Y0197     S1      
317GND              VIA   -    MD0100PA00X+126358Y+016805X0200Y         S0      
327GND              C2049 -2          A01X+126118Y+017205X0198Y0197     S1      
317GND              VIA   -    MD0100PA00X+126358Y+017205X0200Y         S0      
327GND              C33   -2          A01X+126118Y+017605X0198Y0197     S1      
317GND              VIA   -    MD0100PA00X+126358Y+017605X0200Y         S0      
327GND              C37   -2          A01X+126118Y+018055X0198Y0197     S1      
317GND              VIA   -    MD0100PA00X+126358Y+018055X0200Y         S0      
327GND              U269  -4          A01X+122018Y+017240X0140Y0630R270 S1      
317GND              VIA   -    M      A01X+121553Y+017240X0200Y         S2      
017GND              VIA   -    M      A18X+121553Y+017240X0260Y         S2      
017GND                    -    MD0100PA00X+121553Y+017240                       
327GND              C2052 -2          A01X+119213Y+017319X0198Y0197R180 S1      
317GND              VIA   -    M      A01X+118970Y+017319X0200Y         S2      
017GND              VIA   -    M      A18X+118970Y+017319X0260Y         S2      
017GND                    -    MD0100PA00X+118970Y+017319                       
327GND              C2051 -2          A01X+119213Y+017719X0198Y0197R180 S1      
317GND              VIA   -    MD0100PA00X+118973Y+017719X0200Y    R180 S0      
327GND              PU294 -C2         A01X+099442Y+016951X0090Y    R270 S1      
327GND              PU294 -B2         A01X+099639Y+016951X0090Y    R270 S1      
317GND              VIA   -    MD0100PA00X+100644Y+017684X0200Y    R270 S0      
317GND              VIA   -    MD0100PA00X+099251Y+018455X0200Y    R270 S0      
317GND              VIA   -    MD0100PA00X+099642Y+018455X0200Y    R270 S0      
317GND              VIA   -    MD0100PA00X+099992Y+018455X0200Y    R270 S0      
317GND              VIA   -    MD0100PA00X+099321Y+017805X0200Y    R270 S0      
317GND              VIA   -    MD0100PA00X+099331Y+017495X0200Y    R270 S0      
327GND              PC2209-2          A01X+100570Y+017442X0198Y0197R090 S1      
327GND              PR3970-2          A01X+099992Y+018215X0198Y0197R090 S1      
327GND              PR3968-2          A01X+099642Y+018215X0198Y0197R090 S1      
327GND              PU294 -C1         A01X+099442Y+017148X0090Y    R270 S1      
327GND              PC2207-2          A01X+100980Y+017528X0198Y0197R180 S1      
317GND              VIA   -    MD0100PA00X+091739Y+017950X0200Y         S0      
327GND              J90   -A6         A01X+091339Y+017939X0150Y0500R090 S1      
327GND              J90   -A5         A01X+091339Y+017703X0150Y0500R090 S1      
327GND              J90   -A4         A01X+091339Y+017466X0150Y0500R090 S1      
327GND              J90   -A3         A01X+091339Y+017230X0150Y0500R090 S1      
327GND              J90   -A2         A01X+091339Y+016994X0150Y0500R090 S1      
327GND              J90   -A1         A01X+091339Y+016758X0150Y0500R090 S1      
327GND              U279  -4          A01X+085969Y+017633X0240Y0460R270 S1      
317GND              VIA   -    M      A01X+086349Y+017633X0200Y    R180 S2      
017GND              VIA   -    M      A18X+086349Y+017633X0260Y    R180 S2      
017GND                    -    MD0100PA00X+086349Y+017633                       
327GND              Q125  -4          A01X+076124Y+017264X0170Y0200R270 S1      
317GND              VIA   -    M      A01X+075811Y+017264X0200Y    R180 S2      
017GND              VIA   -    M      A18X+075811Y+017264X0260Y    R180 S2      
017GND                    -    MD0100PA00X+075811Y+017264                       
317GND              VIA   -    MD0100PA00X+071420Y+017786X0200Y    R270 S0      
317GND              VIA   -    MD0100PA00X+071420Y+017287X0200Y    R270 S0      
317GND              VIA   -    MD0100PA00X+071920Y+017786X0200Y    R270 S0      
317GND              VIA   -    MD0100PA00X+071920Y+017287X0200Y    R270 S0      
327GND              J59   -45         A01X+069728Y+017835X0110Y0630R270 S1      
317GND              VIA   -    MD0100PA00X+070193Y+017835X0200Y         S0      
327GND              J59   -51         A01X+069728Y+017244X0110Y0630R270 S1      
317GND              VIA   -    MD0100PA00X+070193Y+017244X0200Y         S0      
317GND              VIA   -    MD0100PA00X+064944Y+017700X0200Y         S0      
327GND              R138  -2          A01X+064944Y+017420X0198Y0197     S1      
317GND              VIA   -    MD0100PA00X+059968Y+017553X0200Y    R270 S0      
327GND              U98   -1   M      A01X+059520Y+017553X0140Y0590R270 S1      
327GND              C1323 -2   M      A01X+058819Y+017812X0198Y0197R090 S1      
317GND              VIA   -    MD0100PA00X+058568Y+017812X0200Y    R270 S0      
317GND              VIA   -    M      A01X+044600Y+017070X0200Y         S2      
017GND              VIA   -    M      A18X+044600Y+017070X0260Y         S2      
017GND                    -    MD0100PA00X+044600Y+017070                       
317GND              H32   -1   M      A01X+039521Y+018524X1780Y         S3      
017GND              H32   -1   M      A18X+039521Y+018524X3150Y         S3      
017GND                    -    MD1500PA00X+039521Y+018524                       
327GND              U207  -3          A01X+032922Y+017861X0140Y0490     S1      
317GND              VIA   -    M      A01X+032648Y+018286X0200Y    R270 S2      
017GND              VIA   -    M      A18X+032648Y+018286X0260Y    R270 S2      
017GND                    -    MD0100PA00X+032648Y+018286                       
317GND              H31   -1   M      A01X+027710Y+018524X1780Y         S3      
017GND              H31   -1   M      A18X+027710Y+018524X3150Y         S3      
017GND                    -    MD1500PA00X+027710Y+018524                       
317GND              VIA   -    MD0100PA00X+184787Y+015912X0200Y    R090 S0      
327GND              R6045 -2          A01X+184787Y+016183X0198Y0197     S1      
327GND              R1265 -2          A18X+168735Y+015376X0198Y0197     S2      
317GND              VIA   -    MD0100PA00X+168492Y+015376X0200Y    R090 S0      
327GND              R6044 -2          A18X+168735Y+016176X0198Y0197     S2      
317GND              VIA   -    MD0100PA00X+168492Y+016176X0200Y    R090 S0      
317GND              VIA   -    MD0100PA00X+166510Y+015676X0200Y    R090 S0      
327GND              U116  -2          A01X+145367Y+015687X0140Y0630R180 S1      
317GND              VIA   -    MD0100PA00X+145367Y+015217X0200Y    R180 S0      
317GND              VIA   -    MD0100PA00X+143831Y+015217X0200Y    R180 S0      
327GND              U116  -8          A01X+143831Y+015687X0140Y0630R180 S1      
327GND              R1785 -2          A01X+128968Y+016205X0198Y0197     S1      
317GND              VIA   -    MD0100PA00X+129208Y+016205X0200Y         S0      
327GND              R2843 -2          A01X+128968Y+016605X0198Y0197     S1      
317GND              VIA   -    MD0100PA00X+129208Y+016605X0200Y         S0      
317GND              VIA   -    MD0100PA00X+126358Y+016005X0200Y         S0      
327GND              C2194 -2          A01X+126118Y+015573X0198Y0197     S1      
327GND              C2050 -2   M      A01X+126118Y+016005X0198Y0197     S1      
327GND              C2047 -2          A01X+126118Y+016405X0198Y0197     S1      
317GND              VIA   -    MD0100PA00X+126358Y+016405X0200Y         S0      
327GND              R3668 -2          A01X+120244Y+016099X0198Y0197R180 S1      
317GND              VIA   -    M      A01X+120004Y+016099X0200Y    R180 S2      
017GND              VIA   -    M      A18X+120004Y+016099X0260Y    R180 S2      
017GND                    -    MD0100PA00X+120004Y+016099                       
327GND              R3670 -2          A01X+120244Y+016499X0198Y0197R180 S1      
317GND              VIA   -    MD0100PA00X+120004Y+016499X0200Y    R180 S0      
317GND              VIA   -    MD0100PA00X+099974Y+015794X0200Y    R270 S0      
327GND              PC2215-2          A01X+100574Y+015787X0198Y0197R270 S1      
327GND              PU294 -B7         A01X+099639Y+015967X0090Y    R270 S1      
327GND              PU294 -A7         A01X+099836Y+015967X0090Y    R270 S1      
317GND              VIA   -    M      A01X+100274Y+015794X0200Y    R270 S2      
017GND              VIA   -    M      A18X+100274Y+015794X0260Y    R270 S2      
017GND                    -    MD0100PA00X+100274Y+015794                       
317GND              J90   -G1  MD0440PA00X+092244Y+015431X0640Y1370R090 S3      
317GND              H77   -1   M      A01X+090020Y+017518X1660Y1970     S3      
017GND              H77   -1   M      A18X+090020Y+017518X1580Y         S3      
017GND                    -    MD0790PA00X+090020Y+017518                       
327GND              C1998 -2          A01X+087430Y+016636X0198Y0197     S1      
317GND              VIA   -    M      A01X+087430Y+016386X0200Y    R180 S2      
017GND              VIA   -    M      A18X+087430Y+016386X0260Y    R180 S2      
017GND                    -    MD0100PA00X+087430Y+016386                       
327GND              C1997 -2          A01X+085190Y+016276X0198Y0197     S1      
317GND              VIA   -    M      A01X+085190Y+016014X0200Y         S2      
017GND              VIA   -    M      A18X+085190Y+016014X0260Y         S2      
017GND                    -    MD0100PA00X+085190Y+016014                       
327GND              Q125  -1          A01X+076872Y+016752X0170Y0200R270 S1      
317GND              VIA   -    M      A01X+077136Y+016752X0200Y         S2      
017GND              VIA   -    M      A18X+077136Y+016752X0260Y         S2      
017GND                    -    MD0100PA00X+077136Y+016752                       
317GND              VIA   -    M      A01X+074491Y+016689X0200Y    R270 S2      
017GND              VIA   -    M      A18X+074491Y+016689X0260Y    R270 S2      
017GND                    -    MD0100PA00X+074491Y+016689                       
327GND              J59   -57         A01X+069728Y+016654X0110Y0630R270 S1      
317GND              VIA   -    MD0100PA00X+070193Y+016654X0200Y         S0      
327GND              J59   -G2         A01X+069423Y+014449X0490Y1100R270 S1      
327GND              J59   -75         A01X+069728Y+014882X0110Y0630R270 S1      
327GND              J59   -73         A01X+069728Y+015079X0110Y0630R270 S1      
317GND              VIA   -    MD0100PA00X+069252Y+015248X0200Y         S0      
317GND              VIA   -    MD0100PA00X+068852Y+015248X0200Y         S0      
317GND              VIA   -    MD0100PA00X+068452Y+015248X0200Y         S0      
327GND              J59   -71         A01X+069728Y+015276X0110Y0630R270 S1      
317GND              VIA   -    MD0100PA00X+061860Y+016075X0200Y    R180 S0      
327GND              C1861 -2          A01X+059526Y+016064X0198Y0197R090 S1      
317GND              VIA   -    MD0100PA00X+059398Y+016444X0200Y    R090 S0      
327GND              C1859 -2          A01X+056646Y+016064X0198Y0197R090 S1      
317GND              VIA   -    M      A01X+056395Y+016064X0200Y    R270 S2      
017GND              VIA   -    M      A18X+056395Y+016064X0260Y    R270 S2      
017GND                    -    MD0100PA00X+056395Y+016064                       
327GND              R6209 -2          A01X+055441Y+015274X0198Y0197     S1      
317GND              VIA   -    MD0100PA00X+055681Y+015274X0200Y    R270 S0      
327GND              R6278 -2          A01X+049307Y+017162X0198Y0197     S1      
317GND              VIA   -    MD0100PA00X+049420Y+015880X0200Y         S0      
327GND              R6284 -2          A01X+045800Y+016370X0198Y0197R090 S1      
317GND              VIA   -    M      A01X+045800Y+016640X0200Y    R090 S2      
017GND              VIA   -    M      A18X+045800Y+016640X0260Y    R090 S2      
017GND                    -    MD0100PA00X+045800Y+016640                       
327GND              R6281 -2          A01X+046600Y+016370X0198Y0197R090 S1      
317GND              VIA   -    M      A01X+046600Y+016640X0200Y    R090 S2      
017GND              VIA   -    M      A18X+046600Y+016640X0260Y    R090 S2      
017GND                    -    MD0100PA00X+046600Y+016640                       
327GND              R6288 -2          A01X+044200Y+016370X0198Y0197R090 S1      
317GND              VIA   -    M      A01X+044200Y+016640X0200Y    R090 S2      
017GND              VIA   -    M      A18X+044200Y+016640X0260Y    R090 S2      
017GND                    -    MD0100PA00X+044200Y+016640                       
327GND              R6293 -2          A01X+043000Y+016370X0198Y0197R090 S1      
317GND              VIA   -    M      A01X+043000Y+016640X0200Y    R090 S2      
017GND              VIA   -    M      A18X+043000Y+016640X0260Y    R090 S2      
017GND                    -    MD0100PA00X+043000Y+016640                       
327GND              U217  -3          A01X+039164Y+015794X0170Y0240R090 S1      
317GND              VIA   -    M      A01X+039164Y+016109X0200Y    R180 S2      
017GND              VIA   -    M      A18X+039164Y+016109X0260Y    R180 S2      
017GND                    -    MD0100PA00X+039164Y+016109                       
327GND              C1821 -2          A01X+033749Y+016517X0198Y0197     S1      
317GND              VIA   -    M      A01X+033991Y+016517X0200Y    R090 S2      
017GND              VIA   -    M      A18X+033991Y+016517X0260Y    R090 S2      
017GND                    -    MD0100PA00X+033991Y+016517                       
317GND              VIA   -    MD0100PA00X+029455Y+015382X0200Y         S0      
317GND              VIA   -    M      A01X+029962Y+015871X0200Y         S2      
017GND              VIA   -    M      A18X+029962Y+015871X0260Y         S2      
017GND                    -    MD0100PA00X+029962Y+015871                       
327GND              C2017 -2          A01X+029963Y+015620X0198Y0197     S1      
317GND              VIA   -    MD0100PA00X+028852Y+015706X0200Y         S0      
317GND              VIA   -    MD0100PA00X+028395Y+015251X0200Y         S0      
317GND              VIA   -    MD0100PA00X+026457Y+015521X0200Y         S0      
327GND              R3609 -1          A01X+026698Y+015520X0198Y0197     S1      
317GND              VIA   -    M      A01X+026457Y+015921X0200Y         S2      
017GND              VIA   -    M      A18X+026457Y+015921X0260Y         S2      
017GND                    -    MD0100PA00X+026457Y+015921                       
327GND              R3608 -1          A01X+026698Y+015920X0198Y0197     S1      
317GND              VIA   -    MD0100PA00X+024225Y+016252X0200Y         S0      
327GND              Q119  -1          A01X+024226Y+016016X0170Y0200R090 S1      
327GND              R4066 -2          A01X+023044Y+015907X0198Y0197R180 S1      
317GND              VIA   -    M      A01X+023365Y+016207X0200Y         S2      
017GND              VIA   -    M      A18X+023365Y+016207X0260Y         S2      
017GND                    -    MD0100PA00X+023365Y+016207                       
317GND              VIA   -    MD0100PA00X+175485Y+030393X0200Y    R270 S0      
317GND              VIA   -    MD0100PA00X+175225Y+030385X0200Y    R270 S0      
327GND              VIA   -           A18X+181926Y+029546X0260Y         S2      
327GND              VIA   -           A18X+178661Y+022894X0260Y    R270 S2      
327GND              VIA   -           A18X+177161Y+022894X0260Y    R270 S2      
327GND              VIA   -           A18X+175661Y+022894X0260Y    R270 S2      
327GND              VIA   -           A18X+177161Y+024394X0260Y    R180 S2      
327GND              VIA   -           A18X+178661Y+024394X0260Y    R180 S2      
327GND              VIA   -           A18X+180161Y+024394X0260Y    R180 S2      
327GND              VIA   -           A18X+181661Y+024394X0260Y    R180 S2      
327GND              PC1870-2          A01X+177850Y+018691X0198Y0197R180 S1      
317GND              VIA   -    MD0100PA00X+177850Y+018379X0200Y         S0      
327GND              PC2344-2          A18X+177235Y+018353X0400Y0500R270 S2      
327GND              PC1869-2          A18X+180730Y+025746X0198Y0197R090 S2      
327GND              PC1600-2          A18X+179980Y+025543X0400Y0500R270 S2      
327GND              PC1599-2          A18X+179178Y+025543X0400Y0500R270 S2      
327GND              PC1868-2          A18X+178330Y+025543X0400Y0500R270 S2      
327GND              PC571 -2          A18X+177082Y+021156X0400Y0500R090 S2      
327GND              PC8071-2          A18X+177786Y+021157X0400Y0500R090 S2      
317GND              VIA   -    MD0100PA00X+181953Y+032032X0200Y         S0      
317GND              H6000 -1   MD1470PA00X+176158Y+015913X2440Y         S3      
317GND              H6001 -1   MD1470PA00X+183815Y+020193X2440Y         S3      
327GND              PC8008-2          A01X+181217Y+018580X0280Y0320R180 S1      
327GND              PC591 -2          A01X+181767Y+019180X0280Y0320R180 S1      
317GND              VIA   -    MD0100PA00X+181767Y+018870X0200Y    R180 S0      
317GND              VIA   -    MD0100PA00X+179772Y+018661X0200Y    R270 S0      
327GND              PU9   -32         A01X+179626Y+018973X0110Y0240R180 S1      
317GND              VIA   -    MD0100PA00X+179522Y+018591X0200Y    R180 S0      
327GND              PU9   -31         A01X+179429Y+018973X0110Y0240R180 S1      
317GND              VIA   -    MD0100PA00X+180771Y+017508X0200Y    R180 S0      
327GND              C5015 -2          A18X+181105Y+017487X0198Y0197     S2      
327GND              PR834 -2          A01X+180771Y+018057X0198Y0197R270 S1      
317GND              VIA   -    MD0100PA00X+180771Y+017808X0200Y    R180 S0      
327GND              PR830 -2          A01X+180051Y+018057X0198Y0197R270 S1      
327GND              PR832 -2   M      A01X+180411Y+018057X0198Y0197R270 S1      
317GND              VIA   -    MD0100PA00X+180411Y+017808X0200Y    R180 S0      
327GND              PR833 -2          A01X+178981Y+018057X0198Y0197R270 S1      
317GND              VIA   -    MD0100PA00X+178981Y+017808X0200Y    R180 S0      
317GND              VIA   -    MD0100PA00X+175032Y+017983X0200Y         S0      
317GND              VIA   -    MD0100PA00X+175991Y+017989X0200Y         S0      
317GND              VIA   -    MD0100PA00X+176438Y+017989X0200Y         S0      
317GND              VIA   -    MD0100PA00X+175738Y+017989X0200Y         S0      
317GND              VIA   -    MD0100PA00X+175285Y+017983X0200Y         S0      
317GND              VIA   -    MD0100PA00X+176691Y+017989X0200Y         S0      
317GND              VIA   -    MD0100PA00X+177391Y+017989X0200Y         S0      
317GND              VIA   -    MD0100PA00X+177138Y+017989X0200Y         S0      
317GND              VIA   -    MD0100PA00X+177911Y+021509X0200Y         S0      
317GND              VIA   -    MD0100PA00X+177658Y+021509X0200Y         S0      
317GND              VIA   -    MD0100PA00X+177211Y+021509X0200Y         S0      
317GND              VIA   -    MD0100PA00X+176958Y+021509X0200Y         S0      
317GND              VIA   -    MD0100PA00X+178345Y+021296X0200Y         S0      
317GND              VIA   -    MD0100PA00X+180826Y+021323X0200Y    R270 S0      
327GND              R3118 -2   M      A18X+179164Y+019097X0198Y0197R270 S2      
317GND              VIA   -    MD0100PA00X+179144Y+019750X0200Y    R180 S0      
317GND              VIA   -    MD0100PA00X+179164Y+019340X0200Y    R180 S0      
317GND              VIA   -    MD0100PA00X+179602Y+020203X0200Y    R180 S0      
317GND              VIA   -    MD0100PA00X+180314Y+019870X0200Y    R180 S0      
317GND              VIA   -    MD0100PA00X+179963Y+019887X0200Y    R180 S0      
317GND              VIA   -    MD0100PA00X+179536Y+019757X0200Y    R180 S0      
317GND              VIA   -    MD0100PA00X+180304Y+019340X0200Y    R180 S0      
317GND              VIA   -    MD0100PA00X+180039Y+019342X0200Y    R180 S0      
317GND              VIA   -    MD0100PA00X+179762Y+019337X0200Y    R180 S0      
317GND              VIA   -    MD0100PA00X+179463Y+019332X0200Y    R180 S0      
317GND              VIA   -    MD0100PA00X+180524Y+020465X0200Y    R180 S0      
317GND              VIA   -    MD0100PA00X+180012Y+020186X0200Y    R180 S0      
317GND              VIA   -    MD0100PA00X+180316Y+019613X0200Y    R180 S0      
317GND              VIA   -    MD0100PA00X+180228Y+020471X0200Y    R180 S0      
317GND              VIA   -    MD0100PA00X+180524Y+020895X0200Y    R180 S0      
317GND              VIA   -    MD0100PA00X+179591Y+020913X0200Y    R180 S0      
317GND              VIA   -    MD0100PA00X+180228Y+020901X0200Y    R180 S0      
317GND              VIA   -    MD0100PA00X+179894Y+020904X0200Y    R180 S0      
317GND              VIA   -    MD0100PA00X+179595Y+020558X0200Y    R180 S0      
317GND              VIA   -    MD0100PA00X+179894Y+020474X0200Y    R180 S0      
327GND              PU9   -7_10M      A01X+179724Y+020130X1841Y2087R090 S1      
317GND              VIA   -    MD0100PA00X+181051Y+021466X0200Y    R270 S0      
317GND              VIA   -    MD0100PA00X+181311Y+021466X0200Y    R270 S0      
317GND              VIA   -    MD0100PA00X+181308Y+021185X0200Y    R270 S0      
317GND              VIA   -    MD0100PA00X+181048Y+021185X0200Y    R270 S0      
317GND              VIA   -    MD0100PA00X+174832Y+021643X0200Y         S0      
317GND              VIA   -    MD0100PA00X+176501Y+021649X0200Y         S0      
317GND              VIA   -    MD0100PA00X+176248Y+021649X0200Y         S0      
317GND              VIA   -    MD0100PA00X+175085Y+021643X0200Y         S0      
317GND              VIA   -    MD0100PA00X+175542Y+021643X0200Y         S0      
317GND              VIA   -    MD0100PA00X+175795Y+021643X0200Y         S0      
317GND              VIA   -    MD0100PA00X+180837Y+022638X0200Y    R270 S0      
317GND              VIA   -    MD0100PA00X+180837Y+022245X0200Y    R270 S0      
317GND              VIA   -    M      A01X+181161Y+022644X0200Y    R270 S2      
017GND              VIA   -    M      A18X+181161Y+022644X0260Y    R270 S2      
017GND                    -    MD0100PA00X+181161Y+022644                       
317GND              VIA   -    M      A01X+180843Y+021884X0200Y    R270 S2      
017GND              VIA   -    M      A18X+180843Y+021884X0260Y    R270 S2      
017GND                    -    MD0100PA00X+180843Y+021884                       
317GND              VIA   -    MD0100PA00X+181161Y+022251X0200Y    R270 S0      
317GND              VIA   -    MD0100PA00X+181167Y+021890X0200Y    R270 S0      
317GND              VIA   -    MD0100PA00X+177598Y+025378X0200Y    R180 S0      
317GND              VIA   -    MD0100PA00X+177598Y+025678X0200Y    R180 S0      
317GND              VIA   -    MD0100PA00X+177887Y+025680X0200Y         S0      
317GND              VIA   -    MD0100PA00X+177887Y+025380X0200Y         S0      
317GND              VIA   -    MD0100PA00X+178753Y+025377X0200Y         S0      
317GND              VIA   -    MD0100PA00X+178753Y+025677X0200Y         S0      
317GND              VIA   -    MD0100PA00X+179579Y+025372X0200Y         S0      
317GND              VIA   -    MD0100PA00X+179579Y+025672X0200Y         S0      
317GND              VIA   -    MD0100PA00X+180417Y+025674X0200Y         S0      
317GND              VIA   -    MD0100PA00X+180417Y+025374X0200Y         S0      
317GND              VIA   -    MD0100PA00X+180730Y+025503X0200Y         S0      
317GND              PC1866-2   MD0400PA00X+180000Y+029478X0600Y    R180 S3      
317GND              PC1867-2   MD0400PA00X+177044Y+029478X0600Y    R180 S3      
317GND              VIA   -    MD0100PA00X+176351Y+024834X0200Y    R180 S0      
317GND              VIA   -    MD0100PA00X+176640Y+024836X0200Y         S0      
317GND              VIA   -    MD0100PA00X+176351Y+025134X0200Y    R180 S0      
317GND              VIA   -    MD0100PA00X+176640Y+025136X0200Y         S0      
317GND              VIA   -    MD0100PA00X+175597Y+024852X0200Y    R180 S0      
317GND              VIA   -    MD0100PA00X+175886Y+024854X0200Y         S0      
317GND              VIA   -    MD0100PA00X+175597Y+025152X0200Y    R180 S0      
317GND              VIA   -    MD0100PA00X+175886Y+025154X0200Y         S0      
317GND              VIA   -    MD0100PA00X+174957Y+025232X0200Y    R180 S0      
317GND              VIA   -    MD0100PA00X+175246Y+025234X0200Y         S0      
317GND              VIA   -    MD0100PA00X+174957Y+025532X0200Y    R180 S0      
317GND              VIA   -    MD0100PA00X+175246Y+025534X0200Y         S0      
327GND              PC1649-2   M      A01X+173036Y+017453X0198Y0197R090 S1      
317GND              VIA   -    MD0100PA00X+173036Y+017759X0200Y         S0      
317GND              VIA   -    MD0100PA00X+183764Y+015928X0200Y    R090 S0      
327GND              Q123  -1          A01X+183512Y+015928X0170Y0200R270 S1      
327GND              Q123  -4          A01X+182764Y+016439X0170Y0200R270 S1      
317GND              VIA   -    MD0100PA00X+182511Y+016439X0200Y    R270 S0      
317GND              VIA   -    MD0100PA00X+181257Y+015928X0200Y    R090 S0      
327GND              Q124  -4          A01X+181004Y+015928X0170Y0200R090 S1      
317GND              VIA   -    MD0100PA00X+180004Y+016439X0200Y    R270 S0      
327GND              Q124  -1          A01X+180256Y+016439X0170Y0200R090 S1      
327GND              R4069 -2          A01X+178982Y+016183X0198Y0197R180 S1      
317GND              VIA   -    MD0100PA00X+178739Y+016183X0200Y    R270 S0      
317GND              VIA   -    MD0100PA00X+181816Y+014932X0200Y         S0      
327GND              C36   -2          A01X+181816Y+015183X0198Y0197     S1      
317GND              VIA   -    MD0100PA00X+180552Y+014672X0200Y    R090 S0      
327GND              U8082 -3          A01X+180280Y+014672X0170Y0240R270 S1      
327GND              PC2262-2          A01X+175079Y+018360X0400Y0500R090 S1      
327GND              PC576 -2          A01X+176485Y+018353X0400Y0500R090 S1      
327GND              PC2260-2          A01X+175785Y+018353X0400Y0500R090 S1      
327GND              PC2343-2          A01X+177185Y+018353X0400Y0500R090 S1      
327GND              PC8567-2          A01X+177085Y+021156X0400Y0500R270 S1      
327GND              PC570 -2          A01X+177785Y+021156X0400Y0500R270 S1      
327GND              PC577 -2          A01X+178345Y+021053X0198Y0197R090 S1      
327GND              PC581 -2          A01X+181183Y+020840X0280Y0320     S1      
327GND              PC2263-2          A01X+174983Y+021290X0400Y0500R270 S1      
327GND              PC2342-2          A01X+176398Y+021296X0400Y0500R270 S1      
327GND              PC2261-2          A01X+175692Y+021290X0400Y0500R270 S1      
327GND              C1333 -2          A01X+176507Y+025553X0400Y0500R090 S1      
327GND              C60   -2          A01X+175797Y+025543X0400Y0500R090 S1      
327GND              C1332 -2          A01X+175198Y+025806X0198Y0197R270 S1      
327GND              C1340 -2          A01X+175207Y+029964X0400Y0500R180 S1      
327GND              C61   -2          A01X+174918Y+030511X0198Y0197     S1      
317GND              PC3   -2   MD0400PA00X+170128Y+020846X0600Y    R180 S3      
317GND              PC566 -2   MD0400PA00X+173166Y+020846X0600Y    R180 S3      
327GND              R6043 -1          A18X+168735Y+014976X0198Y0197R180 S2      
317GND              VIA   -    MD0100PA00X+168492Y+014976X0200Y    R090 S0      
327GND              R1508 -1          A01X+165495Y+014176X0198Y0197     S1      
317GND              VIA   -    M      A01X+165252Y+014176X0200Y    R270 S2      
017GND              VIA   -    M      A18X+165252Y+014176X0260Y    R270 S2      
017GND                    -    MD0100PA00X+165252Y+014176                       
327GND              C1757 -2          A01X+129827Y+014574X0198Y0197     S1      
317GND              VIA   -    M      A01X+130067Y+014574X0200Y         S2      
017GND              VIA   -    M      A18X+130067Y+014574X0260Y         S2      
017GND                    -    MD0100PA00X+130067Y+014574                       
327GND              C1768 -2          A01X+130208Y+015122X0400Y0500R180 S1      
317GND              VIA   -    MD0100PA00X+130643Y+015283X0200Y         S0      
317GND              VIA   -    M      A01X+130643Y+014933X0200Y         S2      
017GND              VIA   -    M      A18X+130643Y+014933X0260Y         S2      
017GND                    -    MD0100PA00X+130643Y+014933                       
327GND              U193  -15         A01X+128074Y+014255X0150Y0630R090 S1      
317GND              VIA   -    MD0100PA00X+128539Y+014255X0200Y         S0      
327GND              R4568 -2          A01X+127569Y+015003X0198Y0197     S1      
317GND              VIA   -    MD0100PA00X+127811Y+015003X0200Y         S0      
327GND              U193  -4          A01X+125984Y+013755X0150Y0630R090 S1      
317GND              VIA   -    MD0100PA00X+125518Y+013755X0200Y    R180 S0      
327GND              U193  -2          A01X+125984Y+014255X0150Y0630R090 S1      
317GND              VIA   -    MD0100PA00X+125518Y+014255X0200Y    R180 S0      
327GND              U193  -3          A01X+125984Y+014005X0150Y0630R090 S1      
317GND              VIA   -    MD0100PA00X+125518Y+014005X0200Y    R180 S0      
327GND              C1347 -2          A01X+123112Y+014524X0198Y0197R180 S1      
317GND              VIA   -    M      A01X+123112Y+014212X0200Y    R180 S2      
017GND              VIA   -    M      A18X+123112Y+014212X0260Y    R180 S2      
017GND                    -    MD0100PA00X+123112Y+014212                       
327GND              C1767 -2          A01X+121719Y+014574X0400Y0500     S1      
317GND              VIA   -    MD0100PA00X+121843Y+014153X0200Y    R180 S0      
317GND              VIA   -    MD0100PA00X+121593Y+014153X0200Y    R180 S0      
327GND              PD114 -A          A01X+102192Y+015080X0520Y0560R090 S1      
317GND              VIA   -    MD0100PA00X+102319Y+014658X0200Y         S0      
317GND              VIA   -    MD0100PA00X+102066Y+014658X0200Y         S0      
317GND              H76   -1   M      A01X+094468Y+015520X1660Y1970     S3      
017GND              H76   -1   M      A18X+094468Y+015520X1580Y         S3      
017GND                    -    MD0790PA00X+094468Y+015520                       
317GND              VIA   -    MD0100PA00X+082912Y+015027X0200Y    R090 S0      
327GND              C2014 -2          A01X+082661Y+015027X0198Y0197R090 S1      
317GND              VIA   -    MD0100PA00X+082450Y+014520X0200Y    R090 S0      
327GND              U265  -10         A01X+082450Y+014241X0090Y0240     S1      
327GND              Q39   -S          A01X+076677Y+014344X0320Y0360     S1      
317GND              VIA   -    M      A01X+077007Y+014344X0200Y         S2      
017GND              VIA   -    M      A18X+077007Y+014344X0260Y         S2      
017GND                    -    MD0100PA00X+077007Y+014344                       
317GND              VIA   -    MD0100PA00X+072413Y+014129X0200Y    R180 S0      
327GND              PC2231-2          A01X+072393Y+013856X0198Y0197R090 S1      
317GND              VIA   -    MD0100PA00X+062557Y+015018X0200Y         S0      
327GND              C1663 -2          A01X+063506Y+014622X0198Y0197R090 S1      
317GND              VIA   -    MD0100PA00X+056847Y+014923X0200Y    R270 S0      
327GND              U235  -4          A01X+057230Y+014923X0240Y0460R090 S1      
327GND              C6058 -2          A18X+054746Y+015249X0198Y0197R180 S2      
327GND              C6059 -2          A18X+054746Y+015649X0198Y0197R180 S2      
327GND              C6069 -2          A18X+054746Y+016449X0198Y0197R180 S2      
327GND              C6070 -2          A18X+054746Y+016049X0198Y0197R180 S2      
327GND              C6042 -2          A18X+055338Y+014389X0280Y0320     S2      
327GND              C6044 -2          A18X+054468Y+014057X0198Y0197R270 S2      
327GND              C6045 -2          A18X+054868Y+014057X0198Y0197R270 S2      
327GND              C6056 -2          A18X+054746Y+014849X0198Y0197R180 S2      
327GND              C6057 -2          A18X+054746Y+014449X0198Y0197R180 S2      
317GND              VIA   -    MD0100PA00X+054980Y+014700X0200Y    R270 S0      
317GND              VIA   -    MD0100PA00X+055330Y+016450X0200Y    R270 S0      
317GND              VIA   -    MD0100PA00X+051442Y+014117X0200Y    R270 S0      
317GND              VIA   -    MD0100PA00X+051842Y+013717X0200Y         S0      
317GND              VIA   -    MD0100PA00X+051442Y+014917X0200Y    R090 S0      
317GND              VIA   -    MD0100PA00X+052642Y+013717X0200Y    R180 S0      
317GND              VIA   -    MD0100PA00X+053042Y+014117X0200Y    R270 S0      
317GND              VIA   -    MD0100PA00X+053042Y+014917X0200Y    R090 S0      
317GND              VIA   -    MD0100PA00X+051336Y+016919X0200Y    R090 S0      
327GND              C6048 -2          A18X+053017Y+013321X0198Y0197R180 S2      
327GND              C6043 -2          A18X+054838Y+013042X0198Y0197R090 S2      
327GND              C6064 -2          A18X+051500Y+012450X0198Y0197R180 S2      
327GND              C6051 -2          A18X+051909Y+012528X0198Y0197R270 S2      
327GND              C6080 -2          A18X+050750Y+013250X0198Y0197     S2      
327GND              C6081 -2          A18X+050750Y+013650X0198Y0197     S2      
327GND              C6082 -2          A18X+050750Y+012850X0198Y0197     S2      
327GND              C6076 -2          A18X+050358Y+013097X0198Y0197R270 S2      
327GND              C6075 -2          A18X+049958Y+013097X0198Y0197R270 S2      
327GND              C6074 -2          A18X+049597Y+014754X0198Y0197     S2      
327GND              C6073 -2          A18X+049597Y+014354X0198Y0197     S2      
327GND              C6055 -2          A18X+049597Y+013860X0198Y0197     S2      
327GND              C6078 -2          A18X+050862Y+016672X0198Y0197R270 S2      
327GND              C6077 -2          A18X+050462Y+016672X0198Y0197R270 S2      
327GND              C6079 -2          A18X+049959Y+016732X0280Y0320     S2      
327GND              C6030 -2          A18X+053724Y+015863X0280Y0320R180 S2      
327GND              C6068 -2          A18X+053402Y+015321X0198Y0197     S2      
327GND              C6031 -2          A18X+052929Y+016694X0198Y0197     S2      
327GND              C6035 -2          A18X+052929Y+015792X0198Y0197     S2      
327GND              C6034 -2          A18X+052929Y+016192X0198Y0197     S2      
327GND              C6040 -2          A18X+051762Y+015987X0198Y0197R090 S2      
327GND              C6041 -2          A18X+051362Y+015987X0198Y0197R090 S2      
327GND              C6033 -2          A18X+052162Y+015987X0198Y0197R090 S2      
327GND              C6032 -2          A18X+052562Y+015987X0198Y0197R090 S2      
327GND              C6071 -2          A18X+050871Y+015790X0198Y0197R180 S2      
327GND              C6072 -2          A18X+050871Y+015390X0198Y0197R180 S2      
327GND              C6036 -2          A18X+053402Y+014521X0198Y0197     S2      
327GND              C6037 -2          A18X+053402Y+014121X0198Y0197     S2      
327GND              C6039 -2          A18X+053402Y+013721X0198Y0197     S2      
327GND              C6067 -2          A18X+053402Y+014921X0198Y0197     S2      
327GND              C6062 -2          A18X+050467Y+014762X0198Y0197R270 S2      
327GND              C6063 -2          A18X+050867Y+014762X0198Y0197R270 S2      
327GND              C6054 -2          A18X+050750Y+014050X0198Y0197R180 S2      
327GND              C6061 -2          A18X+049565Y+015147X0198Y0197R090 S2      
327GND              C6060 -2          A18X+049965Y+015147X0198Y0197R090 S2      
327GND              C6038 -2          A18X+053402Y+013321X0198Y0197     S2      
327GND              C6047 -2          A18X+053888Y+012706X0198Y0197R270 S2      
327GND              C6052 -2          A18X+053488Y+012706X0198Y0197R270 S2      
327GND              C6053 -2          A18X+053017Y+012921X0198Y0197R180 S2      
327GND              C6046 -2          A18X+054375Y+012942X0280Y0320     S2      
327GND              C6049 -2          A18X+052309Y+013228X0198Y0197R270 S2      
327GND              C6050 -2          A18X+051909Y+013228X0198Y0197R270 S2      
327GND              C6065 -2          A18X+051458Y+013157X0198Y0197R270 S2      
317GND              VIA   -    MD0100PA00X+050316Y+014990X0200Y    R270 S0      
317GND              VIA   -    MD0100PA00X+053042Y+013717X0200Y    R180 S0      
317GND              VIA   -    MD0100PA00X+052242Y+013717X0200Y    R180 S0      
317GND              VIA   -    MD0100PA00X+051442Y+014517X0200Y    R090 S0      
317GND              VIA   -    MD0100PA00X+051442Y+015317X0200Y    R090 S0      
317GND              VIA   -    MD0100PA00X+052242Y+015317X0200Y    R090 S0      
317GND              VIA   -    MD0100PA00X+053042Y+015317X0200Y    R090 S0      
317GND              VIA   -    MD0100PA00X+053042Y+014517X0200Y    R090 S0      
317GND              VIA   -    MD0100PA00X+048858Y+014194X0200Y         S0      
317GND              VIA   -    MD0100PA00X+047963Y+014194X0200Y         S0      
327GND              R6325 -2          A01X+040063Y+014430X0198Y0197R090 S1      
317GND              VIA   -    MD0100PA00X+040314Y+014430X0200Y         S0      
327GND              R6326 -2          A01X+040557Y+014430X0198Y0197R180 S1      
327GND              C1824 -2          A01X+038957Y+014294X0198Y0197     S1      
317GND              VIA   -    M      A01X+038771Y+014744X0200Y         S2      
017GND              VIA   -    M      A18X+038771Y+014744X0260Y         S2      
017GND                    -    MD0100PA00X+038771Y+014744                       
327GND              C1822 -2          A01X+037592Y+014908X0198Y0197R180 S1      
317GND              VIA   -    M      A01X+037592Y+014658X0200Y         S2      
017GND              VIA   -    M      A18X+037592Y+014658X0260Y         S2      
017GND                    -    MD0100PA00X+037592Y+014658                       
317GND              VIA   -    M      A01X+029963Y+014920X0200Y         S2      
017GND              VIA   -    M      A18X+029963Y+014920X0260Y         S2      
017GND                    -    MD0100PA00X+029963Y+014920                       
327GND              C2012 -2          A01X+029963Y+015170X0198Y0197     S1      
317GND              VIA   -    M      A01X+026289Y+014739X0200Y    R270 S2      
017GND              VIA   -    M      A18X+026289Y+014739X0260Y    R270 S2      
017GND                    -    MD0100PA00X+026289Y+014739                       
327GND              R6060 -2          A01X+026289Y+014488X0198Y0197     S1      
327GND              Q119  -4          A01X+024974Y+015504X0170Y0200R090 S1      
317GND              VIA   -    M      A01X+024974Y+015269X0200Y         S2      
017GND              VIA   -    M      A18X+024974Y+015269X0260Y         S2      
017GND                    -    MD0100PA00X+024974Y+015269                       
327GND              Q118  -1          A01X+024970Y+014432X0170Y0200R270 S1      
317GND              VIA   -    M      A01X+025220Y+014432X0200Y    R180 S2      
017GND              VIA   -    M      A18X+025220Y+014432X0260Y    R180 S2      
017GND                    -    MD0100PA00X+025220Y+014432                       
327GND              Q118  -4          A01X+024222Y+014944X0170Y0200R270 S1      
317GND              VIA   -    M      A01X+024222Y+015179X0200Y    R180 S2      
017GND              VIA   -    M      A18X+024222Y+015179X0260Y    R180 S2      
017GND                    -    MD0100PA00X+024222Y+015179                       
327GND              R3207 -2          A01X+019600Y+014496X0198Y0197     S1      
317GND              VIA   -    M      A01X+020549Y+014279X0200Y         S2      
017GND              VIA   -    M      A18X+020549Y+014279X0260Y         S2      
017GND                    -    MD0100PA00X+020549Y+014279                       
327GND              PU204 -7          A01X+173761Y+011644X0100Y0320R180 S1      
317GND              VIA   -    MD0100PA00X+173647Y+013495X0200Y         S0      
317GND              VIA   -    MD0100PA00X+173334Y+013495X0200Y         S0      
327GND              PC2155-2          A01X+173642Y+012824X0198Y0197R090 S1      
327GND              PC2156-2          A01X+172942Y+012824X0198Y0197R090 S1      
327GND              PR3837-2          A01X+172542Y+012824X0198Y0197R090 S1      
327GND              PC2153-2          A01X+174692Y+012824X0198Y0197R090 S1      
327GND              PR3835-2          A01X+174342Y+013174X0198Y0197R090 S1      
317GND              VIA   -    MD0100PA00X+167310Y+012676X0200Y    R270 S0      
317GND              VIA   -    MD0100PA00X+149224Y+012384X0200Y         S0      
317GND              VIA   -    MD0100PA00X+149554Y+013124X0200Y         S0      
327GND              C2344 -2          A01X+148382Y+012568X0198Y0197R270 S1      
317GND              VIA   -    MD0100PA00X+148382Y+012271X0200Y         S0      
317GND              VIA   -    MD0100PA00X+146302Y+013637X0200Y    R090 S0      
327GND              C1352 -2          A01X+146051Y+013637X0198Y0197R270 S1      
327GND              C1354 -2          A01X+145882Y+012824X0198Y0197     S1      
317GND              VIA   -    MD0100PA00X+146124Y+012824X0200Y    R090 S0      
327GND              U116  -10         A01X+144087Y+013482X0140Y0630R180 S1      
317GND              VIA   -    MD0100PA00X+144087Y+013012X0200Y    R180 S0      
327GND              C2042 -2          A01X+129827Y+012974X0198Y0197     S1      
317GND              VIA   -    MD0100PA00X+130067Y+012974X0200Y         S0      
327GND              C35   -2          A18X+129655Y+013441X0198Y0197R180 S2      
317GND              VIA   -    MD0100PA00X+130067Y+013374X0200Y         S0      
327GND              C2045 -2          A01X+129827Y+013374X0198Y0197     S1      
327GND              C2043 -2          A01X+129827Y+012574X0198Y0197     S1      
317GND              VIA   -    M      A01X+130067Y+012574X0200Y         S2      
017GND              VIA   -    M      A18X+130067Y+012574X0260Y         S2      
017GND                    -    MD0100PA00X+130067Y+012574                       
317GND              VIA   -    MD0100PA00X+123922Y+012374X0200Y    R180 S0      
327GND              C2044 -2          A01X+124162Y+012374X0198Y0197R180 S1      
317GND              VIA   -    MD0100PA00X+123922Y+013274X0200Y    R180 S0      
327GND              C2176 -2          A01X+124162Y+013274X0198Y0197R180 S1      
327GND              C1344 -2          A01X+124162Y+013724X0198Y0197R180 S1      
317GND              VIA   -    M      A01X+123922Y+013724X0200Y    R180 S2      
017GND              VIA   -    M      A18X+123922Y+013724X0260Y    R180 S2      
017GND                    -    MD0100PA00X+123922Y+013724                       
327GND              C59   -2          A01X+124162Y+012824X0198Y0197R180 S1      
317GND              VIA   -    M      A01X+123922Y+012824X0200Y    R180 S2      
017GND              VIA   -    M      A18X+123922Y+012824X0260Y    R180 S2      
017GND                    -    MD0100PA00X+123922Y+012824                       
317GND              BT2   -2   MD0400PA00X+107764Y+013387X0600Y    R270 S3      
317GND              VIA   -    MD0100PA00X+082112Y+013463X0200Y         S0      
317GND              VIA   -    MD0100PA00X+082570Y+013906X0200Y         S0      
327GND              U265  -TH  M      A01X+082351Y+013690X0670Y0670R090 S1      
327GND              C2019 -2          A18X+082112Y+013939X0198Y0197R090 S2      
317GND              VIA   -    MD0100PA00X+070724Y+012395X0200Y         S0      
327GND              PU299 -2          A01X+070549Y+011944X0100Y0320R180 S1      
327GND              PC2340-2          A18X+070785Y+012712X0198Y0197R090 S2      
317GND              VIA   -    MD0100PA00X+070414Y+012260X0200Y         S0      
327GND              PU299 -3          A01X+070352Y+011944X0100Y0320R180 S1      
327GND              PR3999-2          A01X+070096Y+013130X0198Y0197R090 S1      
327GND              PC2232-2          A01X+069445Y+013124X0198Y0197R090 S1      
327GND              PC2229-2          A01X+070495Y+013124X0198Y0197R090 S1      
327GND              PR4005-2          A01X+068345Y+013124X0198Y0197R090 S1      
327GND              PC2235-2          A01X+068745Y+013124X0198Y0197R090 S1      
317GND              VIA   -    MD0100PA00X+069106Y+013141X0200Y         S0      
317GND              VIA   -    MD0100PA00X+070557Y+013376X0200Y         S0      
327GND              PU299 -7          A01X+069565Y+011944X0100Y0320R180 S1      
327GND              U157  -3          A01X+064239Y+012805X0220Y0320     S1      
317GND              VIA   -    M      A01X+064239Y+013117X0200Y         S2      
017GND              VIA   -    M      A18X+064239Y+013117X0260Y         S2      
017GND                    -    MD0100PA00X+064239Y+013117                       
317GND              VIA   -    MD0100PA00X+057086Y+012751X0200Y         S0      
317GND              VIA   -    MD0100PA00X+056521Y+012582X0200Y         S0      
317GND              VIA   -    MD0100PA00X+057651Y+012582X0200Y         S0      
317GND              VIA   -    MD0100PA00X+055378Y+012714X0200Y         S0      
327GND              C6066 -2          A18X+049836Y+012307X0280Y0320R090 S2      
317GND              VIA   -    MD0100PA00X+049230Y+012439X0200Y         S0      
317GND              VIA   -    MD0100PA00X+049628Y+013144X0200Y         S0      
317GND              VIA   -    MD0100PA00X+048788Y+013144X0200Y         S0      
317GND              VIA   -    MD0100PA00X+048226Y+013572X0200Y         S0      
317GND              VIA   -    MD0100PA00X+048226Y+012732X0200Y         S0      
317GND              VIA   -    MD0100PA00X+047830Y+012802X0200Y         S0      
317GND              VIA   -    MD0100PA00X+047090Y+012802X0200Y         S0      
317GND              VIA   -    MD0100PA00X+041449Y+012418X0200Y         S0      
317GND              VIA   -    MD0100PA00X+041449Y+012758X0200Y         S0      
327GND              R345  -2          A01X+040944Y+012410X0120Y0150R090 S1      
317GND              VIA   -    MD0100PA00X+041195Y+012305X0200Y    R180 S0      
327GND              R343  -2          A01X+040944Y+013170X0120Y0150R270 S1      
317GND              VIA   -    MD0100PA00X+041195Y+013275X0200Y    R180 S0      
317GND              VIA   -    MD0100PA00X+040261Y+012606X0200Y         S0      
317GND              VIA   -    MD0100PA00X+040261Y+012946X0200Y         S0      
317GND              VIA   -    M      A01X+036677Y+012766X0200Y         S2      
017GND              VIA   -    M      A18X+036677Y+012766X0260Y         S2      
017GND                    -    MD0100PA00X+036677Y+012766                       
327GND              C38   -2          A01X+036677Y+013016X0198Y0197     S1      
327GND              U219  -3          A01X+037100Y+013516X0220Y0320R270 S1      
317GND              VIA   -    M      A01X+036687Y+013516X0200Y         S2      
017GND              VIA   -    M      A18X+036687Y+013516X0260Y         S2      
017GND                    -    MD0100PA00X+036687Y+013516                       
327GND              R3235 -2          A01X+022406Y+012466X0198Y0197     S1      
317GND              VIA   -    M      A01X+022406Y+012715X0200Y    R270 S2      
017GND              VIA   -    M      A18X+022406Y+012715X0260Y    R270 S2      
017GND                    -    MD0100PA00X+022406Y+012715                       
327GND              C1841 -2          A01X+020306Y+012865X0198Y0197R090 S1      
317GND              VIA   -    M      A01X+020306Y+013116X0200Y         S2      
017GND              VIA   -    M      A18X+020306Y+013116X0260Y         S2      
017GND                    -    MD0100PA00X+020306Y+013116                       
327GND              C1825 -2          A01X+019086Y+012865X0198Y0197R090 S1      
317GND              VIA   -    M      A01X+018725Y+012967X0200Y    R090 S2      
017GND              VIA   -    M      A18X+018725Y+012967X0260Y    R090 S2      
017GND                    -    MD0100PA00X+018725Y+012967                       
317GND              VIA   -    MD0100PA00X+174745Y+012141X0200Y         S0      
327GND              PU204 -2          A01X+174745Y+011644X0100Y0320R180 S1      
317GND              VIA   -    MD0100PA00X+174545Y+011958X0200Y         S0      
327GND              PU204 -3          A01X+174548Y+011644X0100Y0320R180 S1      
317GND              VIA   -    MD0100PA00X+168492Y+011876X0200Y    R090 S0      
327GND              R6041 -1          A18X+168735Y+011876X0198Y0197R180 S2      
317GND              VIA   -    MD0100PA00X+152292Y+011991X0200Y         S0      
327GND              Q61   -S          A01X+140882Y+010904X0400Y0480R270 S1      
317GND              VIA   -    MD0100PA00X+140492Y+010904X0200Y    R270 S0      
327GND              U86   -3          A01X+136063Y+011620X0220Y0530R180 S1      
317GND              VIA   -    MD0100PA00X+136063Y+012038X0200Y    R180 S0      
317GND              JP12  -3   MD0410PA00X+129944Y+011281X0610Y    R180 S3      
317GND              VIA   -    MD0100PA00X+130786Y+011135X0200Y    R180 S0      
327GND              C1567 -2          A01X+130786Y+010893X0198Y0197R090 S1      
317GND              VIA   -    MD0100PA00X+126615Y+012102X0200Y         S0      
317GND              VIA   -    MD0100PA00X+083112Y+011522X0200Y    R090 S0      
327GND              R3613 -1          A01X+083111Y+011762X0198Y0197R090 S1      
317GND              VIA   -    MD0100PA00X+081912Y+011522X0200Y    R090 S0      
327GND              R3612 -1          A01X+081911Y+011762X0198Y0197R090 S1      
317GND              VIA   -    M      A01X+063090Y+011892X0200Y    R180 S2      
017GND              VIA   -    M      A18X+063090Y+011892X0260Y    R180 S2      
017GND                    -    MD0100PA00X+063090Y+011892                       
317GND              VIA   -    MD0100PA00X+057086Y+011831X0200Y         S0      
317GND              VIA   -    MD0100PA00X+055378Y+011874X0200Y         S0      
327GND              R6203 -1          A01X+054313Y+012326X0198Y0197R090 S1      
317GND              VIA   -    MD0100PA00X+054640Y+012070X0200Y         S0      
317GND              VIA   -    MD0100PA00X+053517Y+011763X0200Y         S0      
317GND              VIA   -    MD0100PA00X+053517Y+010873X0200Y         S0      
317GND              VIA   -    MD0100PA00X+051602Y+011177X0200Y         S0      
317GND              VIA   -    MD0100PA00X+052142Y+010983X0200Y         S0      
327GND              R340  -2          A01X+052037Y+010732X0120Y0150R180 S1      
317GND              VIA   -    MD0100PA00X+051114Y+010983X0200Y         S0      
327GND              R339  -2          A01X+051167Y+010732X0120Y0150     S1      
327GND              C6119 -2          A18X+046261Y+011204X0198Y0197R180 S2      
327GND              C6117 -2          A18X+046261Y+010804X0198Y0197R180 S2      
327GND              C6112 -2          A18X+042075Y+012178X0198Y0197R090 S2      
327GND              C6114 -2          A18X+043109Y+013657X0198Y0197R090 S2      
327GND              C6109 -2          A18X+042719Y+013657X0198Y0197R090 S2      
327GND              C6115 -2          A18X+043499Y+013657X0198Y0197R090 S2      
327GND              C6110 -2          A18X+044279Y+013657X0198Y0197R090 S2      
327GND              C6111 -2          A18X+043889Y+013657X0198Y0197R090 S2      
327GND              C6105 -2          A18X+044809Y+013174X0400Y0500R270 S2      
327GND              C6092 -2          A18X+043288Y+012830X0198Y0197R180 S2      
327GND              C6095 -2          A18X+043288Y+013230X0198Y0197R180 S2      
327GND              C6093 -2          A18X+043288Y+012421X0198Y0197R180 S2      
327GND              C6121 -2          A18X+043288Y+012021X0198Y0197R180 S2      
327GND              C6096 -2          A18X+042973Y+011458X0198Y0197R270 S2      
327GND              C6104 -2          A18X+043323Y+011458X0198Y0197R270 S2      
327GND              C6102 -2          A18X+042205Y+011794X0198Y0197R270 S2      
327GND              C6099 -2          A18X+042555Y+011794X0198Y0197R270 S2      
327GND              C6120 -2          A18X+045946Y+010089X0198Y0197R090 S2      
327GND              C6116 -2          A18X+045546Y+010089X0198Y0197R090 S2      
327GND              C6118 -2          A18X+045160Y+012001X0400Y0500R180 S2      
327GND              C6108 -2          A18X+045289Y+011358X0198Y0197R270 S2      
327GND              C6107 -2          A18X+044889Y+011358X0198Y0197R270 S2      
327GND              C6106 -2          A18X+044662Y+010249X0198Y0197     S2      
327GND              C6113 -2          A18X+044662Y+010649X0198Y0197     S2      
327GND              C6100 -2          A18X+042487Y+010454X0198Y0197R090 S2      
327GND              C6101 -2          A18X+042087Y+010454X0198Y0197R090 S2      
327GND              C6097 -2          A18X+042887Y+010454X0198Y0197R090 S2      
327GND              C6103 -2          A18X+043287Y+010454X0198Y0197R090 S2      
327GND              C6094 -2          A18X+044087Y+010454X0198Y0197R090 S2      
327GND              C6098 -2          A18X+043687Y+010454X0198Y0197R090 S2      
317GND              VIA   -    MD0100PA00X+044809Y+011601X0200Y    R180 S0      
317GND              VIA   -    MD0100PA00X+043609Y+012001X0200Y    R090 S0      
317GND              VIA   -    MD0100PA00X+044009Y+013201X0200Y         S0      
317GND              VIA   -    MD0100PA00X+043609Y+012801X0200Y         S0      
317GND              VIA   -    MD0100PA00X+045209Y+012801X0200Y         S0      
317GND              VIA   -    MD0100PA00X+043609Y+013201X0200Y    R180 S0      
317GND              VIA   -    MD0100PA00X+044409Y+013201X0200Y    R180 S0      
317GND              VIA   -    MD0100PA00X+045209Y+013201X0200Y         S0      
317GND              VIA   -    MD0100PA00X+045209Y+012401X0200Y         S0      
317GND              VIA   -    MD0100PA00X+045209Y+011601X0200Y         S0      
317GND              VIA   -    MD0100PA00X+043609Y+011601X0200Y    R180 S0      
317GND              VIA   -    MD0100PA00X+044409Y+011601X0200Y    R270 S0      
317GND              VIA   -    MD0100PA00X+043609Y+012401X0200Y    R180 S0      
317GND              VIA   -    MD0100PA00X+039743Y+011622X0200Y         S0      
317GND              VIA   -    MD0100PA00X+039743Y+011282X0200Y         S0      
327GND              R344  -2          A01X+040624Y+011845X0120Y0150R270 S1      
317GND              VIA   -    MD0100PA00X+040373Y+011898X0200Y         S0      
327GND              R346  -2          A01X+040624Y+011085X0120Y0150R090 S1      
317GND              VIA   -    M      A01X+040373Y+011033X0200Y         S2      
017GND              VIA   -    M      A18X+040373Y+011033X0260Y         S2      
017GND                    -    MD0100PA00X+040373Y+011033                       
327GND              C6089 -2          A01X+038670Y+012376X0198Y0197R270 S1      
327GND              R6333 -2   M      A01X+039086Y+012381X0198Y0197R270 S1      
317GND              VIA   -    M      A01X+039160Y+012118X0200Y         S2      
017GND              VIA   -    M      A18X+039160Y+012118X0260Y         S2      
017GND                    -    MD0100PA00X+039160Y+012118                       
317GND              VIA   -    M      A01X+034304Y+012252X0200Y         S2      
017GND              VIA   -    M      A18X+034304Y+012252X0260Y         S2      
017GND                    -    MD0100PA00X+034304Y+012252                       
327GND              U225  -3          A01X+020818Y+011302X0170Y0240     S1      
317GND              VIA   -    M      A01X+021411Y+011302X0200Y         S2      
017GND              VIA   -    M      A18X+021411Y+011302X0260Y         S2      
017GND                    -    MD0100PA00X+021411Y+011302                       
327GND              U286  -3          A01X+019598Y+011302X0170Y0240     S1      
317GND              VIA   -    M      A01X+019598Y+010946X0200Y         S2      
017GND              VIA   -    M      A18X+019598Y+010946X0260Y         S2      
017GND                    -    MD0100PA00X+019598Y+010946                       
317GND              VIA   -    MD0100PA00X+171555Y+010292X0200Y         S0      
327GND              R1897 -2          A18X+171280Y+010428X0198Y0197R090 S2      
317GND              VIA   -    MD0100PA00X+144687Y+010513X0200Y         S0      
327GND              C363  -2          A01X+144687Y+010829X0198Y0197R270 S1      
317GND              VIA   -    MD0100PA00X+143451Y+010695X0200Y         S0      
327GND              C364  -2          A01X+143451Y+010982X0198Y0197R270 S1      
327GND              C219  -2          A01X+137126Y+010051X0198Y0197     S1      
317GND              VIA   -    M      A01X+137126Y+009800X0200Y         S2      
017GND              VIA   -    M      A18X+137126Y+009800X0260Y         S2      
017GND                    -    MD0100PA00X+137126Y+009800                       
327GND              C5032 -2          A01X+131251Y+009403X0400Y0500R090 S1      
317GND              VIA   -    MD0100PA00X+130645Y+009218X0200Y         S0      
327GND              Q30   -S          A01X+131967Y+010133X0400Y0480R180 S1      
317GND              VIA   -    M      A01X+131967Y+010523X0200Y    R180 S2      
017GND              VIA   -    M      A18X+131967Y+010523X0260Y    R180 S2      
017GND                    -    MD0100PA00X+131967Y+010523                       
327GND              C553  -2          A01X+125315Y+010110X0198Y0197R090 S1      
317GND              VIA   -    M      A01X+125606Y+010110X0200Y         S2      
017GND              VIA   -    M      A18X+125606Y+010110X0260Y         S2      
017GND                    -    MD0100PA00X+125606Y+010110                       
327GND              C22   -2          A01X+121316Y+009485X0198Y0197     S1      
317GND              VIA   -    MD0100PA00X+121558Y+009485X0200Y    R180 S0      
317GND              VIA   -    M      A01X+120052Y+010088X0200Y         S2      
017GND              VIA   -    M      A18X+120052Y+010088X0260Y         S2      
017GND                    -    MD0100PA00X+120052Y+010088                       
317GND              VIA   -    MD0100PA00X+117743Y+009356X0200Y         S0      
327GND              C45   -2          A01X+117500Y+009356X0198Y0197     S1      
317GND              VIA   -    MD0100PA00X+075463Y+010529X0200Y         S0      
327GND              PU300 -B7         A01X+075291Y+010194X0090Y         S1      
327GND              PU300 -A7         A01X+075291Y+010391X0090Y         S1      
317GND              VIA   -    MD0100PA00X+075463Y+010829X0200Y         S0      
327GND              PC2237-2          A01X+075471Y+011129X0198Y0197     S1      
317GND              VIA   -    MD0100PA00X+073452Y+009876X0200Y         S0      
317GND              VIA   -    MD0100PA00X+073762Y+009886X0200Y         S0      
317GND              VIA   -    MD0100PA00X+072799Y+010548X0200Y         S0      
317GND              VIA   -    MD0100PA00X+072990Y+009809X0200Y         S0      
317GND              VIA   -    MD0100PA00X+072799Y+010198X0200Y         S0      
327GND              PC2234-1          A01X+072995Y+009516X0198Y0197     S1      
327GND              PR4008-2          A01X+073043Y+010547X0198Y0197R180 S1      
327GND              PR4004-2          A01X+073043Y+010197X0198Y0197R180 S1      
327GND              PU300 -C2         A01X+074307Y+009997X0090Y         S1      
327GND              PU300 -C1         A01X+074110Y+009997X0090Y         S1      
327GND              PU300 -B2         A01X+074307Y+010194X0090Y         S1      
317GND              VIA   -    MD0100PA00X+073573Y+011199X0200Y         S0      
327GND              PC2230-2          A01X+073734Y+011566X0198Y0197R270 S1      
327GND              PC2233-2          A01X+073816Y+011125X0198Y0197R180 S1      
317GND              VIA   -    MD0100PA00X+071342Y+010206X0200Y    R180 S0      
327GND              PC2241-2          A01X+071000Y+010331X0198Y0197     S1      
317GND              VIA   -    MD0100PA00X+068495Y+010497X0200Y         S0      
327GND              PC2239-2          A01X+068464Y+010176X0280Y0320R090 S1      
327GND              PR4011-2          A01X+068464Y+010881X0198Y0197R270 S1      
327GND              PC2240-2          A18X+068542Y+009706X0400Y0500R180 S2      
317GND              VIA   -    M      A01X+058010Y+009644X0200Y         S2      
017GND              VIA   -    M      A18X+058010Y+009644X0260Y         S2      
017GND                    -    MD0100PA00X+058010Y+009644                       
327GND              C6000 -2          A01X+058219Y+009325X0198Y0197R090 S1      
317GND              VIA   -    MD0100PA00X+053862Y+009329X0200Y    R135 S0      
317GND              VIA   -    MD0100PA00X+051924Y+009497X0200Y         S0      
317GND              VIA   -    MD0100PA00X+051602Y+010287X0200Y         S0      
317GND              VIA   -    MD0100PA00X+052383Y+010293X0200Y    R270 S0      
317GND              VIA   -    MD0100PA00X+052383Y+009544X0200Y    R270 S0      
317GND              VIA   -    MD0100PA00X+051265Y+009497X0200Y         S0      
327GND              Y9    -2   M      A01X+049305Y+011724X0360Y0400R180 S1      
327GND              Y9    -4   M      A01X+048695Y+010996X0360Y0400R180 S1      
327GND              C91   -2   M      A01X+049838Y+010812X0198Y0197R270 S1      
317GND              VIA   -    MD0100PA00X+050282Y+010698X0200Y         S0      
317GND              VIA   -    MD0100PA00X+049481Y+010597X0200Y         S0      
317GND              VIA   -    MD0100PA00X+048759Y+010597X0200Y         S0      
317GND              VIA   -    MD0100PA00X+049230Y+012139X0200Y         S0      
317GND              VIA   -    MD0100PA00X+050084Y+011909X0200Y         S0      
327GND              C93   -2   M      A01X+049831Y+011849X0198Y0197R090 S1      
317GND              VIA   -    MD0100PA00X+045706Y+009310X0200Y         S0      
317GND              VIA   -    MD0100PA00X+046446Y+009310X0200Y         S0      
317GND              VIA   -    MD0100PA00X+044301Y+009238X0200Y         S0      
317GND              VIA   -    MD0100PA00X+045041Y+009238X0200Y         S0      
327GND              R6330 -1          A01X+040624Y+010250X0198Y0197R090 S1      
317GND              VIA   -    M      A01X+040624Y+010008X0200Y    R180 S2      
017GND              VIA   -    M      A18X+040624Y+010008X0260Y    R180 S2      
017GND                    -    MD0100PA00X+040624Y+010008                       
327GND              PC2087-1          A01X+176049Y+007680X0198Y0197     S1      
317GND              VIA   -    MD0100PA00X+176503Y+008044X0200Y         S0      
317GND              VIA   -    MD0100PA00X+175853Y+007974X0200Y         S0      
317GND              VIA   -    MD0100PA00X+175854Y+008365X0200Y         S0      
317GND              VIA   -    MD0100PA00X+175854Y+008715X0200Y         S0      
327GND              PR3781-2          A01X+176097Y+008711X0198Y0197R180 S1      
327GND              PR5484-2          A01X+176097Y+008361X0198Y0197R180 S1      
317GND              VIA   -    MD0100PA00X+176813Y+008054X0200Y         S0      
327GND              PU203 -C2         A01X+177361Y+008161X0090Y         S1      
327GND              PU203 -C1         A01X+177164Y+008161X0090Y         S1      
327GND              PU203 -B2         A01X+177361Y+008358X0090Y         S1      
317GND              VIA   -    MD0100PA00X+176624Y+009367X0200Y         S0      
317GND              VIA   -    MD0100PA00X+175436Y+010035X0200Y    R180 S0      
327GND              PC2085-2          A01X+176870Y+009289X0198Y0197R180 S1      
327GND              PC2079-2          A01X+176789Y+009724X0198Y0197R270 S1      
317GND              VIA   -    MD0100PA00X+171089Y+008221X0200Y         S0      
327GND              R1929 -1          A01X+171180Y+007884X0198Y0197R270 S1      
317GND              VIA   -    MD0100PA00X+170111Y+007784X0200Y         S0      
317GND              VIA   -    MD0100PA00X+170609Y+007784X0200Y         S0      
317GND              VIA   -    MD0100PA00X+168409Y+007784X0200Y         S0      
317GND              VIA   -    MD0100PA00X+167911Y+007784X0200Y         S0      
317GND              VIA   -    MD0100PA00X+165698Y+007784X0200Y         S0      
317GND              VIA   -    MD0100PA00X+166206Y+007784X0200Y         S0      
317GND              VIA   -    MD0100PA00X+163996Y+007784X0200Y         S0      
317GND              VIA   -    MD0100PA00X+163498Y+007784X0200Y         S0      
317GND              VIA   -    MD0100PA00X+161676Y+007784X0200Y         S0      
317GND              VIA   -    MD0100PA00X+161178Y+007784X0200Y         S0      
317GND              VIA   -    MD0100PA00X+159476Y+007784X0200Y         S0      
317GND              VIA   -    MD0100PA00X+158978Y+007784X0200Y         S0      
317GND              VIA   -    MD0100PA00X+156778Y+007784X0200Y         S0      
317GND              VIA   -    MD0100PA00X+157276Y+007784X0200Y         S0      
317GND              VIA   -    MD0100PA00X+154578Y+007784X0200Y         S0      
317GND              VIA   -    MD0100PA00X+155076Y+007784X0200Y         S0      
317GND              J13   -4   MD0320PA00X+145480Y+008743X0480Y    R180 S3      
327GND              Q12   -S          A01X+136981Y+008369X0400Y0480R180 S1      
317GND              VIA   -    M      A01X+136981Y+008759X0200Y    R180 S2      
017GND              VIA   -    M      A18X+136981Y+008759X0260Y    R180 S2      
017GND                    -    MD0100PA00X+136981Y+008759                       
327GND              Q11   -1          A01X+135687Y+008282X0170Y0200     S1      
317GND              VIA   -    M      A01X+135687Y+008532X0200Y    R180 S2      
017GND              VIA   -    M      A18X+135687Y+008532X0260Y    R180 S2      
017GND                    -    MD0100PA00X+135687Y+008532                       
327GND              Q2    -1          A01X+134496Y+008285X0170Y0200     S1      
317GND              VIA   -    M      A01X+134496Y+008536X0200Y    R180 S2      
017GND              VIA   -    M      A18X+134496Y+008536X0260Y    R180 S2      
017GND                    -    MD0100PA00X+134496Y+008536                       
327GND              Q29   -S          A01X+131967Y+008369X0400Y0480R180 S1      
317GND              VIA   -    M      A01X+131967Y+008759X0200Y    R180 S2      
017GND              VIA   -    M      A18X+131967Y+008759X0260Y    R180 S2      
017GND                    -    MD0100PA00X+131967Y+008759                       
327GND              Q28   -1          A01X+130170Y+008287X0170Y0200R090 S1      
317GND              VIA   -    MD0100PA00X+130470Y+007981X0200Y    R270 S0      
317GND              VIA   -    MD0100PA00X+123281Y+008864X0200Y    R180 S0      
327GND              U99   -3          A01X+123691Y+009047X0220Y0530R270 S1      
327GND              R1342 -2          A01X+123031Y+009106X0198Y0197R270 S1      
317GND              VIA   -    MD0100PA00X+123031Y+008864X0200Y    R180 S0      
327GND              C63   -2          A01X+122346Y+008892X0198Y0197R090 S1      
317GND              VIA   -    M      A01X+122346Y+009135X0200Y    R180 S2      
017GND              VIA   -    M      A18X+122346Y+009135X0260Y    R180 S2      
017GND                    -    MD0100PA00X+122346Y+009135                       
317GND              VIA   -    MD0100PA00X+121558Y+009135X0200Y    R180 S0      
327GND              C62   -2          A01X+121558Y+008892X0198Y0197R090 S1      
317GND              VIA   -    MD0100PA00X+118847Y+008016X0200Y    R270 S0      
327GND              Q8    -1          A01X+118847Y+008266X0170Y0200     S1      
317GND              VIA   -    MD0100PA00X+119149Y+009112X0200Y         S0      
327GND              R1776 -2          A01X+118906Y+009112X0198Y0197     S1      
327GND              C1563 -2          A01X+118906Y+008712X0198Y0197     S1      
317GND              VIA   -    M      A01X+119149Y+008712X0200Y         S2      
017GND              VIA   -    M      A18X+119149Y+008712X0260Y         S2      
017GND                    -    MD0100PA00X+119149Y+008712                       
317GND              VIA   -    MD0100PA00X+117743Y+008956X0200Y         S0      
327GND              C193  -2          A01X+117500Y+008956X0198Y0197     S1      
317GND              VIA   -    MD0100PA00X+117697Y+008679X0200Y    R090 S0      
327GND              U167  -1          A01X+117697Y+008349X0280Y0360R180 S1      
317GND              VIA   -    MD0100PA00X+085411Y+009123X0200Y         S0      
317GND              VIA   -    MD0100PA00X+085458Y+009965X0200Y    R090 S0      
327GND              U90   -4   M      A01X+084004Y+008145X0140Y0590R180 S1      
327GND              C1274 -2   M      A01X+083462Y+010421X0198Y0197R270 S1      
317GND              VIA   -    MD0100PA00X+083779Y+008519X0200Y         S0      
317GND              VIA   -    MD0100PA00X+083462Y+009432X0200Y         S0      
317GND              VIA   -    M      A01X+083130Y+010421X0200Y         S2      
017GND              VIA   -    M      A18X+083130Y+010421X0260Y         S2      
017GND                    -    MD0100PA00X+083130Y+010421                       
317GND              VIA   -    M      A01X+084286Y+011030X0200Y         S2      
017GND              VIA   -    M      A18X+084286Y+011030X0260Y         S2      
017GND                    -    MD0100PA00X+084286Y+011030                       
317GND              VIA   -    MD0100PA00X+072794Y+008897X0200Y         S0      
327GND              PR4002-2          A01X+072992Y+008700X0198Y0197R180 S1      
317GND              VIA   -    MD0100PA00X+068578Y+007877X0200Y         S0      
317GND              VIA   -    MD0100PA00X+068190Y+008221X0200Y         S0      
317GND              VIA   -    MD0100PA00X+068855Y+007917X0200Y         S0      
327GND              PC2238-2          A01X+069064Y+007696X0198Y0197R180 S1      
327GND              PC2242-2          A01X+068572Y+008336X0400Y0500     S1      
317GND              VIA   -    MD0100PA00X+067375Y+007809X0200Y         S0      
317GND              VIA   -    MD0100PA00X+067866Y+008808X0200Y         S0      
327GND              R87   -2          A01X+065382Y+008734X0198Y0197R090 S1      
317GND              VIA   -    MD0100PA00X+065382Y+009033X0200Y    R090 S0      
317GND              VIA   -    MD0100PA00X+066078Y+007833X0200Y         S0      
317GND              VIA   -    MD0100PA00X+055382Y+007752X0200Y         S0      
317GND              VIA   -    MD0100PA00X+054594Y+007752X0200Y         S0      
317GND              VIA   -    MD0100PA00X+054328Y+008863X0200Y    R135 S0      
317GND              VIA   -    MD0100PA00X+045750Y+008701X0200Y         S0      
317GND              VIA   -    MD0100PA00X+045010Y+008701X0200Y         S0      
327GND              R6331 -2   M      A01X+042968Y+009108X0198Y0197R270 S1      
327GND              R6332 -2          A01X+043368Y+009108X0198Y0197R270 S1      
317GND              VIA   -    M      A01X+042968Y+008866X0200Y    R180 S2      
017GND              VIA   -    M      A18X+042968Y+008866X0260Y    R180 S2      
017GND                    -    MD0100PA00X+042968Y+008866                       
317GND              VIA   -    MD0100PA00X+042556Y+008201X0200Y    R270 S0      
317GND              VIA   -    MD0100PA00X+041762Y+007907X0200Y    R180 S0      
327GND              Y6000 -4          A01X+041496Y+008335X0480Y0560R180 S1      
317GND              VIA   -    MD0100PA00X+042556Y+009201X0200Y    R270 S0      
327GND              Y6000 -2          A01X+042166Y+009201X0480Y0560R180 S1      
317GND              VIA   -    MD0100PA00X+041070Y+009915X0200Y    R090 S0      
327GND              C6090 -2          A01X+041313Y+009915X0198Y0197R180 S1      
317GND              VIA   -    MD0100PA00X+042338Y+009666X0200Y    R180 S0      
327GND              C6091 -2          A01X+042338Y+009915X0198Y0197     S1      
317GND              VIA   -    MD0100PA00X+022670Y+007784X0200Y         S0      
317GND              VIA   -    MD0100PA00X+023168Y+007784X0200Y         S0      
317GND              VIA   -    MD0100PA00X+020968Y+007784X0200Y         S0      
317GND              VIA   -    MD0100PA00X+020470Y+007784X0200Y         S0      
317GND              VIA   -    MD0100PA00X+018766Y+007784X0200Y         S0      
317GND              VIA   -    MD0100PA00X+018257Y+007784X0200Y         S0      
317GND              VIA   -    MD0100PA00X+016555Y+007784X0200Y         S0      
317GND              VIA   -    MD0100PA00X+016057Y+007784X0200Y         S0      
317GND              VIA   -    MD0100PA00X+014235Y+007784X0200Y         S0      
317GND              VIA   -    MD0100PA00X+013737Y+007784X0200Y         S0      
317GND              VIA   -    MD0100PA00X+012035Y+007784X0200Y         S0      
317GND              VIA   -    MD0100PA00X+011537Y+007784X0200Y         S0      
317GND              VIA   -    MD0100PA00X+009835Y+007784X0200Y         S0      
317GND              VIA   -    MD0100PA00X+009337Y+007784X0200Y         S0      
317GND              VIA   -    MD0100PA00X+007137Y+007784X0200Y         S0      
317GND              VIA   -    MD0100PA00X+007635Y+007784X0200Y         S0      
327GND              PR3788-2          A01X+176046Y+006864X0198Y0197R180 S1      
317GND              VIA   -    MD0100PA00X+175805Y+006864X0200Y         S0      
317GND              VIA   -    MD0100PA00X+170800Y+007534X0200Y    R180 S0      
317GND              VIA   -    MD0100PA00X+169509Y+007184X0200Y         S0      
317GND              VIA   -    MD0100PA00X+169509Y+006685X0200Y         S0      
317GND              VIA   -    MD0100PA00X+169920Y+007534X0200Y         S0      
317GND              VIA   -    MD0100PA00X+169700Y+006934X0200Y    R180 S0      
317GND              VIA   -    MD0100PA00X+170609Y+007285X0200Y         S0      
317GND              VIA   -    MD0100PA00X+170111Y+007285X0200Y         S0      
317GND              VIA   -    MD0100PA00X+168409Y+007285X0200Y         S0      
317GND              VIA   -    MD0100PA00X+168600Y+007534X0200Y    R180 S0      
317GND              VIA   -    MD0100PA00X+169011Y+007184X0200Y         S0      
317GND              VIA   -    MD0100PA00X+169011Y+006685X0200Y         S0      
317GND              VIA   -    MD0100PA00X+168820Y+006934X0200Y         S0      
317GND              VIA   -    MD0100PA00X+167911Y+007285X0200Y         S0      
317GND              VIA   -    MD0100PA00X+166607Y+006934X0200Y         S0      
317GND              VIA   -    MD0100PA00X+166798Y+007184X0200Y         S0      
317GND              VIA   -    MD0100PA00X+167487Y+006934X0200Y    R180 S0      
317GND              VIA   -    MD0100PA00X+167296Y+006685X0200Y         S0      
317GND              VIA   -    MD0100PA00X+166798Y+006685X0200Y         S0      
317GND              VIA   -    MD0100PA00X+167296Y+007184X0200Y         S0      
317GND              VIA   -    MD0100PA00X+166387Y+007534X0200Y    R180 S0      
317GND              VIA   -    MD0100PA00X+167720Y+007534X0200Y         S0      
317GND              VIA   -    MD0100PA00X+165096Y+007184X0200Y         S0      
317GND              VIA   -    MD0100PA00X+165698Y+007285X0200Y         S0      
317GND              VIA   -    MD0100PA00X+166206Y+007285X0200Y         S0      
317GND              VIA   -    MD0100PA00X+165507Y+007534X0200Y         S0      
317GND              VIA   -    MD0100PA00X+165287Y+006934X0200Y    R180 S0      
317GND              VIA   -    MD0100PA00X+165096Y+006685X0200Y         S0      
317GND              VIA   -    MD0100PA00X+164598Y+006685X0200Y         S0      
317GND              VIA   -    MD0100PA00X+164407Y+006934X0200Y         S0      
317GND              VIA   -    MD0100PA00X+164598Y+007184X0200Y         S0      
317GND              VIA   -    MD0100PA00X+164187Y+007534X0200Y    R180 S0      
317GND              VIA   -    MD0100PA00X+163996Y+007285X0200Y         S0      
317GND              VIA   -    MD0100PA00X+163498Y+007285X0200Y         S0      
317GND              VIA   -    MD0100PA00X+162086Y+006934X0200Y         S0      
317GND              VIA   -    MD0100PA00X+162278Y+006685X0200Y         S0      
317GND              VIA   -    MD0100PA00X+162776Y+006685X0200Y         S0      
317GND              VIA   -    MD0100PA00X+162278Y+007184X0200Y         S0      
317GND              VIA   -    MD0100PA00X+162776Y+007184X0200Y         S0      
317GND              VIA   -    MD0100PA00X+161867Y+007534X0200Y    R180 S0      
317GND              VIA   -    MD0100PA00X+163307Y+007534X0200Y         S0      
317GND              VIA   -    MD0100PA00X+162966Y+006934X0200Y         S0      
317GND              VIA   -    MD0100PA00X+160576Y+006685X0200Y         S0      
317GND              VIA   -    MD0100PA00X+160576Y+007184X0200Y         S0      
317GND              VIA   -    MD0100PA00X+160767Y+006934X0200Y    R180 S0      
317GND              VIA   -    MD0100PA00X+161676Y+007285X0200Y         S0      
317GND              VIA   -    MD0100PA00X+161178Y+007285X0200Y         S0      
317GND              VIA   -    MD0100PA00X+160987Y+007534X0200Y         S0      
317GND              VIA   -    MD0100PA00X+160078Y+006685X0200Y         S0      
317GND              VIA   -    MD0100PA00X+159887Y+006934X0200Y         S0      
317GND              VIA   -    MD0100PA00X+160078Y+007184X0200Y         S0      
317GND              VIA   -    MD0100PA00X+159667Y+007534X0200Y    R180 S0      
317GND              VIA   -    MD0100PA00X+159476Y+007285X0200Y         S0      
317GND              VIA   -    MD0100PA00X+158978Y+007285X0200Y         S0      
317GND              VIA   -    MD0100PA00X+158567Y+006934X0200Y    R180 S0      
317GND              VIA   -    MD0100PA00X+158376Y+006685X0200Y         S0      
317GND              VIA   -    MD0100PA00X+157878Y+006685X0200Y         S0      
317GND              VIA   -    MD0100PA00X+157687Y+006934X0200Y         S0      
317GND              VIA   -    MD0100PA00X+158376Y+007184X0200Y         S0      
317GND              VIA   -    MD0100PA00X+157878Y+007184X0200Y         S0      
317GND              VIA   -    MD0100PA00X+157467Y+007534X0200Y    R180 S0      
317GND              VIA   -    MD0100PA00X+158787Y+007534X0200Y         S0      
317GND              VIA   -    MD0100PA00X+156367Y+006934X0200Y    R180 S0      
317GND              VIA   -    MD0100PA00X+156176Y+006685X0200Y         S0      
317GND              VIA   -    MD0100PA00X+156778Y+007285X0200Y         S0      
317GND              VIA   -    MD0100PA00X+156587Y+007534X0200Y         S0      
317GND              VIA   -    MD0100PA00X+156176Y+007184X0200Y         S0      
317GND              VIA   -    MD0100PA00X+157276Y+007285X0200Y         S0      
317GND              VIA   -    MD0100PA00X+155678Y+006685X0200Y         S0      
317GND              VIA   -    MD0100PA00X+155487Y+006934X0200Y         S0      
317GND              VIA   -    MD0100PA00X+154578Y+007285X0200Y         S0      
317GND              VIA   -    MD0100PA00X+155076Y+007285X0200Y         S0      
317GND              VIA   -    MD0100PA00X+155678Y+007184X0200Y         S0      
317GND              VIA   -    MD0100PA00X+155266Y+007534X0200Y    R180 S0      
317GND              VIA   -    MD0100PA00X+154167Y+006934X0200Y    R180 S0      
317GND              VIA   -    MD0100PA00X+153287Y+006934X0200Y         S0      
317GND              VIA   -    MD0100PA00X+153478Y+006685X0200Y         S0      
317GND              VIA   -    MD0100PA00X+153976Y+006685X0200Y         S0      
317GND              VIA   -    MD0100PA00X+153478Y+007184X0200Y         S0      
317GND              VIA   -    MD0100PA00X+153976Y+007184X0200Y         S0      
317GND              VIA   -    MD0100PA00X+154386Y+007534X0200Y         S0      
327GND              D49   -C          A01X+136155Y+006456X0240Y0280R090 S1      
317GND              VIA   -    M      A01X+136155Y+006726X0200Y         S2      
017GND              VIA   -    M      A18X+136155Y+006726X0260Y         S2      
017GND                    -    MD0100PA00X+136155Y+006726                       
327GND              Q2    -4          A01X+133984Y+007537X0170Y0200     S1      
317GND              VIA   -    M      A01X+133984Y+007286X0200Y         S2      
017GND              VIA   -    M      A18X+133984Y+007286X0260Y         S2      
017GND                    -    MD0100PA00X+133984Y+007286                       
327GND              Q11   -4          A01X+135175Y+007534X0170Y0200     S1      
317GND              VIA   -    M      A01X+135175Y+007283X0200Y         S2      
017GND              VIA   -    M      A18X+135175Y+007283X0260Y         S2      
017GND                    -    MD0100PA00X+135175Y+007283                       
317GND              VIA   -    MD0100PA00X+130918Y+007475X0200Y    R270 S0      
327GND              Q28   -4          A01X+130918Y+007775X0170Y0200R090 S1      
327GND              Q8    -4          A01X+118335Y+007518X0170Y0200     S1      
317GND              VIA   -    M      A01X+118335Y+007768X0200Y    R090 S2      
017GND              VIA   -    M      A18X+118335Y+007768X0260Y    R090 S2      
017GND                    -    MD0100PA00X+118335Y+007768                       
327GND              C1564 -2          A01X+116620Y+007420X0198Y0197R270 S1      
317GND              VIA   -    M      A01X+116869Y+007420X0200Y         S2      
017GND              VIA   -    M      A18X+116869Y+007420X0260Y         S2      
017GND                    -    MD0100PA00X+116869Y+007420                       
317GND              VIA   -    MD0100PA00X+115558Y+007394X0200Y         S0      
327GND              C73   -2          A01X+115894Y+007394X0198Y0197R180 S1      
317GND              VIA   -    MD0100PA00X+083613Y+006268X0200Y         S0      
327GND              C1275 -2          A01X+083454Y+005863X0198Y0197     S1      
327GND              PD115 -A          A01X+075794Y+012642X0520Y0560R180 S1      
327GND              PD116 -A          A01X+076302Y+007924X0670Y0990R270 S1      
317GND              VIA   -    MD0100PA00X+076220Y+012968X0200Y    R180 S0      
317GND              VIA   -    MD0100PA00X+076220Y+012668X0200Y    R180 S0      
317GND              VIA   -    MD0100PA00X+076217Y+012390X0200Y         S0      
317GND              VIA   -    MD0100PA00X+076948Y+007536X0200Y         S0      
317GND              VIA   -    MD0100PA00X+075462Y+007456X0200Y         S0      
327GND              R1801 -2          A18X+075224Y+007603X0198Y0197R180 S2      
317GND              VIA   -    MD0100PA00X+074513Y+006951X0200Y         S0      
317GND              VIA   -    MD0100PA00X+073804Y+007153X0200Y         S0      
317GND              VIA   -    MD0100PA00X+073096Y+007101X0200Y         S0      
317GND              VIA   -    MD0100PA00X+068289Y+007264X0200Y         S0      
327GND              R6028 -2          A18X+068037Y+007563X0198Y0197     S2      
317GND              VIA   -    MD0100PA00X+068295Y+006998X0200Y         S0      
317GND              VIA   -    MD0100PA00X+066641Y+006951X0200Y         S0      
317GND              VIA   -    MD0100PA00X+064515Y+006951X0200Y         S0      
317GND              VIA   -    MD0100PA00X+061519Y+007053X0200Y         S0      
317GND              VIA   -    MD0100PA00X+060338Y+007051X0200Y         S0      
317GND              VIA   -    MD0100PA00X+056043Y+006951X0200Y         S0      
317GND              VIA   -    MD0100PA00X+055334Y+006951X0200Y         S0      
317GND              VIA   -    MD0100PA00X+054625Y+006951X0200Y         S0      
317GND              VIA   -    MD0100PA00X+053917Y+006951X0200Y         S0      
317GND              VIA   -    MD0100PA00X+053208Y+006951X0200Y         S0      
317GND              VIA   -    MD0100PA00X+052499Y+006951X0200Y         S0      
317GND              VIA   -    MD0100PA00X+051791Y+006951X0200Y         S0      
317GND              VIA   -    MD0100PA00X+051082Y+006956X0200Y         S0      
317GND              VIA   -    MD0100PA00X+047895Y+006498X0200Y         S0      
327GND              R4201 -2          A01X+047543Y+006498X0198Y0197     S1      
317GND              VIA   -    MD0100PA00X+046823Y+007002X0200Y    R270 S0      
327GND              C31   -2          A01X+046580Y+007002X0198Y0197     S1      
327GND              R6272 -2          A01X+042967Y+007712X0198Y0197R270 S1      
317GND              VIA   -    MD0100PA00X+043050Y+007290X0200Y         S0      
317GND              VIA   -    MD0100PA00X+041395Y+006927X0200Y         S0      
317GND              VIA   -    MD0100PA00X+025825Y+013379X0200Y         S0      
317GND              VIA   -    MD0100PA00X+026138Y+013379X0200Y         S0      
327GND              PC2166-2          A01X+026130Y+012712X0198Y0197R090 S1      
327GND              PC2167-2          A01X+025430Y+012712X0198Y0197R090 S1      
327GND              PR3849-2          A01X+025030Y+012712X0198Y0197R090 S1      
327GND              PC2164-2          A01X+027180Y+012712X0198Y0197R090 S1      
327GND              PR3847-2          A01X+026830Y+013062X0198Y0197R090 S1      
327GND              PU206 -7          A01X+026249Y+011532X0100Y0320R180 S1      
327GND              PD108 -A          A01X+032844Y+005975X0670Y0990R270 S1      
317GND              VIA   -    MD0100PA00X+028955Y+012181X0200Y    R180 S0      
327GND              PC2165-2          A01X+028936Y+011908X0198Y0197R090 S1      
317GND              VIA   -    MD0100PA00X+030175Y+012147X0200Y    R270 S0      
317GND              VIA   -    MD0100PA00X+031175Y+012147X0200Y    R270 S0      
317GND              VIA   -    MD0100PA00X+030175Y+012447X0200Y    R270 S0      
317GND              VIA   -    MD0100PA00X+030175Y+012747X0200Y    R270 S0      
327GND              PD107 -A          A01X+030675Y+012426X0520Y0560R270 S1      
317GND              VIA   -    MD0100PA00X+031175Y+012747X0200Y    R270 S0      
317GND              VIA   -    MD0100PA00X+031175Y+012447X0200Y    R270 S0      
317GND              VIA   -    MD0100PA00X+027236Y+012024X0200Y         S0      
327GND              PU206 -2          A01X+027233Y+011532X0100Y0320R180 S1      
317GND              VIA   -    MD0100PA00X+027036Y+011842X0200Y         S0      
327GND              PU206 -3          A01X+027036Y+011532X0100Y0320R180 S1      
317GND              VIA   -    MD0100PA00X+032005Y+008881X0200Y         S0      
317GND              VIA   -    MD0100PA00X+032005Y+008581X0200Y         S0      
327GND              PC2150-2          A01X+032013Y+009180X0198Y0197     S1      
327GND              PU201 -B7         A01X+031833Y+008246X0090Y         S1      
327GND              PU201 -A7         A01X+031833Y+008443X0090Y         S1      
327GND              PC2146-1          A01X+029537Y+007567X0198Y0197     S1      
317GND              VIA   -    MD0100PA00X+029994Y+007928X0200Y         S0      
317GND              VIA   -    MD0100PA00X+030304Y+007938X0200Y         S0      
317GND              VIA   -    MD0100PA00X+029345Y+008599X0200Y         S0      
317GND              VIA   -    MD0100PA00X+029345Y+008249X0200Y         S0      
317GND              VIA   -    MD0100PA00X+029344Y+007858X0200Y         S0      
327GND              PC2098-2          A01X+030208Y+009177X0198Y0197R180 S1      
327GND              PR3823-2          A01X+029585Y+008598X0198Y0197R180 S1      
327GND              PR3821-2          A01X+029585Y+008248X0198Y0197R180 S1      
327GND              PU201 -C2         A01X+030849Y+008049X0090Y         S1      
327GND              PU201 -C1         A01X+030652Y+008049X0090Y         S1      
327GND              PU201 -B2         A01X+030849Y+008246X0090Y         S1      
317GND              VIA   -    MD0100PA00X+027927Y+009919X0200Y    R180 S0      
317GND              VIA   -    MD0100PA00X+029965Y+009251X0200Y         S0      
327GND              PC2139-2          A01X+030132Y+009572X0198Y0197R270 S1      
317GND              VIA   -    MD0100PA00X+023360Y+007534X0200Y    R180 S0      
317GND              VIA   -    MD0100PA00X+022068Y+007184X0200Y         S0      
317GND              VIA   -    MD0100PA00X+022068Y+006685X0200Y         S0      
317GND              VIA   -    MD0100PA00X+023168Y+007285X0200Y         S0      
317GND              VIA   -    MD0100PA00X+022670Y+007285X0200Y         S0      
317GND              VIA   -    MD0100PA00X+022480Y+007534X0200Y         S0      
317GND              VIA   -    MD0100PA00X+022259Y+006934X0200Y    R180 S0      
317GND              VIA   -    MD0100PA00X+021570Y+007184X0200Y         S0      
317GND              VIA   -    MD0100PA00X+021570Y+006685X0200Y         S0      
317GND              VIA   -    MD0100PA00X+021379Y+006934X0200Y         S0      
317GND              VIA   -    MD0100PA00X+021160Y+007534X0200Y    R180 S0      
317GND              VIA   -    MD0100PA00X+020968Y+007285X0200Y         S0      
317GND              VIA   -    MD0100PA00X+020470Y+007285X0200Y         S0      
317GND              VIA   -    MD0100PA00X+020280Y+007534X0200Y         S0      
317GND              VIA   -    MD0100PA00X+018766Y+007285X0200Y         S0      
317GND              VIA   -    MD0100PA00X+020046Y+006934X0200Y    R180 S0      
317GND              VIA   -    MD0100PA00X+019855Y+006685X0200Y         S0      
317GND              VIA   -    MD0100PA00X+019357Y+006685X0200Y         S0      
317GND              VIA   -    MD0100PA00X+019166Y+006934X0200Y         S0      
317GND              VIA   -    MD0100PA00X+019855Y+007184X0200Y         S0      
317GND              VIA   -    MD0100PA00X+019357Y+007184X0200Y         S0      
317GND              VIA   -    MD0100PA00X+018946Y+007534X0200Y    R180 S0      
317GND              VIA   -    MD0100PA00X+018257Y+007285X0200Y         S0      
317GND              VIA   -    MD0100PA00X+018066Y+007534X0200Y         S0      
317GND              VIA   -    MD0100PA00X+017846Y+006934X0200Y    R180 S0      
317GND              VIA   -    MD0100PA00X+017655Y+006685X0200Y         S0      
317GND              VIA   -    MD0100PA00X+017655Y+007184X0200Y         S0      
317GND              VIA   -    MD0100PA00X+017157Y+006685X0200Y         S0      
317GND              VIA   -    MD0100PA00X+016966Y+006934X0200Y         S0      
317GND              VIA   -    MD0100PA00X+017157Y+007184X0200Y         S0      
317GND              VIA   -    MD0100PA00X+016746Y+007534X0200Y    R180 S0      
317GND              VIA   -    MD0100PA00X+016555Y+007285X0200Y         S0      
317GND              VIA   -    MD0100PA00X+016057Y+007285X0200Y         S0      
317GND              VIA   -    MD0100PA00X+015866Y+007534X0200Y         S0      
317GND              VIA   -    MD0100PA00X+014645Y+006934X0200Y         S0      
317GND              VIA   -    MD0100PA00X+015525Y+006934X0200Y    R180 S0      
317GND              VIA   -    MD0100PA00X+014837Y+006685X0200Y         S0      
317GND              VIA   -    MD0100PA00X+015335Y+006685X0200Y         S0      
317GND              VIA   -    MD0100PA00X+014837Y+007184X0200Y         S0      
317GND              VIA   -    MD0100PA00X+015335Y+007184X0200Y         S0      
317GND              VIA   -    MD0100PA00X+014426Y+007534X0200Y    R180 S0      
317GND              VIA   -    MD0100PA00X+013135Y+006685X0200Y         S0      
317GND              VIA   -    MD0100PA00X+013135Y+007184X0200Y         S0      
317GND              VIA   -    MD0100PA00X+013326Y+006934X0200Y    R180 S0      
317GND              VIA   -    MD0100PA00X+014235Y+007285X0200Y         S0      
317GND              VIA   -    MD0100PA00X+013737Y+007285X0200Y         S0      
317GND              VIA   -    MD0100PA00X+013546Y+007534X0200Y         S0      
317GND              VIA   -    MD0100PA00X+012637Y+006685X0200Y         S0      
317GND              VIA   -    MD0100PA00X+012446Y+006934X0200Y         S0      
317GND              VIA   -    MD0100PA00X+012637Y+007184X0200Y         S0      
317GND              VIA   -    MD0100PA00X+012226Y+007534X0200Y    R180 S0      
317GND              VIA   -    MD0100PA00X+012035Y+007285X0200Y         S0      
317GND              VIA   -    MD0100PA00X+011537Y+007285X0200Y         S0      
317GND              VIA   -    MD0100PA00X+011346Y+007534X0200Y         S0      
317GND              VIA   -    MD0100PA00X+011126Y+006934X0200Y    R180 S0      
317GND              VIA   -    MD0100PA00X+010935Y+006685X0200Y         S0      
317GND              VIA   -    MD0100PA00X+010437Y+006685X0200Y         S0      
317GND              VIA   -    MD0100PA00X+010246Y+006934X0200Y         S0      
317GND              VIA   -    MD0100PA00X+010935Y+007184X0200Y         S0      
317GND              VIA   -    MD0100PA00X+010437Y+007184X0200Y         S0      
317GND              VIA   -    MD0100PA00X+010026Y+007534X0200Y    R180 S0      
317GND              VIA   -    MD0100PA00X+009835Y+007285X0200Y         S0      
317GND              VIA   -    MD0100PA00X+009337Y+007285X0200Y         S0      
317GND              VIA   -    MD0100PA00X+009146Y+007534X0200Y         S0      
317GND              VIA   -    MD0100PA00X+008926Y+006934X0200Y    R180 S0      
317GND              VIA   -    MD0100PA00X+008735Y+006685X0200Y         S0      
317GND              VIA   -    MD0100PA00X+008735Y+007184X0200Y         S0      
317GND              VIA   -    MD0100PA00X+007137Y+007285X0200Y         S0      
317GND              VIA   -    MD0100PA00X+007635Y+007285X0200Y         S0      
317GND              VIA   -    MD0100PA00X+008237Y+006685X0200Y         S0      
317GND              VIA   -    MD0100PA00X+008046Y+006934X0200Y         S0      
317GND              VIA   -    MD0100PA00X+008237Y+007184X0200Y         S0      
317GND              VIA   -    MD0100PA00X+007825Y+007534X0200Y    R180 S0      
317GND              VIA   -    MD0100PA00X+006945Y+007534X0200Y         S0      
317GND              VIA   -    MD0100PA00X+006726Y+006934X0200Y    R180 S0      
317GND              VIA   -    MD0100PA00X+005846Y+006934X0200Y         S0      
317GND              VIA   -    MD0100PA00X+006037Y+007184X0200Y         S0      
317GND              VIA   -    MD0100PA00X+006535Y+007184X0200Y         S0      
317GND              VIA   -    MD0100PA00X+006037Y+006685X0200Y         S0      
317GND              VIA   -    MD0100PA00X+006535Y+006685X0200Y         S0      
327GND              VIA   -           A18X+179255Y+008944X0260Y         S2      
327GND              VIA   -           A18X+179255Y+007444X0260Y         S2      
327GND              VIA   -           A18X+179255Y+005944X0260Y         S2      
327GND              VIA   -           A18X+180005Y+009694X0260Y         S2      
327GND              VIA   -           A18X+180005Y+008194X0260Y         S2      
327GND              VIA   -           A18X+180005Y+006694X0260Y         S2      
327GND              PD101 -A          A01X+177688Y+012539X0520Y0560R270 S1      
327GND              PC2154-2          A01X+176448Y+012020X0198Y0197R090 S1      
327GND              PD102 -A          A01X+180011Y+006104X0670Y0990R270 S1      
327GND              R1930 -1          A18X+179167Y+005316X0198Y0197R090 S2      
317GND              VIA   -    M      A01X+180755Y+005944X0200Y         S2      
017GND              VIA   -    M      A18X+180755Y+005944X0260Y         S2      
017GND                    -    MD0100PA00X+180755Y+005944                       
317GND              VIA   -    MD0100PA00X+180752Y+005646X0200Y         S0      
317GND              VIA   -    MD0100PA00X+178197Y+012350X0200Y    R180 S0      
317GND              VIA   -    MD0100PA00X+178197Y+012600X0200Y    R180 S0      
317GND              VIA   -    MD0100PA00X+178197Y+012850X0200Y    R180 S0      
317GND              VIA   -    MD0100PA00X+177188Y+012344X0200Y    R180 S0      
317GND              VIA   -    MD0100PA00X+177188Y+012594X0200Y    R180 S0      
317GND              VIA   -    MD0100PA00X+177188Y+012844X0200Y    R180 S0      
317GND              VIA   -    MD0100PA00X+178514Y+008997X0200Y         S0      
317GND              VIA   -    MD0100PA00X+178514Y+008697X0200Y         S0      
327GND              PU203 -B7         A01X+178345Y+008358X0090Y         S1      
327GND              PU203 -A7         A01X+178345Y+008555X0090Y         S1      
327GND              PC4056-2          A01X+178525Y+009293X0198Y0197     S1      
317GND              VIA   -    M      A01X+176464Y+012297X0200Y    R180 S2      
017GND              VIA   -    M      A18X+176464Y+012297X0260Y    R180 S2      
017GND                    -    MD0100PA00X+176464Y+012297                       
327GND              R3132 -1          A18X+178767Y+005316X0198Y0197R090 S2      
317GND              VIA   -    MD0100PA00X+178507Y+005316X0200Y    R180 S0      
317GND              VIA   -    MD0100PA00X+176437Y+005751X0200Y         S0      
317GND              VIA   -    MD0100PA00X+175967Y+005771X0200Y         S0      
317GND              VIA   -    MD0100PA00X+176048Y+004872X0200Y         S0      
327GND              J38   -OB10       A01X+176048Y+004437X0150Y0570R180 S1      
317GND              VIA   -    MD0100PA00X+175340Y+004872X0200Y         S0      
327GND              J38   -OB13       A01X+175339Y+004437X0150Y0570R180 S1      
317GND              VIA   -    MD0100PA00X+170539Y+004872X0200Y         S0      
327GND              J38   -B13        A01X+170538Y+004437X0150Y0570R180 S1      
317GND              VIA   -    MD0100PA00X+146240Y+006156X0200Y    R090 S0      
327GND              C72   -2          A01X+145990Y+006156X0198Y0197R090 S1      
327GND              U104  -3          A01X+144537Y+005293X0220Y0320R270 S1      
317GND              VIA   -    MD0100PA00X+144114Y+005370X0200Y    R270 S0      
317GND              J8    -4   MD0320PA00X+122553Y+006038X0480Y         S3      
327GND              R4197 -2   M      A01X+119596Y+005702X0198Y0197     S1      
327GND              R4189 -2          A01X+119588Y+005282X0198Y0197     S1      
327GND              R4205 -2          A01X+119586Y+006152X0198Y0197     S1      
317GND              VIA   -    M      A01X+119869Y+005702X0200Y         S2      
017GND              VIA   -    M      A18X+119869Y+005702X0260Y         S2      
017GND                    -    MD0100PA00X+119869Y+005702                       
327GND              U271  -4          A01X+114849Y+005319X0240Y0520R270 S1      
317GND              VIA   -    M      A01X+114283Y+005319X0200Y         S2      
017GND              VIA   -    M      A18X+114283Y+005319X0260Y         S2      
017GND                    -    MD0100PA00X+114283Y+005319                       
317GND              VIA   -    MD0100PA00X+086135Y+006167X0200Y         S0      
317GND              VIA   -    MD0100PA00X+075226Y+005978X0200Y         S0      
317GND              VIA   -    MD0100PA00X+074749Y+004906X0200Y         S0      
317GND              VIA   -    MD0100PA00X+074499Y+004906X0200Y         S0      
317GND              VIA   -    MD0100PA00X+074448Y+005837X0200Y         S0      
317GND              VIA   -    MD0100PA00X+073013Y+006076X0200Y         S0      
317GND              VIA   -    MD0100PA00X+072258Y+004918X0200Y    R180 S0      
317GND              VIA   -    MD0100PA00X+067972Y+005907X0200Y         S0      
317GND              VIA   -    MD0100PA00X+066876Y+004919X0200Y    R180 S0      
317GND              VIA   -    MD0100PA00X+067585Y+004919X0200Y    R180 S0      
317GND              VIA   -    MD0100PA00X+066168Y+004919X0200Y    R180 S0      
317GND              VIA   -    MD0100PA00X+065459Y+004919X0200Y    R180 S0      
317GND              VIA   -    MD0100PA00X+065357Y+005836X0200Y         S0      
317GND              VIA   -    MD0100PA00X+061518Y+004919X0200Y    R180 S0      
317GND              VIA   -    MD0100PA00X+059392Y+004919X0200Y    R180 S0      
317GND              VIA   -    MD0100PA00X+053916Y+004919X0200Y    R180 S0      
317GND              VIA   -    MD0100PA00X+053207Y+004919X0200Y    R180 S0      
317GND              VIA   -    MD0100PA00X+052476Y+004919X0200Y    R180 S0      
317GND              VIA   -    MD0100PA00X+051790Y+004919X0200Y    R180 S0      
317GND              VIA   -    MD0100PA00X+051081Y+004919X0200Y    R180 S0      
317GND              VIA   -    MD0100PA00X+047895Y+005514X0200Y         S0      
327GND              R4185 -2          A01X+047536Y+005514X0198Y0197     S1      
317GND              VIA   -    MD0100PA00X+047895Y+006003X0200Y         S0      
327GND              R4193 -2          A01X+047543Y+006003X0198Y0197     S1      
327GND              U273  -4          A01X+043526Y+005502X0240Y0520R270 S1      
317GND              VIA   -    MD0100PA00X+043056Y+005635X0200Y         S0      
317GND              VIA   -    MD0100PA00X+028608Y+004872X0200Y         S0      
327GND              J35   -OB10       A01X+028607Y+004437X0150Y0570R180 S1      
317GND              VIA   -    MD0100PA00X+027899Y+004872X0200Y         S0      
327GND              J35   -OB13       A01X+027898Y+004437X0150Y0570R180 S1      
317GND              VIA   -    MD0100PA00X+028550Y+005319X0200Y         S0      
327GND              R34   -2          A18X+176976Y+003448X0198Y0197R270 S2      
327GND              R8422 -2          A18X+177355Y+004013X0198Y0197R090 S2      
317GND              VIA   -    MD0100PA00X+177289Y+003743X0200Y         S0      
327GND              R32   -2          A18X+176206Y+004003X0198Y0197R090 S2      
317GND              VIA   -    MD0100PA00X+176384Y+003779X0200Y         S0      
317GND              VIA   -    MD0100PA00X+174812Y+003706X0200Y         S0      
317GND              VIA   -    MD0100PA00X+169829Y+004002X0200Y    R180 S0      
317GND              VIA   -    MD0100PA00X+169830Y+004872X0200Y         S0      
327GND              J38   -B16 M      A01X+169830Y+004437X0150Y0570R180 S1      
317GND              VIA   -    MD0100PA00X+168412Y+004002X0200Y    R180 S0      
317GND              VIA   -    MD0100PA00X+168413Y+004872X0200Y         S0      
327GND              J38   -B22 M      A01X+168412Y+004437X0150Y0570R180 S1      
317GND              VIA   -    MD0100PA00X+169120Y+004002X0200Y    R180 S0      
317GND              VIA   -    MD0100PA00X+169121Y+004872X0200Y         S0      
327GND              J38   -B19 M      A01X+169121Y+004437X0150Y0570R180 S1      
317GND              VIA   -    MD0100PA00X+166994Y+004002X0200Y    R180 S0      
317GND              VIA   -    MD0100PA00X+166995Y+004872X0200Y         S0      
327GND              J38   -B28 M      A01X+166995Y+004437X0150Y0570R180 S1      
317GND              VIA   -    MD0100PA00X+167703Y+004002X0200Y    R180 S0      
317GND              VIA   -    MD0100PA00X+167704Y+004872X0200Y         S0      
327GND              J38   -B25 M      A01X+167704Y+004437X0150Y0570R180 S1      
317GND              VIA   -    MD0100PA00X+165416Y+004002X0200Y    R180 S0      
317GND              VIA   -    MD0100PA00X+165417Y+004872X0200Y         S0      
327GND              J38   -B29 M      A01X+165416Y+004437X0150Y0570R180 S1      
317GND              VIA   -    MD0100PA00X+163998Y+004002X0200Y    R180 S0      
317GND              VIA   -    MD0100PA00X+163999Y+004872X0200Y         S0      
327GND              J38   -B35 M      A01X+163999Y+004437X0150Y0570R180 S1      
317GND              VIA   -    MD0100PA00X+164707Y+004002X0200Y    R180 S0      
317GND              VIA   -    MD0100PA00X+164708Y+004872X0200Y         S0      
327GND              J38   -B32 M      A01X+164707Y+004437X0150Y0570R180 S1      
317GND              VIA   -    MD0100PA00X+162581Y+004002X0200Y    R180 S0      
317GND              VIA   -    MD0100PA00X+162582Y+004872X0200Y         S0      
327GND              J38   -B41 M      A01X+162581Y+004437X0150Y0570R180 S1      
317GND              VIA   -    MD0100PA00X+163290Y+004002X0200Y    R180 S0      
317GND              VIA   -    MD0100PA00X+163291Y+004872X0200Y         S0      
327GND              J38   -B38 M      A01X+163290Y+004437X0150Y0570R180 S1      
317GND              VIA   -    MD0100PA00X+160412Y+004002X0200Y    R180 S0      
317GND              VIA   -    MD0100PA00X+160413Y+004872X0200Y         S0      
327GND              J38   -B43 M      A01X+160412Y+004437X0150Y0570R180 S1      
317GND              VIA   -    MD0100PA00X+158994Y+004002X0200Y    R180 S0      
317GND              VIA   -    MD0100PA00X+158995Y+004872X0200Y         S0      
327GND              J38   -B49 M      A01X+158995Y+004437X0150Y0570R180 S1      
317GND              VIA   -    MD0100PA00X+159703Y+004002X0200Y    R180 S0      
317GND              VIA   -    MD0100PA00X+159704Y+004872X0200Y         S0      
327GND              J38   -B46 M      A01X+159704Y+004437X0150Y0570R180 S1      
317GND              VIA   -    MD0100PA00X+157577Y+004002X0200Y    R180 S0      
317GND              VIA   -    MD0100PA00X+157578Y+004872X0200Y         S0      
327GND              J38   -B55 M      A01X+157578Y+004437X0150Y0570R180 S1      
317GND              VIA   -    MD0100PA00X+158286Y+004002X0200Y    R180 S0      
317GND              VIA   -    MD0100PA00X+158287Y+004872X0200Y         S0      
327GND              J38   -B52 M      A01X+158286Y+004437X0150Y0570R180 S1      
317GND              VIA   -    MD0100PA00X+156160Y+004002X0200Y    R180 S0      
317GND              VIA   -    MD0100PA00X+156161Y+004872X0200Y         S0      
327GND              J38   -B61 M      A01X+156160Y+004437X0150Y0570R180 S1      
317GND              VIA   -    MD0100PA00X+156868Y+004002X0200Y    R180 S0      
317GND              VIA   -    MD0100PA00X+156869Y+004872X0200Y         S0      
327GND              J38   -B58 M      A01X+156869Y+004437X0150Y0570R180 S1      
317GND              VIA   -    MD0100PA00X+154742Y+004002X0200Y    R180 S0      
317GND              VIA   -    MD0100PA00X+154743Y+004872X0200Y         S0      
327GND              J38   -B67 M      A01X+154743Y+004437X0150Y0570R180 S1      
317GND              VIA   -    MD0100PA00X+155451Y+004002X0200Y    R180 S0      
317GND              VIA   -    MD0100PA00X+155452Y+004872X0200Y         S0      
327GND              J38   -B64 M      A01X+155452Y+004437X0150Y0570R180 S1      
317GND              VIA   -    MD0100PA00X+074284Y+003983X0200Y         S0      
317GND              VIA   -    MD0100PA00X+073679Y+003983X0200Y         S0      
317GND              VIA   -    MD0100PA00X+072898Y+003987X0200Y         S0      
317GND              VIA   -    MD0100PA00X+070184Y+004511X0200Y         S0      
317GND              VIA   -    MD0100PA00X+068686Y+004370X0200Y         S0      
317GND              VIA   -    MD0100PA00X+069367Y+003268X0200Y         S0      
317GND              VIA   -    MD0100PA00X+067589Y+004526X0200Y         S0      
317GND              VIA   -    MD0100PA00X+067759Y+003620X0200Y         S0      
317GND              VIA   -    MD0100PA00X+066874Y+004526X0200Y         S0      
317GND              VIA   -    MD0100PA00X+066370Y+003257X0200Y         S0      
317GND              VIA   -    MD0100PA00X+064849Y+004411X0200Y    R180 S0      
317GND              VIA   -    MD0100PA00X+062039Y+003679X0200Y    R180 S0      
317GND              VIA   -    MD0100PA00X+062494Y+004402X0200Y    R180 S0      
317GND              VIA   -    MD0100PA00X+061843Y+004343X0200Y    R180 S0      
317GND              VIA   -    MD0100PA00X+059928Y+003287X0200Y    R180 S0      
317GND              VIA   -    MD0100PA00X+060306Y+004452X0200Y    R180 S0      
317GND              VIA   -    MD0100PA00X+059568Y+004484X0200Y    R180 S0      
317GND              VIA   -    MD0100PA00X+057862Y+004511X0200Y    R180 S0      
317GND              VIA   -    MD0100PA00X+056443Y+004513X0200Y    R180 S0      
317GND              VIA   -    MD0100PA00X+054272Y+003956X0200Y         S0      
327GND              R6035 -2          A18X+054272Y+003715X0198Y0197R270 S2      
317GND              VIA   -    MD0100PA00X+052500Y+004226X0200Y    R180 S0      
317GND              VIA   -    MD0100PA00X+051792Y+004226X0200Y    R180 S0      
317GND              VIA   -    MD0100PA00X+030672Y+003998X0200Y         S0      
327GND              R3165 -1   M      A18X+030772Y+004279X0198Y0197R270 S2      
327GND              R8413 -1          A18X+031172Y+004279X0198Y0197R270 S2      
327GND              R3163 -2          A18X+028672Y+004279X0198Y0197R090 S2      
317GND              VIA   -    MD0100PA00X+028672Y+004002X0200Y         S0      
327GND              R3175 -2          A18X+028857Y+003742X0198Y0197     S2      
317GND              VIA   -    MD0100PA00X+027160Y+004016X0200Y         S0      
317GND              VIA   -    MD0100PA00X+026328Y+003462X0200Y         S0      
317GND              VIA   -    MD0100PA00X+023097Y+004002X0200Y    R180 S0      
317GND              VIA   -    MD0100PA00X+023098Y+004872X0200Y         S0      
327GND              J35   -B13 M      A01X+023097Y+004437X0150Y0570R180 S1      
317GND              VIA   -    MD0100PA00X+022388Y+004002X0200Y    R180 S0      
317GND              VIA   -    MD0100PA00X+022389Y+004872X0200Y         S0      
327GND              J35   -B16 M      A01X+022389Y+004437X0150Y0570R180 S1      
317GND              VIA   -    MD0100PA00X+021679Y+004002X0200Y    R180 S0      
317GND              VIA   -    MD0100PA00X+021680Y+004872X0200Y         S0      
327GND              J35   -B19 M      A01X+021680Y+004437X0150Y0570R180 S1      
317GND              VIA   -    MD0100PA00X+020971Y+004002X0200Y    R180 S0      
317GND              VIA   -    MD0100PA00X+020972Y+004872X0200Y         S0      
327GND              J35   -B22 M      A01X+020971Y+004437X0150Y0570R180 S1      
317GND              VIA   -    MD0100PA00X+020262Y+004002X0200Y    R180 S0      
317GND              VIA   -    MD0100PA00X+020263Y+004872X0200Y         S0      
327GND              J35   -B25 M      A01X+020263Y+004437X0150Y0570R180 S1      
317GND              VIA   -    MD0100PA00X+019553Y+004002X0200Y    R180 S0      
317GND              VIA   -    MD0100PA00X+019554Y+004872X0200Y         S0      
327GND              J35   -B28 M      A01X+019554Y+004437X0150Y0570R180 S1      
317GND              VIA   -    MD0100PA00X+017975Y+004002X0200Y    R180 S0      
317GND              VIA   -    MD0100PA00X+017976Y+004872X0200Y         S0      
327GND              J35   -B29 M      A01X+017975Y+004437X0150Y0570R180 S1      
317GND              VIA   -    MD0100PA00X+017266Y+004002X0200Y    R180 S0      
317GND              VIA   -    MD0100PA00X+017267Y+004872X0200Y         S0      
327GND              J35   -B32 M      A01X+017266Y+004437X0150Y0570R180 S1      
317GND              VIA   -    MD0100PA00X+016557Y+004002X0200Y    R180 S0      
317GND              VIA   -    MD0100PA00X+016558Y+004872X0200Y         S0      
327GND              J35   -B35 M      A01X+016558Y+004437X0150Y0570R180 S1      
317GND              VIA   -    MD0100PA00X+015849Y+004002X0200Y    R180 S0      
317GND              VIA   -    MD0100PA00X+015850Y+004872X0200Y         S0      
327GND              J35   -B38 M      A01X+015849Y+004437X0150Y0570R180 S1      
317GND              VIA   -    MD0100PA00X+015140Y+004002X0200Y    R180 S0      
317GND              VIA   -    MD0100PA00X+015141Y+004872X0200Y         S0      
327GND              J35   -B41 M      A01X+015140Y+004437X0150Y0570R180 S1      
317GND              VIA   -    MD0100PA00X+012971Y+004002X0200Y    R180 S0      
317GND              VIA   -    MD0100PA00X+012972Y+004872X0200Y         S0      
327GND              J35   -B43 M      A01X+012971Y+004437X0150Y0570R180 S1      
317GND              VIA   -    MD0100PA00X+012262Y+004002X0200Y    R180 S0      
317GND              VIA   -    MD0100PA00X+012263Y+004872X0200Y         S0      
327GND              J35   -B46 M      A01X+012263Y+004437X0150Y0570R180 S1      
317GND              VIA   -    MD0100PA00X+011553Y+004002X0200Y    R180 S0      
317GND              VIA   -    MD0100PA00X+011554Y+004872X0200Y         S0      
327GND              J35   -B49 M      A01X+011554Y+004437X0150Y0570R180 S1      
317GND              VIA   -    MD0100PA00X+010845Y+004002X0200Y    R180 S0      
317GND              VIA   -    MD0100PA00X+010846Y+004872X0200Y         S0      
327GND              J35   -B52 M      A01X+010845Y+004437X0150Y0570R180 S1      
317GND              VIA   -    MD0100PA00X+010136Y+004002X0200Y    R180 S0      
317GND              VIA   -    MD0100PA00X+010137Y+004872X0200Y         S0      
327GND              J35   -B55 M      A01X+010137Y+004437X0150Y0570R180 S1      
317GND              VIA   -    MD0100PA00X+009427Y+004002X0200Y    R180 S0      
317GND              VIA   -    MD0100PA00X+009428Y+004872X0200Y         S0      
327GND              J35   -B58 M      A01X+009428Y+004437X0150Y0570R180 S1      
317GND              VIA   -    MD0100PA00X+008719Y+004002X0200Y    R180 S0      
317GND              VIA   -    MD0100PA00X+008720Y+004872X0200Y         S0      
327GND              J35   -B61 M      A01X+008719Y+004437X0150Y0570R180 S1      
317GND              VIA   -    MD0100PA00X+008010Y+004002X0200Y    R180 S0      
317GND              VIA   -    MD0100PA00X+008011Y+004872X0200Y         S0      
327GND              J35   -B64 M      A01X+008011Y+004437X0150Y0570R180 S1      
317GND              VIA   -    MD0100PA00X+007302Y+004002X0200Y    R180 S0      
317GND              VIA   -    MD0100PA00X+007302Y+004872X0200Y         S0      
327GND              J35   -B67 M      A01X+007302Y+004437X0150Y0570R180 S1      
317GND              VIA   -    MD0100PA00X+177742Y+002451X0200Y    R225 S0      
317GND              VIA   -    MD0100PA00X+177742Y+001951X0200Y    R225 S0      
317GND              VIA   -    MD0100PA00X+176942Y+001951X0200Y    R225 S0      
317GND              VIA   -    MD0100PA00X+176048Y+002841X0200Y    R180 S0      
327GND              J38   -OA10       A01X+176048Y+003276X0150Y0570R180 S1      
317GND              VIA   -    MD0100PA00X+175339Y+002841X0200Y    R180 S0      
327GND              J38   -OA13       A01X+175339Y+003276X0150Y0570R180 S1      
317GND              VIA   -    MD0100PA00X+175201Y+002515X0200Y         S0      
327GND              J38   -A1         A01X+173373Y+003276X0150Y0570R180 S1      
327GND              J38   -A2         A01X+173137Y+003276X0150Y0570R180 S1      
327GND              J38   -A3         A01X+172900Y+003276X0150Y0570R180 S1      
327GND              J38   -A4         A01X+172664Y+003276X0150Y0570R180 S1      
327GND              J38   -A5         A01X+172428Y+003276X0150Y0570R180 S1      
327GND              J38   -A6         A01X+172192Y+003276X0150Y0570R180 S1      
317GND              VIA   -    MD0100PA00X+172529Y+002821X0200Y         S0      
317GND              VIA   -    MD0100PA00X+172879Y+002821X0200Y         S0      
317GND              VIA   -    MD0100PA00X+173229Y+002821X0200Y         S0      
317GND              VIA   -    MD0100PA00X+172015Y+002291X0200Y         S0      
317GND              VIA   -    MD0100PA00X+170538Y+003711X0200Y         S0      
327GND              J38   -A13 M      A01X+170538Y+003276X0150Y0570R180 S1      
317GND              VIA   -    MD0100PA00X+170538Y+002841X0200Y    R180 S0      
327GND              R1895 -2          A18X+171317Y+003432X0198Y0197R270 S2      
317GND              VIA   -    MD0100PA00X+169829Y+002841X0200Y    R180 S0      
317GND              VIA   -    MD0100PA00X+169830Y+003711X0200Y         S0      
327GND              J38   -A16 M      A01X+169830Y+003276X0150Y0570R180 S1      
317GND              VIA   -    MD0100PA00X+169724Y+002204X0200Y         S0      
317GND              VIA   -    MD0100PA00X+169925Y+001954X0200Y         S0      
317GND              VIA   -    MD0100PA00X+168319Y+002598X0200Y         S0      
317GND              VIA   -    MD0100PA00X+168519Y+002398X0200Y         S0      
317GND              VIA   -    MD0100PA00X+169014Y+002398X0200Y         S0      
317GND              VIA   -    MD0100PA00X+169120Y+002841X0200Y    R180 S0      
317GND              VIA   -    MD0100PA00X+169121Y+003711X0200Y         S0      
327GND              J38   -A19 M      A01X+169121Y+003276X0150Y0570R180 S1      
317GND              VIA   -    MD0100PA00X+168412Y+002841X0200Y    R180 S0      
317GND              VIA   -    MD0100PA00X+168413Y+003711X0200Y         S0      
327GND              J38   -A22 M      A01X+168412Y+003276X0150Y0570R180 S1      
317GND              VIA   -    MD0100PA00X+168508Y+001954X0200Y         S0      
317GND              VIA   -    MD0100PA00X+169029Y+001954X0200Y         S0      
317GND              VIA   -    MD0100PA00X+168307Y+002204X0200Y         S0      
317GND              VIA   -    MD0100PA00X+167809Y+002204X0200Y         S0      
317GND              VIA   -    MD0100PA00X+169214Y+002598X0200Y         S0      
317GND              VIA   -    MD0100PA00X+169226Y+002204X0200Y         S0      
317GND              VIA   -    MD0100PA00X+166902Y+002598X0200Y         S0      
317GND              VIA   -    MD0100PA00X+167102Y+002398X0200Y         S0      
317GND              VIA   -    MD0100PA00X+167597Y+002398X0200Y         S0      
317GND              VIA   -    MD0100PA00X+166994Y+002841X0200Y    R180 S0      
317GND              VIA   -    MD0100PA00X+166995Y+003711X0200Y         S0      
327GND              J38   -A28 M      A01X+166995Y+003276X0150Y0570R180 S1      
317GND              VIA   -    MD0100PA00X+167612Y+001954X0200Y         S0      
317GND              VIA   -    MD0100PA00X+167797Y+002598X0200Y         S0      
317GND              VIA   -    MD0100PA00X+167703Y+002841X0200Y    R180 S0      
317GND              VIA   -    MD0100PA00X+167704Y+003711X0200Y         S0      
327GND              J38   -A25 M      A01X+167704Y+003276X0150Y0570R180 S1      
317GND              VIA   -    MD0100PA00X+165416Y+002841X0200Y    R180 S0      
317GND              VIA   -    MD0100PA00X+165417Y+003711X0200Y         S0      
327GND              J38   -A29 M      A01X+165416Y+003276X0150Y0570R180 S1      
317GND              VIA   -    MD0100PA00X+165311Y+002204X0200Y         S0      
317GND              VIA   -    MD0100PA00X+165512Y+001954X0200Y         S0      
317GND              VIA   -    MD0100PA00X+163384Y+002598X0200Y         S0      
317GND              VIA   -    MD0100PA00X+163906Y+002598X0200Y         S0      
317GND              VIA   -    MD0100PA00X+164601Y+002398X0200Y         S0      
317GND              VIA   -    MD0100PA00X+164106Y+002398X0200Y         S0      
317GND              VIA   -    MD0100PA00X+163998Y+002841X0200Y    R180 S0      
317GND              VIA   -    MD0100PA00X+163999Y+003711X0200Y         S0      
327GND              J38   -A35 M      A01X+163999Y+003276X0150Y0570R180 S1      
317GND              VIA   -    MD0100PA00X+164094Y+001954X0200Y         S0      
317GND              VIA   -    MD0100PA00X+164616Y+001954X0200Y         S0      
317GND              VIA   -    MD0100PA00X+163893Y+002204X0200Y         S0      
317GND              VIA   -    MD0100PA00X+163395Y+002204X0200Y         S0      
317GND              VIA   -    MD0100PA00X+164801Y+002598X0200Y         S0      
317GND              VIA   -    MD0100PA00X+164707Y+002841X0200Y    R180 S0      
317GND              VIA   -    MD0100PA00X+164708Y+003711X0200Y         S0      
327GND              J38   -A32 M      A01X+164707Y+003276X0150Y0570R180 S1      
317GND              VIA   -    MD0100PA00X+164813Y+002204X0200Y         S0      
317GND              VIA   -    MD0100PA00X+162488Y+002598X0200Y         S0      
317GND              VIA   -    MD0100PA00X+163184Y+002398X0200Y         S0      
317GND              VIA   -    MD0100PA00X+162688Y+002398X0200Y         S0      
317GND              VIA   -    MD0100PA00X+162581Y+002841X0200Y    R180 S0      
317GND              VIA   -    MD0100PA00X+162582Y+003711X0200Y         S0      
327GND              J38   -A41 M      A01X+162581Y+003276X0150Y0570R180 S1      
317GND              VIA   -    MD0100PA00X+163290Y+002841X0200Y    R180 S0      
317GND              VIA   -    MD0100PA00X+163291Y+003711X0200Y         S0      
327GND              J38   -A38 M      A01X+163290Y+003276X0150Y0570R180 S1      
317GND              VIA   -    MD0100PA00X+163199Y+001954X0200Y         S0      
317GND              VIA   -    MD0100PA00X+160412Y+002841X0200Y    R180 S0      
317GND              VIA   -    MD0100PA00X+160413Y+003711X0200Y         S0      
327GND              J38   -A43 M      A01X+160412Y+003276X0150Y0570R180 S1      
317GND              VIA   -    MD0100PA00X+160508Y+001954X0200Y         S0      
317GND              VIA   -    MD0100PA00X+159797Y+002598X0200Y         S0      
317GND              VIA   -    MD0100PA00X+158902Y+002598X0200Y         S0      
317GND              VIA   -    MD0100PA00X+159703Y+002841X0200Y    R180 S0      
317GND              VIA   -    MD0100PA00X+159704Y+003711X0200Y         S0      
327GND              J38   -A46 M      A01X+159704Y+003276X0150Y0570R180 S1      
317GND              VIA   -    MD0100PA00X+159102Y+002398X0200Y         S0      
317GND              VIA   -    MD0100PA00X+159597Y+002398X0200Y         S0      
317GND              VIA   -    MD0100PA00X+158994Y+002841X0200Y    R180 S0      
317GND              VIA   -    MD0100PA00X+158995Y+003711X0200Y         S0      
327GND              J38   -A49 M      A01X+158995Y+003276X0150Y0570R180 S1      
317GND              VIA   -    MD0100PA00X+158890Y+002204X0200Y         S0      
317GND              VIA   -    MD0100PA00X+159090Y+001954X0200Y         S0      
317GND              VIA   -    MD0100PA00X+159612Y+001954X0200Y         S0      
317GND              VIA   -    MD0100PA00X+159809Y+002204X0200Y         S0      
317GND              VIA   -    MD0100PA00X+160307Y+002204X0200Y         S0      
317GND              VIA   -    MD0100PA00X+158380Y+002598X0200Y         S0      
317GND              VIA   -    MD0100PA00X+157484Y+002598X0200Y         S0      
317GND              VIA   -    MD0100PA00X+158180Y+002398X0200Y         S0      
317GND              VIA   -    MD0100PA00X+158286Y+002841X0200Y    R180 S0      
317GND              VIA   -    MD0100PA00X+158287Y+003711X0200Y         S0      
327GND              J38   -A52 M      A01X+158286Y+003276X0150Y0570R180 S1      
317GND              VIA   -    MD0100PA00X+157684Y+002398X0200Y         S0      
317GND              VIA   -    MD0100PA00X+157577Y+002841X0200Y    R180 S0      
317GND              VIA   -    MD0100PA00X+157578Y+003711X0200Y         S0      
327GND              J38   -A55 M      A01X+157578Y+003276X0150Y0570R180 S1      
317GND              VIA   -    MD0100PA00X+157472Y+002204X0200Y         S0      
317GND              VIA   -    MD0100PA00X+157673Y+001954X0200Y         S0      
317GND              VIA   -    MD0100PA00X+158392Y+002204X0200Y         S0      
317GND              VIA   -    MD0100PA00X+158195Y+001954X0200Y         S0      
317GND              VIA   -    MD0100PA00X+156256Y+001954X0200Y         S0      
317GND              VIA   -    MD0100PA00X+156962Y+002598X0200Y         S0      
317GND              VIA   -    MD0100PA00X+156067Y+002598X0200Y         S0      
317GND              VIA   -    MD0100PA00X+156762Y+002398X0200Y         S0      
317GND              VIA   -    MD0100PA00X+156868Y+002841X0200Y    R180 S0      
317GND              VIA   -    MD0100PA00X+156869Y+003711X0200Y         S0      
327GND              J38   -A58 M      A01X+156869Y+003276X0150Y0570R180 S1      
317GND              VIA   -    MD0100PA00X+156267Y+002398X0200Y         S0      
317GND              VIA   -    MD0100PA00X+156160Y+002841X0200Y    R180 S0      
317GND              VIA   -    MD0100PA00X+156161Y+003711X0200Y         S0      
327GND              J38   -A61 M      A01X+156160Y+003276X0150Y0570R180 S1      
317GND              VIA   -    MD0100PA00X+156055Y+002204X0200Y         S0      
317GND              VIA   -    MD0100PA00X+156974Y+002204X0200Y         S0      
317GND              VIA   -    MD0100PA00X+156777Y+001954X0200Y         S0      
317GND              VIA   -    MD0100PA00X+154650Y+002598X0200Y         S0      
317GND              VIA   -    MD0100PA00X+154850Y+002398X0200Y         S0      
317GND              VIA   -    MD0100PA00X+155345Y+002398X0200Y         S0      
317GND              VIA   -    MD0100PA00X+154743Y+003711X0200Y         S0      
317GND              VIA   -    MD0100PA00X+154742Y+002841X0200Y    R180 S0      
327GND              J38   -A67 M      A01X+154743Y+003276X0150Y0570R180 S1      
317GND              VIA   -    MD0100PA00X+155545Y+002598X0200Y         S0      
317GND              VIA   -    MD0100PA00X+155451Y+002841X0200Y    R180 S0      
317GND              VIA   -    MD0100PA00X+155452Y+003711X0200Y         S0      
327GND              J38   -A64 M      A01X+155452Y+003276X0150Y0570R180 S1      
317GND              VIA   -    MD0100PA00X+155360Y+001954X0200Y         S0      
317GND              VIA   -    MD0100PA00X+155557Y+002204X0200Y         S0      
317GND              VIA   -    MD0100PA00X+078746Y+004938X0200Y         S0      
317GND              VIA   -    MD0100PA00X+080946Y+004938X0200Y         S0      
317GND              VIA   -    MD0100PA00X+083146Y+004938X0200Y         S0      
317GND              VIA   -    MD0100PA00X+085346Y+004938X0200Y         S0      
317GND              VIA   -    MD0100PA00X+087534Y+005160X0200Y         S0      
317GND              VIA   -    MD0100PA00X+087613Y+007358X0200Y    R090 S0      
317GND              VIA   -    MD0100PA00X+087613Y+009558X0200Y    R090 S0      
317GND              VIA   -    MD0100PA00X+087613Y+011758X0200Y    R090 S0      
317GND              VIA   -    MD0100PA00X+087746Y+013954X0200Y         S0      
317GND              VIA   -    MD0100PA00X+089872Y+014521X0200Y         S0      
317GND              VIA   -    MD0100PA00X+092072Y+014521X0200Y         S0      
317GND              VIA   -    MD0100PA00X+096472Y+014521X0200Y         S0      
317GND              VIA   -    MD0100PA00X+098672Y+014521X0200Y         S0      
317GND              VIA   -    MD0100PA00X+100872Y+014521X0200Y         S0      
317GND              VIA   -    MD0100PA00X+102190Y+012759X0200Y    R270 S0      
317GND              VIA   -    MD0100PA00X+102190Y+006159X0200Y    R270 S0      
317GND              VIA   -    MD0100PA00X+104020Y+004938X0200Y         S0      
317GND              VIA   -    MD0100PA00X+106220Y+004938X0200Y         S0      
317GND              VIA   -    MD0100PA00X+108420Y+004938X0200Y         S0      
317GND              VIA   -    MD0100PA00X+110620Y+004938X0200Y         S0      
317GND              VIA   -    MD0100PA00X+112820Y+004938X0200Y         S0      
317GND              VIA   -    MD0100PA00X+115020Y+004938X0200Y         S0      
317GND              VIA   -    MD0100PA00X+119420Y+004938X0200Y         S0      
317GND              VIA   -    MD0100PA00X+121620Y+004938X0200Y         S0      
317GND              VIA   -    MD0100PA00X+123820Y+004938X0200Y         S0      
317GND              VIA   -    MD0100PA00X+126020Y+004938X0200Y         S0      
317GND              VIA   -    MD0100PA00X+128220Y+004938X0200Y         S0      
317GND              VIA   -    MD0100PA00X+130420Y+004938X0200Y         S0      
317GND              VIA   -    MD0100PA00X+132620Y+004938X0200Y         S0      
317GND              VIA   -    MD0100PA00X+134820Y+004938X0200Y         S0      
317GND              VIA   -    MD0100PA00X+137020Y+004938X0200Y         S0      
317GND              VIA   -    MD0100PA00X+139220Y+004938X0200Y         S0      
317GND              VIA   -    MD0100PA00X+141420Y+004938X0200Y         S0      
317GND              VIA   -    MD0100PA00X+143620Y+004938X0200Y         S0      
317GND              VIA   -    MD0100PA00X+145820Y+004938X0200Y         S0      
317GND              VIA   -    MD0100PA00X+148020Y+004938X0200Y         S0      
317GND              VIA   -    MD0100PA00X+150220Y+004938X0200Y         S0      
317GND              VIA   -    MD0100PA00X+152412Y+004757X0200Y         S0      
317GND              VIA   -    MD0100PA00X+152899Y+002612X0200Y    R270 S0      
317GND              VIA   -    MD0100PA00X+064958Y+002930X0200Y         S0      
317GND              VIA   -    MD0100PA00X+051884Y+002379X0200Y         S0      
317GND              VIA   -    MD0100PA00X+054084Y+002379X0200Y         S0      
317GND              VIA   -    MD0100PA00X+056284Y+002379X0200Y         S0      
317GND              VIA   -    MD0100PA00X+058484Y+002379X0200Y         S0      
317GND              VIA   -    MD0100PA00X+060684Y+002379X0200Y         S0      
317GND              VIA   -    MD0100PA00X+062884Y+002379X0200Y         S0      
317GND              VIA   -    MD0100PA00X+065084Y+002379X0200Y         S0      
317GND              VIA   -    MD0100PA00X+067284Y+002379X0200Y         S0      
317GND              VIA   -    MD0100PA00X+069484Y+002379X0200Y         S0      
317GND              VIA   -    MD0100PA00X+071684Y+002379X0200Y         S0      
317GND              VIA   -    MD0100PA00X+073884Y+002379X0200Y         S0      
317GND              VIA   -    MD0100PA00X+076084Y+002379X0200Y         S0      
317GND              VIA   -    MD0100PA00X+032954Y+004938X0200Y         S0      
317GND              VIA   -    MD0100PA00X+035154Y+004938X0200Y         S0      
317GND              VIA   -    MD0100PA00X+037354Y+004938X0200Y         S0      
317GND              VIA   -    MD0100PA00X+039554Y+004938X0200Y         S0      
317GND              VIA   -    MD0100PA00X+041754Y+004938X0200Y         S0      
317GND              VIA   -    MD0100PA00X+043954Y+004938X0200Y         S0      
317GND              VIA   -    MD0100PA00X+046154Y+004938X0200Y         S0      
317GND              VIA   -    MD0100PA00X+048354Y+004938X0200Y         S0      
317GND              VIA   -    MD0100PA00X+031866Y+002499X0200Y    R090 S0      
317GND              VIA   -    MD0100PA00X+029116Y+002140X0200Y         S0      
317GND              VIA   -    MD0100PA00X+028607Y+002841X0200Y    R180 S0      
327GND              J35   -OA10       A01X+028607Y+003276X0150Y0570R180 S1      
317GND              VIA   -    MD0100PA00X+027898Y+002841X0200Y    R180 S0      
327GND              J35   -OA13       A01X+027898Y+003276X0150Y0570R180 S1      
317GND              VIA   -    MD0100PA00X+028590Y+002396X0200Y         S0      
317GND              VIA   -    MD0100PA00X+027260Y+002718X0200Y         S0      
327GND              J35   -A1         A01X+025932Y+003276X0150Y0570R180 S1      
327GND              J35   -A2         A01X+025696Y+003276X0150Y0570R180 S1      
327GND              J35   -A3         A01X+025459Y+003276X0150Y0570R180 S1      
327GND              J35   -A4         A01X+025223Y+003276X0150Y0570R180 S1      
327GND              J35   -A5         A01X+024987Y+003276X0150Y0570R180 S1      
327GND              J35   -A6         A01X+024751Y+003276X0150Y0570R180 S1      
327GND              C1838 -2          A18X+025022Y+003379X0198Y0197R090 S2      
327GND              C1835 -2          A18X+025412Y+003380X0198Y0197R090 S2      
327GND              R3180 -2          A18X+023806Y+003433X0198Y0197R270 S2      
327GND              C1837 -2          A18X+024622Y+003379X0198Y0197R090 S2      
327GND              C1836 -2          A18X+024222Y+003379X0198Y0197R090 S2      
317GND              VIA   -    MD0100PA00X+026000Y+002836X0200Y    R180 S0      
317GND              VIA   -    MD0100PA00X+024950Y+002836X0200Y    R180 S0      
317GND              VIA   -    MD0100PA00X+025650Y+002836X0200Y    R180 S0      
317GND              VIA   -    MD0100PA00X+025300Y+002836X0200Y    R180 S0      
317GND              VIA   -    MD0100PA00X+024349Y+002300X0200Y         S0      
317GND              VIA   -    MD0100PA00X+022484Y+001954X0200Y         S0      
317GND              VIA   -    MD0100PA00X+022283Y+002204X0200Y         S0      
317GND              VIA   -    MD0100PA00X+021785Y+002204X0200Y         S0      
317GND              VIA   -    MD0100PA00X+023097Y+002841X0200Y    R180 S0      
317GND              VIA   -    MD0100PA00X+023098Y+003711X0200Y         S0      
327GND              J35   -A13 M      A01X+023097Y+003276X0150Y0570R180 S1      
317GND              VIA   -    MD0100PA00X+022388Y+002841X0200Y    R180 S0      
317GND              VIA   -    MD0100PA00X+022389Y+003711X0200Y         S0      
327GND              J35   -A16 M      A01X+022389Y+003276X0150Y0570R180 S1      
317GND              VIA   -    MD0100PA00X+021774Y+002598X0200Y         S0      
317GND              VIA   -    MD0100PA00X+020368Y+002204X0200Y         S0      
317GND              VIA   -    MD0100PA00X+020866Y+002204X0200Y         S0      
317GND              VIA   -    MD0100PA00X+021588Y+001954X0200Y         S0      
317GND              VIA   -    MD0100PA00X+021067Y+001954X0200Y         S0      
317GND              VIA   -    MD0100PA00X+020971Y+002841X0200Y    R180 S0      
317GND              VIA   -    MD0100PA00X+020972Y+003711X0200Y         S0      
327GND              J35   -A22 M      A01X+020971Y+003276X0150Y0570R180 S1      
317GND              VIA   -    MD0100PA00X+021679Y+002841X0200Y    R180 S0      
317GND              VIA   -    MD0100PA00X+021680Y+003711X0200Y         S0      
327GND              J35   -A19 M      A01X+021680Y+003276X0150Y0570R180 S1      
317GND              VIA   -    MD0100PA00X+021574Y+002398X0200Y         S0      
317GND              VIA   -    MD0100PA00X+021078Y+002398X0200Y         S0      
317GND              VIA   -    MD0100PA00X+020262Y+002841X0200Y    R180 S0      
317GND              VIA   -    MD0100PA00X+020263Y+003711X0200Y         S0      
327GND              J35   -A25 M      A01X+020263Y+003276X0150Y0570R180 S1      
317GND              VIA   -    MD0100PA00X+020356Y+002598X0200Y         S0      
317GND              VIA   -    MD0100PA00X+020878Y+002598X0200Y         S0      
317GND              VIA   -    MD0100PA00X+020171Y+001954X0200Y         S0      
317GND              VIA   -    MD0100PA00X+019553Y+002841X0200Y    R180 S0      
317GND              VIA   -    MD0100PA00X+019554Y+003711X0200Y         S0      
327GND              J35   -A28 M      A01X+019554Y+003276X0150Y0570R180 S1      
317GND              VIA   -    MD0100PA00X+020156Y+002398X0200Y         S0      
317GND              VIA   -    MD0100PA00X+019661Y+002398X0200Y         S0      
317GND              VIA   -    MD0100PA00X+019461Y+002598X0200Y         S0      
317GND              VIA   -    MD0100PA00X+018071Y+001954X0200Y         S0      
317GND              VIA   -    MD0100PA00X+017870Y+002204X0200Y         S0      
317GND              VIA   -    MD0100PA00X+017372Y+002204X0200Y         S0      
317GND              VIA   -    MD0100PA00X+017975Y+002841X0200Y    R180 S0      
317GND              VIA   -    MD0100PA00X+017976Y+003711X0200Y         S0      
327GND              J35   -A29 M      A01X+017975Y+003276X0150Y0570R180 S1      
317GND              VIA   -    MD0100PA00X+017266Y+002841X0200Y    R180 S0      
317GND              VIA   -    MD0100PA00X+017267Y+003711X0200Y         S0      
327GND              J35   -A32 M      A01X+017266Y+003276X0150Y0570R180 S1      
317GND              VIA   -    MD0100PA00X+017360Y+002598X0200Y         S0      
317GND              VIA   -    MD0100PA00X+015954Y+002204X0200Y         S0      
317GND              VIA   -    MD0100PA00X+016452Y+002204X0200Y         S0      
317GND              VIA   -    MD0100PA00X+017175Y+001954X0200Y         S0      
317GND              VIA   -    MD0100PA00X+016653Y+001954X0200Y         S0      
317GND              VIA   -    MD0100PA00X+015758Y+001954X0200Y         S0      
317GND              VIA   -    MD0100PA00X+016557Y+002841X0200Y    R180 S0      
317GND              VIA   -    MD0100PA00X+016558Y+003711X0200Y         S0      
327GND              J35   -A35 M      A01X+016558Y+003276X0150Y0570R180 S1      
317GND              VIA   -    MD0100PA00X+016665Y+002398X0200Y         S0      
317GND              VIA   -    MD0100PA00X+017160Y+002398X0200Y         S0      
317GND              VIA   -    MD0100PA00X+016465Y+002598X0200Y         S0      
317GND              VIA   -    MD0100PA00X+015849Y+002841X0200Y    R180 S0      
317GND              VIA   -    MD0100PA00X+015850Y+003711X0200Y         S0      
327GND              J35   -A38 M      A01X+015849Y+003276X0150Y0570R180 S1      
317GND              VIA   -    MD0100PA00X+015943Y+002598X0200Y         S0      
317GND              VIA   -    MD0100PA00X+015140Y+002841X0200Y    R180 S0      
317GND              VIA   -    MD0100PA00X+015141Y+003711X0200Y         S0      
327GND              J35   -A41 M      A01X+015140Y+003276X0150Y0570R180 S1      
317GND              VIA   -    MD0100PA00X+015247Y+002398X0200Y         S0      
317GND              VIA   -    MD0100PA00X+015743Y+002398X0200Y         S0      
317GND              VIA   -    MD0100PA00X+015047Y+002598X0200Y         S0      
317GND              VIA   -    MD0100PA00X+012866Y+002204X0200Y         S0      
317GND              VIA   -    MD0100PA00X+013067Y+001954X0200Y         S0      
317GND              VIA   -    MD0100PA00X+012971Y+002841X0200Y    R180 S0      
317GND              VIA   -    MD0100PA00X+012972Y+003711X0200Y         S0      
327GND              J35   -A43 M      A01X+012971Y+003276X0150Y0570R180 S1      
317GND              VIA   -    MD0100PA00X+012368Y+002204X0200Y         S0      
317GND              VIA   -    MD0100PA00X+012171Y+001954X0200Y         S0      
317GND              VIA   -    MD0100PA00X+011649Y+001954X0200Y         S0      
317GND              VIA   -    MD0100PA00X+011449Y+002204X0200Y         S0      
317GND              VIA   -    MD0100PA00X+011553Y+002841X0200Y    R180 S0      
317GND              VIA   -    MD0100PA00X+011554Y+003711X0200Y         S0      
327GND              J35   -A49 M      A01X+011554Y+003276X0150Y0570R180 S1      
317GND              VIA   -    MD0100PA00X+012156Y+002398X0200Y         S0      
317GND              VIA   -    MD0100PA00X+011661Y+002398X0200Y         S0      
317GND              VIA   -    MD0100PA00X+012262Y+002841X0200Y    R180 S0      
317GND              VIA   -    MD0100PA00X+012263Y+003711X0200Y         S0      
327GND              J35   -A46 M      A01X+012263Y+003276X0150Y0570R180 S1      
317GND              VIA   -    MD0100PA00X+011461Y+002598X0200Y         S0      
317GND              VIA   -    MD0100PA00X+012356Y+002598X0200Y         S0      
317GND              VIA   -    MD0100PA00X+010754Y+001954X0200Y         S0      
317GND              VIA   -    MD0100PA00X+010951Y+002204X0200Y         S0      
317GND              VIA   -    MD0100PA00X+010232Y+001954X0200Y         S0      
317GND              VIA   -    MD0100PA00X+010031Y+002204X0200Y         S0      
317GND              VIA   -    MD0100PA00X+010136Y+002841X0200Y    R180 S0      
317GND              VIA   -    MD0100PA00X+010137Y+003711X0200Y         S0      
327GND              J35   -A55 M      A01X+010137Y+003276X0150Y0570R180 S1      
317GND              VIA   -    MD0100PA00X+010243Y+002398X0200Y         S0      
317GND              VIA   -    MD0100PA00X+010845Y+002841X0200Y    R180 S0      
317GND              VIA   -    MD0100PA00X+010846Y+003711X0200Y         S0      
327GND              J35   -A52 M      A01X+010845Y+003276X0150Y0570R180 S1      
317GND              VIA   -    MD0100PA00X+010739Y+002398X0200Y         S0      
317GND              VIA   -    MD0100PA00X+010043Y+002598X0200Y         S0      
317GND              VIA   -    MD0100PA00X+010939Y+002598X0200Y         S0      
317GND              VIA   -    MD0100PA00X+009336Y+001954X0200Y         S0      
317GND              VIA   -    MD0100PA00X+009533Y+002204X0200Y         S0      
317GND              VIA   -    MD0100PA00X+008614Y+002204X0200Y         S0      
317GND              VIA   -    MD0100PA00X+008719Y+002841X0200Y    R180 S0      
317GND              VIA   -    MD0100PA00X+008720Y+003711X0200Y         S0      
327GND              J35   -A61 M      A01X+008719Y+003276X0150Y0570R180 S1      
317GND              VIA   -    MD0100PA00X+008826Y+002398X0200Y         S0      
317GND              VIA   -    MD0100PA00X+009427Y+002841X0200Y    R180 S0      
317GND              VIA   -    MD0100PA00X+009428Y+003711X0200Y         S0      
327GND              J35   -A58 M      A01X+009428Y+003276X0150Y0570R180 S1      
317GND              VIA   -    MD0100PA00X+009322Y+002398X0200Y         S0      
317GND              VIA   -    MD0100PA00X+008626Y+002598X0200Y         S0      
317GND              VIA   -    MD0100PA00X+009522Y+002598X0200Y         S0      
317GND              VIA   -    MD0100PA00X+008815Y+001954X0200Y         S0      
317GND              VIA   -    MD0100PA00X+008116Y+002204X0200Y         S0      
317GND              VIA   -    MD0100PA00X+007919Y+001954X0200Y         S0      
317GND              VIA   -    MD0100PA00X+008010Y+002841X0200Y    R180 S0      
317GND              VIA   -    MD0100PA00X+008011Y+003711X0200Y         S0      
327GND              J35   -A64 M      A01X+008011Y+003276X0150Y0570R180 S1      
317GND              VIA   -    MD0100PA00X+008104Y+002598X0200Y         S0      
317GND              VIA   -    MD0100PA00X+007302Y+002841X0200Y    R180 S0      
317GND              VIA   -    MD0100PA00X+007302Y+003711X0200Y         S0      
327GND              J35   -A67 M      A01X+007302Y+003276X0150Y0570R180 S1      
317GND              VIA   -    MD0100PA00X+007904Y+002398X0200Y         S0      
317GND              VIA   -    MD0100PA00X+007409Y+002398X0200Y         S0      
317GND              VIA   -    MD0100PA00X+007209Y+002598X0200Y         S0      
317GND              VIA   -    MD0100PA00X+001088Y+129172X0200Y    R270 S0      
317GND              VIA   -    MD0100PA00X+001088Y+126972X0200Y    R270 S0      
317GND              VIA   -    MD0100PA00X+001088Y+124772X0200Y    R270 S0      
317GND              VIA   -    MD0100PA00X+001088Y+122572X0200Y    R270 S0      
317GND              VIA   -    MD0100PA00X+001088Y+120372X0200Y    R270 S0      
317GND              VIA   -    MD0100PA00X+001088Y+118172X0200Y    R270 S0      
317GND              VIA   -    MD0100PA00X+001088Y+115972X0200Y    R270 S0      
317GND              VIA   -    MD0100PA00X+001088Y+113772X0200Y    R270 S0      
317GND              VIA   -    MD0100PA00X+001088Y+111572X0200Y    R270 S0      
317GND              VIA   -    MD0100PA00X+001088Y+109372X0200Y    R270 S0      
317GND              VIA   -    MD0100PA00X+001088Y+107172X0200Y    R270 S0      
317GND              VIA   -    MD0100PA00X+001088Y+104972X0200Y    R270 S0      
317GND              VIA   -    MD0100PA00X+001088Y+102772X0200Y    R270 S0      
317GND              VIA   -    MD0100PA00X+001088Y+100572X0200Y    R270 S0      
317GND              VIA   -    MD0100PA00X+001088Y+098372X0200Y    R270 S0      
317GND              VIA   -    MD0100PA00X+001088Y+096172X0200Y    R270 S0      
317GND              VIA   -    MD0100PA00X+001088Y+093972X0200Y    R270 S0      
317GND              VIA   -    MD0100PA00X+001088Y+091772X0200Y    R270 S0      
317GND              VIA   -    MD0100PA00X+001088Y+089572X0200Y    R270 S0      
317GND              VIA   -    MD0100PA00X+001088Y+087372X0200Y    R270 S0      
317GND              VIA   -    MD0100PA00X+001088Y+085172X0200Y    R270 S0      
317GND              VIA   -    MD0100PA00X+001088Y+082972X0200Y    R270 S0      
317GND              VIA   -    MD0100PA00X+001088Y+080772X0200Y    R270 S0      
317GND              VIA   -    MD0100PA00X+001088Y+078572X0200Y    R270 S0      
317GND              VIA   -    MD0100PA00X+001088Y+076372X0200Y    R270 S0      
317GND              VIA   -    MD0100PA00X+001088Y+074172X0200Y    R270 S0      
317GND              VIA   -    MD0100PA00X+184070Y+072220X0200Y    R090 S0      
317GND              VIA   -    MD0100PA00X+001896Y+159818X0200Y    R225 S0      
317GND              VIA   -    MD0100PA00X+001088Y+157772X0200Y    R270 S0      
317GND              VIA   -    MD0100PA00X+001088Y+155572X0200Y    R270 S0      
317GND              VIA   -    MD0100PA00X+001088Y+153372X0200Y    R270 S0      
317GND              VIA   -    MD0100PA00X+001088Y+151172X0200Y    R270 S0      
317GND              VIA   -    MD0100PA00X+001088Y+148972X0200Y    R270 S0      
317GND              VIA   -    MD0100PA00X+001088Y+146772X0200Y    R270 S0      
317GND              VIA   -    MD0100PA00X+001088Y+144572X0200Y    R270 S0      
317GND              VIA   -    MD0100PA00X+002859Y+168396X0200Y    R270 S0      
317GND              VIA   -    MD0100PA00X+002859Y+166196X0200Y    R270 S0      
317GND              VIA   -    MD0100PA00X+002859Y+163996X0200Y    R270 S0      
317GND              VIA   -    MD0100PA00X+002859Y+161796X0200Y    R270 S0      
317GND              VIA   -    MD0100PA00X+009260Y+173712X0200Y    R180 S0      
317GND              VIA   -    MD0100PA00X+011460Y+173712X0200Y    R180 S0      
317GND              VIA   -    MD0100PA00X+013660Y+173712X0200Y    R180 S0      
317GND              VIA   -    MD0100PA00X+015860Y+173712X0200Y    R180 S0      
317GND              VIA   -    MD0100PA00X+018060Y+173712X0200Y    R180 S0      
317GND              VIA   -    MD0100PA00X+020260Y+173712X0200Y    R180 S0      
317GND              VIA   -    MD0100PA00X+022460Y+173712X0200Y    R180 S0      
317GND              VIA   -    MD0100PA00X+026660Y+173712X0200Y    R180 S0      
317GND              VIA   -    MD0100PA00X+031260Y+173712X0200Y    R180 S0      
317GND              VIA   -    MD0100PA00X+033460Y+173712X0200Y    R180 S0      
317GND              VIA   -    MD0100PA00X+035660Y+173712X0200Y    R180 S0      
317GND              VIA   -    MD0100PA00X+042260Y+173712X0200Y    R180 S0      
317GND              VIA   -    MD0100PA00X+044460Y+173712X0200Y    R180 S0      
317GND              VIA   -    MD0100PA00X+046660Y+173712X0200Y    R180 S0      
317GND              VIA   -    MD0100PA00X+048860Y+173712X0200Y    R180 S0      
317GND              VIA   -    MD0100PA00X+053260Y+173712X0200Y    R180 S0      
317GND              VIA   -    MD0100PA00X+055460Y+173712X0200Y    R180 S0      
317GND              VIA   -    MD0100PA00X+057660Y+173712X0200Y    R180 S0      
317GND              VIA   -    MD0100PA00X+059860Y+173712X0200Y    R180 S0      
317GND              VIA   -    MD0100PA00X+062060Y+173712X0200Y    R180 S0      
317GND              VIA   -    MD0100PA00X+064260Y+173712X0200Y    R180 S0      
317GND              VIA   -    MD0100PA00X+066460Y+173712X0200Y    R180 S0      
317GND              VIA   -    MD0100PA00X+075260Y+173712X0200Y    R180 S0      
317GND              VIA   -    MD0100PA00X+077397Y+173192X0200Y    R180 S0      
317GND              VIA   -    MD0100PA00X+079593Y+173192X0200Y    R180 S0      
317GND              VIA   -    MD0100PA00X+081797Y+173192X0200Y    R180 S0      
317GND              VIA   -    MD0100PA00X+083997Y+173192X0200Y    R180 S0      
317GND              VIA   -    MD0100PA00X+086197Y+173192X0200Y    R180 S0      
317GND              VIA   -    MD0100PA00X+088397Y+173192X0200Y    R180 S0      
317GND              VIA   -    MD0100PA00X+090597Y+173192X0200Y    R180 S0      
317GND              VIA   -    MD0100PA00X+092797Y+173192X0200Y    R180 S0      
317GND              VIA   -    MD0100PA00X+094997Y+173192X0200Y    R180 S0      
317GND              VIA   -    MD0100PA00X+097197Y+173192X0200Y    R180 S0      
317GND              VIA   -    MD0100PA00X+099397Y+173192X0200Y    R180 S0      
317GND              VIA   -    MD0100PA00X+101597Y+173192X0200Y    R180 S0      
317GND              VIA   -    MD0100PA00X+103797Y+173192X0200Y    R180 S0      
317GND              VIA   -    MD0100PA00X+108197Y+173192X0200Y    R180 S0      
317GND              VIA   -    MD0100PA00X+110335Y+173712X0200Y    R180 S0      
317GND              VIA   -    MD0100PA00X+112535Y+173712X0200Y    R180 S0      
317GND              VIA   -    MD0100PA00X+119135Y+173712X0200Y    R180 S0      
317GND              VIA   -    MD0100PA00X+121335Y+173712X0200Y    R180 S0      
317GND              VIA   -    MD0100PA00X+123535Y+173712X0200Y    R180 S0      
317GND              VIA   -    MD0100PA00X+125735Y+173712X0200Y    R180 S0      
317GND              VIA   -    MD0100PA00X+127935Y+173712X0200Y    R180 S0      
317GND              VIA   -    MD0100PA00X+130135Y+173712X0200Y    R180 S0      
317GND              VIA   -    MD0100PA00X+132335Y+173712X0200Y    R180 S0      
317GND              VIA   -    MD0100PA00X+134535Y+173712X0200Y    R180 S0      
317GND              VIA   -    MD0100PA00X+136735Y+173712X0200Y    R180 S0      
317GND              VIA   -    MD0100PA00X+138935Y+173712X0200Y    R180 S0      
317GND              VIA   -    MD0100PA00X+141135Y+173712X0200Y    R180 S0      
317GND              VIA   -    MD0100PA00X+143335Y+173712X0200Y    R180 S0      
317GND              VIA   -    MD0100PA00X+149935Y+173712X0200Y    R180 S0      
317GND              VIA   -    MD0100PA00X+152135Y+173712X0200Y    R180 S0      
317GND              VIA   -    MD0100PA00X+154335Y+173712X0200Y    R180 S0      
317GND              VIA   -    MD0100PA00X+156535Y+173712X0200Y    R180 S0      
317GND              VIA   -    MD0100PA00X+158735Y+173712X0200Y    R180 S0      
317GND              VIA   -    MD0100PA00X+160935Y+173712X0200Y    R180 S0      
317GND              VIA   -    MD0100PA00X+163135Y+173712X0200Y    R180 S0      
317GND              VIA   -    MD0100PA00X+165335Y+173712X0200Y    R180 S0      
317GND              VIA   -    MD0100PA00X+167535Y+173712X0200Y    R180 S0      
317GND              VIA   -    MD0100PA00X+169735Y+173712X0200Y    R180 S0      
317GND              VIA   -    MD0100PA00X+171935Y+173712X0200Y    R180 S0      
317GND              VIA   -    MD0100PA00X+174135Y+173712X0200Y    R180 S0      
317GND              VIA   -    MD0100PA00X+176335Y+173712X0200Y    R180 S0      
317GND              VIA   -    MD0100PA00X+184070Y+083220X0200Y    R090 S0      
317GND              VIA   -    MD0100PA00X+184070Y+081020X0200Y    R090 S0      
317GND              VIA   -    MD0100PA00X+184070Y+078820X0200Y    R090 S0      
317GND              VIA   -    MD0100PA00X+184070Y+076620X0200Y    R090 S0      
317GND              VIA   -    MD0100PA00X+184070Y+074420X0200Y    R090 S0      
317GND              VIA   -    MD0100PA00X+182889Y+168858X0200Y    R090 S0      
317GND              VIA   -    MD0100PA00X+182889Y+166658X0200Y    R090 S0      
317GND              VIA   -    MD0100PA00X+182889Y+164458X0200Y    R090 S0      
317GND              VIA   -    MD0100PA00X+182889Y+162258X0200Y    R090 S0      
317GND              VIA   -    MD0100PA00X+183520Y+160150X0200Y    R135 S0      
317GND              VIA   -    MD0100PA00X+184070Y+158020X0200Y    R090 S0      
317GND              VIA   -    MD0100PA00X+184070Y+155820X0200Y    R090 S0      
317GND              VIA   -    MD0100PA00X+184070Y+153620X0200Y    R090 S0      
317GND              VIA   -    MD0100PA00X+184070Y+151420X0200Y    R090 S0      
317GND              VIA   -    MD0100PA00X+184070Y+149220X0200Y    R090 S0      
317GND              VIA   -    MD0100PA00X+184070Y+147020X0200Y    R090 S0      
317GND              VIA   -    MD0100PA00X+184070Y+144820X0200Y    R090 S0      
317GND              VIA   -    MD0100PA00X+184070Y+140420X0200Y    R090 S0      
317GND              VIA   -    MD0100PA00X+184070Y+133820X0200Y    R090 S0      
317GND              VIA   -    MD0100PA00X+184070Y+131620X0200Y    R090 S0      
317GND              VIA   -    MD0100PA00X+184070Y+129420X0200Y    R090 S0      
317GND              VIA   -    MD0100PA00X+184070Y+127220X0200Y    R090 S0      
317GND              VIA   -    MD0100PA00X+184070Y+125020X0200Y    R090 S0      
317GND              VIA   -    MD0100PA00X+184070Y+122820X0200Y    R090 S0      
317GND              VIA   -    MD0100PA00X+184070Y+120620X0200Y    R090 S0      
317GND              VIA   -    MD0100PA00X+184070Y+118420X0200Y    R090 S0      
317GND              VIA   -    MD0100PA00X+184070Y+116220X0200Y    R090 S0      
317GND              VIA   -    MD0100PA00X+184070Y+114020X0200Y    R090 S0      
317GND              VIA   -    MD0100PA00X+184070Y+111820X0200Y    R090 S0      
317GND              VIA   -    MD0100PA00X+184070Y+109620X0200Y    R090 S0      
317GND              VIA   -    MD0100PA00X+184070Y+107420X0200Y    R090 S0      
317GND              VIA   -    MD0100PA00X+184070Y+105220X0200Y    R090 S0      
317GND              VIA   -    MD0100PA00X+184070Y+103020X0200Y    R090 S0      
317GND              VIA   -    MD0100PA00X+184070Y+100820X0200Y    R090 S0      
317GND              VIA   -    MD0100PA00X+184070Y+098620X0200Y    R090 S0      
317GND              VIA   -    MD0100PA00X+184070Y+096420X0200Y    R090 S0      
317GND              VIA   -    MD0100PA00X+184070Y+094220X0200Y    R090 S0      
317GND              VIA   -    MD0100PA00X+184070Y+092020X0200Y    R090 S0      
317GND              VIA   -    MD0100PA00X+184070Y+089820X0200Y    R090 S0      
317GND              VIA   -    MD0100PA00X+184070Y+087620X0200Y    R090 S0      
317GND              VIA   -    MD0100PA00X+184070Y+085420X0200Y    R090 S0      
317GND              VIA   -    MD0100PA00X+179307Y+002500X0200Y    R090 S0      
317GND              VIA   -    MD0100PA00X+179678Y+004669X0200Y         S0      
317GND              VIA   -    MD0100PA00X+181862Y+004938X0200Y         S0      
317GND              VIA   -    MD0100PA00X+184062Y+004938X0200Y         S0      
317GND              VIA   -    MD0100PA00X+185448Y+006646X0200Y    R090 S0      
317GND              VIA   -    MD0100PA00X+185448Y+011046X0200Y    R090 S0      
317GND              VIA   -    MD0100PA00X+185448Y+013246X0200Y    R090 S0      
317GND              VIA   -    MD0100PA00X+185448Y+015446X0200Y    R090 S0      
317GND              VIA   -    MD0100PA00X+185448Y+017646X0200Y    R090 S0      
317GND              VIA   -    MD0100PA00X+185448Y+019846X0200Y    R090 S0      
317GND              VIA   -    MD0100PA00X+185448Y+022046X0200Y    R090 S0      
317GND              VIA   -    MD0100PA00X+185448Y+024246X0200Y    R090 S0      
317GND              VIA   -    MD0100PA00X+185448Y+026446X0200Y    R090 S0      
317GND              VIA   -    MD0100PA00X+185448Y+028646X0200Y    R090 S0      
317GND              VIA   -    MD0100PA00X+185369Y+030845X0200Y         S0      
317GND              VIA   -    MD0100PA00X+184070Y+032620X0200Y    R090 S0      
317GND              VIA   -    MD0100PA00X+184070Y+034820X0200Y    R090 S0      
317GND              VIA   -    MD0100PA00X+184070Y+037020X0200Y    R090 S0      
317GND              VIA   -    MD0100PA00X+184070Y+039220X0200Y    R090 S0      
317GND              VIA   -    MD0100PA00X+184070Y+041420X0200Y    R090 S0      
317GND              VIA   -    MD0100PA00X+184070Y+043620X0200Y    R090 S0      
317GND              VIA   -    MD0100PA00X+184070Y+045820X0200Y    R090 S0      
317GND              VIA   -    MD0100PA00X+184070Y+048020X0200Y    R090 S0      
317GND              VIA   -    MD0100PA00X+184070Y+050220X0200Y    R090 S0      
317GND              VIA   -    MD0100PA00X+184070Y+052420X0200Y    R090 S0      
317GND              VIA   -    MD0100PA00X+184070Y+054620X0200Y    R090 S0      
317GND              VIA   -    MD0100PA00X+184070Y+056820X0200Y    R090 S0      
317GND              VIA   -    MD0100PA00X+184070Y+059020X0200Y    R090 S0      
317GND              VIA   -    MD0100PA00X+184070Y+065620X0200Y    R090 S0      
317GND              VIA   -    MD0100PA00X+184070Y+067820X0200Y    R090 S0      
317GND              VIA   -    MD0100PA00X+184070Y+070020X0200Y    R090 S0      
317GND              VIA   -    MD0100PA00X+001088Y+071972X0200Y    R270 S0      
317GND              VIA   -    MD0100PA00X+001088Y+069772X0200Y    R270 S0      
317GND              VIA   -    MD0100PA00X+001088Y+067572X0200Y    R270 S0      
317GND              VIA   -    MD0100PA00X+001088Y+065372X0200Y    R270 S0      
317GND              VIA   -    MD0100PA00X+001088Y+060972X0200Y    R270 S0      
317GND              VIA   -    MD0100PA00X+001088Y+058772X0200Y    R270 S0      
317GND              VIA   -    MD0100PA00X+001088Y+056572X0200Y    R270 S0      
317GND              VIA   -    MD0100PA00X+001088Y+054372X0200Y    R270 S0      
317GND              VIA   -    MD0100PA00X+001088Y+052172X0200Y    R270 S0      
317GND              VIA   -    MD0100PA00X+001088Y+049972X0200Y    R270 S0      
317GND              VIA   -    MD0100PA00X+001088Y+047772X0200Y    R270 S0      
317GND              VIA   -    MD0100PA00X+001088Y+045572X0200Y    R270 S0      
317GND              VIA   -    MD0100PA00X+001088Y+043372X0200Y    R270 S0      
317GND              VIA   -    MD0100PA00X+001088Y+041172X0200Y    R270 S0      
317GND              VIA   -    MD0100PA00X+001088Y+038972X0200Y    R270 S0      
317GND              VIA   -    MD0100PA00X+001088Y+036772X0200Y    R270 S0      
317GND              VIA   -    MD0100PA00X+001088Y+034572X0200Y    R270 S0      
317GND              VIA   -    MD0100PA00X+001088Y+032372X0200Y    R270 S0      
317GND              VIA   -    MD0100PA00X+000300Y+030318X0200Y    R270 S0      
317GND              VIA   -    MD0100PA00X+000300Y+028118X0200Y    R270 S0      
317GND              VIA   -    MD0100PA00X+000300Y+025918X0200Y    R270 S0      
317GND              VIA   -    MD0100PA00X+000300Y+023718X0200Y    R270 S0      
317GND              VIA   -    MD0100PA00X+000300Y+021518X0200Y    R270 S0      
317GND              VIA   -    MD0100PA00X+000300Y+019318X0200Y    R270 S0      
317GND              VIA   -    MD0100PA00X+000300Y+017118X0200Y    R270 S0      
317GND              VIA   -    MD0100PA00X+000300Y+014918X0200Y    R270 S0      
317GND              VIA   -    MD0100PA00X+000300Y+012718X0200Y    R270 S0      
317GND              VIA   -    MD0100PA00X+000300Y+006118X0200Y    R270 S0      
317GND              VIA   -    MD0100PA00X+002157Y+004938X0200Y         S0      
317GND              VIA   -    MD0100PA00X+004357Y+004938X0200Y         S0      
317GND              VIA   -    MD0100PA00X+005458Y+003034X0200Y    R270 S0      
317GND              J38   -G1  MD0440PA00X+179001Y+001248X0640Y    R180 S3      
317GND              VIA   -    MD0100PA00X+176242Y+001703X0200Y         S0      
317GND              J38   -G2  MD0440PA00X+174127Y+001248X0640Y    R180 S3      
317GND              VIA   -    MD0100PA00X+169724Y+001704X0200Y         S0      
317GND              VIA   -    MD0100PA00X+168307Y+001704X0200Y         S0      
317GND              VIA   -    MD0100PA00X+167809Y+001704X0200Y         S0      
317GND              VIA   -    MD0100PA00X+169226Y+001704X0200Y         S0      
317GND              VIA   -    MD0100PA00X+165311Y+001704X0200Y         S0      
317GND              J38   -G3  MD0440PA00X+166103Y+001248X0640Y    R180 S3      
317GND              VIA   -    MD0100PA00X+163893Y+001704X0200Y         S0      
317GND              VIA   -    MD0100PA00X+163395Y+001704X0200Y         S0      
317GND              VIA   -    MD0100PA00X+164813Y+001704X0200Y         S0      
317GND              J38   -G4  MD0440PA00X+161168Y+001248X0640Y    R180 S3      
317GND              VIA   -    MD0100PA00X+158890Y+001704X0200Y         S0      
317GND              VIA   -    MD0100PA00X+159809Y+001704X0200Y         S0      
317GND              VIA   -    MD0100PA00X+160307Y+001704X0200Y         S0      
317GND              VIA   -    MD0100PA00X+157472Y+001704X0200Y         S0      
317GND              VIA   -    MD0100PA00X+158392Y+001704X0200Y         S0      
317GND              VIA   -    MD0100PA00X+156055Y+001704X0200Y         S0      
317GND              VIA   -    MD0100PA00X+156974Y+001704X0200Y         S0      
317GND              VIA   -    MD0100PA00X+155557Y+001704X0200Y         S0      
317GND              VIA   -    MD0100PA00X+152899Y+000412X0200Y    R270 S0      
317GND              VIA   -    MD0100PA00X+155096Y+000300X0200Y         S0      
317GND              VIA   -    MD0100PA00X+157296Y+000300X0200Y         S0      
317GND              VIA   -    MD0100PA00X+159496Y+000300X0200Y         S0      
317GND              VIA   -    MD0100PA00X+161696Y+000300X0200Y         S0      
317GND              VIA   -    MD0100PA00X+163896Y+000300X0200Y         S0      
317GND              VIA   -    MD0100PA00X+166096Y+000300X0200Y         S0      
317GND              VIA   -    MD0100PA00X+168296Y+000300X0200Y         S0      
317GND              VIA   -    MD0100PA00X+170496Y+000300X0200Y         S0      
317GND              VIA   -    MD0100PA00X+172696Y+000300X0200Y         S0      
317GND              VIA   -    MD0100PA00X+174896Y+000300X0200Y         S0      
317GND              VIA   -    MD0100PA00X+177096Y+000300X0200Y         S0      
317GND              VIA   -    MD0100PA00X+179296Y+000300X0200Y         S0      
317GND              J38   -G5  MD0440PA00X+153206Y+001248X0640Y    R180 S3      
317GND              J35   -G1  MD0440PA00X+031560Y+001248X0640Y    R180 S3      
327GND              R3167 -2          A18X+029352Y+001516X0198Y0197R090 S2      
317GND              VIA   -    MD0100PA00X+029100Y+001482X0200Y         S0      
317GND              J35   -G2  MD0440PA00X+026686Y+001248X0640Y    R180 S3      
317GND              VIA   -    MD0100PA00X+022283Y+001704X0200Y         S0      
317GND              VIA   -    MD0100PA00X+021785Y+001704X0200Y         S0      
317GND              VIA   -    MD0100PA00X+020368Y+001704X0200Y         S0      
317GND              VIA   -    MD0100PA00X+020866Y+001704X0200Y         S0      
317GND              VIA   -    MD0100PA00X+017870Y+001704X0200Y         S0      
317GND              VIA   -    MD0100PA00X+017372Y+001704X0200Y         S0      
317GND              J35   -G3  MD0440PA00X+018662Y+001248X0640Y    R180 S3      
317GND              VIA   -    MD0100PA00X+015954Y+001704X0200Y         S0      
317GND              VIA   -    MD0100PA00X+016452Y+001704X0200Y         S0      
317GND              VIA   -    MD0100PA00X+012866Y+001704X0200Y         S0      
317GND              J35   -G4  MD0440PA00X+013727Y+001248X0640Y    R180 S3      
317GND              VIA   -    MD0100PA00X+012368Y+001704X0200Y         S0      
317GND              VIA   -    MD0100PA00X+011449Y+001704X0200Y         S0      
317GND              VIA   -    MD0100PA00X+010951Y+001704X0200Y         S0      
317GND              VIA   -    MD0100PA00X+010031Y+001704X0200Y         S0      
317GND              VIA   -    MD0100PA00X+009533Y+001704X0200Y         S0      
317GND              VIA   -    MD0100PA00X+008614Y+001704X0200Y         S0      
317GND              VIA   -    MD0100PA00X+008116Y+001704X0200Y         S0      
317GND              J35   -G5  MD0440PA00X+005765Y+001248X0640Y    R180 S3      
317GND              VIA   -    MD0100PA00X+005458Y+000834X0200Y    R270 S0      
317GND              VIA   -    MD0100PA00X+007593Y+000300X0200Y         S0      
317GND              VIA   -    MD0100PA00X+009793Y+000300X0200Y         S0      
317GND              VIA   -    MD0100PA00X+011993Y+000300X0200Y         S0      
317GND              VIA   -    MD0100PA00X+014193Y+000300X0200Y         S0      
317GND              VIA   -    MD0100PA00X+016393Y+000300X0200Y         S0      
317GND              VIA   -    MD0100PA00X+018593Y+000300X0200Y         S0      
317GND              VIA   -    MD0100PA00X+020793Y+000300X0200Y         S0      
317GND              VIA   -    MD0100PA00X+022993Y+000300X0200Y         S0      
317GND              VIA   -    MD0100PA00X+025193Y+000300X0200Y         S0      
317GND              VIA   -    MD0100PA00X+027393Y+000300X0200Y         S0      
317GND              VIA   -    MD0100PA00X+029593Y+000300X0200Y         S0      
317GND              VIA   -    MD0100PA00X+031793Y+000300X0200Y         S0      
327GND              C612  -2          A18X+094950Y+088042X0198Y0197R090 S2      
327GND              C611  -2   M      A18X+094950Y+087658X0198Y0197R270 S2      
327GND              C1756 -2          A18X+020366Y+166860X0198Y0197R090 S2      
327GND              R3491 -2          A01X+046542Y+173350X0198Y0197R180 S1      
327GND              R3493 -2          A01X+040908Y+165350X0198Y0197     S1      
327GND              U6014 -H19 M      A01X+026108Y+152453X0120Y         S1      
327GND              U6014 -H16 M      A01X+026108Y+152689X0120Y         S1      
327GND              U6014 -H12        A01X+026108Y+152926X0120Y         S1      
327GND              U6014 -E14 M      A01X+026313Y+152808X0120Y         S1      
327GND              U6014 -B19        A01X+026517Y+152453X0100Y0130R090 S1      
327GND              U6014 -J22 M      A01X+026012Y+152220X0120Y         S1      
327GND              PC606 -2          A01X+164651Y+063269X0198Y0197R270 S1      
317GND              VIA   -    MD0100PA00X+174098Y+157790X0200Y    R090 S0      
317GND              VIA   -    MD0100PA00X+173658Y+158748X0200Y    R090 S0      
327GND              PU6503-7_9-M      A01X+175249Y+155943X0827Y2126R090 S1      
317GND              VIA   -    MD0100PA00X+174996Y+156254X0193Y         S0      
327GND              PU6503-40  M      A01X+174904Y+156898X0690Y0770     S1      
317GND              VIA   -    MD0100PA00X+174904Y+156619X0193Y         S0      
317GND              VIA   -    MD0100PA00X+174656Y+156619X0193Y         S0      
317GND              VIA   -    MD0100PA00X+174904Y+157179X0193Y         S0      
317GND              VIA   -    MD0100PA00X+174656Y+157179X0193Y         S0      
317GND              VIA   -    MD0100PA00X+175308Y+160015X0200Y    R090 S0      
317GND              VIA   -    MD0100PA00X+175308Y+160305X0200Y    R090 S0      
317GND              VIA   -    MD0100PA00X+175308Y+159665X0200Y    R090 S0      
317GND              VIA   -    MD0100PA00X+174698Y+161655X0200Y    R090 S0      
317GND              VIA   -    MD0100PA00X+175048Y+161655X0200Y    R090 S0      
317GND              VIA   -    MD0100PA00X+174348Y+161655X0200Y    R090 S0      
317GND              VIA   -    MD0100PA00X+174718Y+162675X0200Y    R090 S0      
317GND              VIA   -    MD0100PA00X+175068Y+162675X0200Y    R090 S0      
317GND              VIA   -    MD0100PA00X+174368Y+162675X0200Y    R090 S0      
317GND              VIA   -    MD0100PA00X+175448Y+158590X0200Y         S0      
317GND              VIA   -    MD0100PA00X+175308Y+160655X0200Y    R090 S0      
317GND              VIA   -    MD0100PA00X+176184Y+163422X0200Y    R090 S0      
317GND              VIA   -    M      A01X+176905Y+158570X0200Y    R090 S2      
017GND              VIA   -    M      A18X+176905Y+158570X0260Y    R090 S2      
017GND                    -    MD0100PA00X+176905Y+158570                       
317GND              VIA   -    MD0100PA00X+177290Y+158500X0200Y    R090 S0      
317GND              VIA   -    MD0100PA00X+174019Y+155637X0200Y         S0      
317GND              VIA   -    MD0100PA00X+174008Y+155950X0200Y         S0      
317GND              VIA   -    MD0100PA00X+175152Y+156619X0193Y         S0      
317GND              VIA   -    MD0100PA00X+175256Y+156254X0193Y         S0      
317GND              VIA   -    MD0100PA00X+174716Y+155943X0193Y         S0      
317GND              VIA   -    MD0100PA00X+174716Y+155632X0193Y         S0      
317GND              VIA   -    MD0100PA00X+174976Y+155943X0193Y         S0      
317GND              VIA   -    MD0100PA00X+174976Y+155632X0193Y         S0      
317GND              VIA   -    MD0100PA00X+174456Y+155943X0193Y         S0      
317GND              VIA   -    MD0100PA00X+174456Y+155632X0193Y         S0      
317GND              VIA   -    MD0100PA00X+175236Y+155943X0193Y         S0      
317GND              VIA   -    MD0100PA00X+175236Y+155632X0193Y         S0      
317GND              VIA   -    MD0100PA00X+175504Y+155624X0193Y         S0      
317GND              VIA   -    MD0100PA00X+175152Y+157179X0193Y         S0      
317GND              VIA   -    MD0100PA00X+176983Y+156256X0200Y         S0      
317GND              VIA   -    MD0100PA00X+176108Y+156260X0193Y         S0      
317GND              VIA   -    MD0100PA00X+176111Y+155945X0193Y         S0      
317GND              VIA   -    MD0100PA00X+176111Y+155634X0193Y         S0      
317GND              VIA   -    MD0100PA00X+175824Y+155624X0193Y         S0      
317GND              VIA   -    MD0100PA00X+176821Y+155600X0200Y         S0      
327GND              PU6504-7_9-M      A01X+178823Y+155943X0827Y2126R090 S1      
317GND              VIA   -    MD0100PA00X+178571Y+156254X0193Y         S0      
317GND              VIA   -    MD0100PA00X+178551Y+155632X0193Y         S0      
317GND              VIA   -    MD0100PA00X+178551Y+155943X0193Y         S0      
327GND              PU6504-40  M      A01X+178479Y+156898X0690Y0770     S1      
317GND              VIA   -    MD0100PA00X+178478Y+156619X0193Y         S0      
317GND              VIA   -    MD0100PA00X+178230Y+156619X0193Y         S0      
317GND              VIA   -    MD0100PA00X+177598Y+155980X0200Y         S0      
317GND              VIA   -    MD0100PA00X+177598Y+155680X0200Y         S0      
317GND              VIA   -    MD0100PA00X+178031Y+155632X0193Y         S0      
317GND              VIA   -    MD0100PA00X+178031Y+155943X0193Y         S0      
317GND              VIA   -    MD0100PA00X+178291Y+155632X0193Y         S0      
317GND              VIA   -    MD0100PA00X+178291Y+155943X0193Y         S0      
317GND              VIA   -    MD0100PA00X+178230Y+157179X0193Y         S0      
317GND              VIA   -    MD0100PA00X+178478Y+157179X0193Y         S0      
317GND              VIA   -    MD0100PA00X+178938Y+158848X0200Y    R090 S0      
317GND              VIA   -    MD0100PA00X+181618Y+161655X0200Y    R090 S0      
317GND              VIA   -    MD0100PA00X+180918Y+161655X0200Y    R090 S0      
317GND              VIA   -    MD0100PA00X+181268Y+161655X0200Y    R090 S0      
317GND              VIA   -    MD0100PA00X+178726Y+156619X0193Y         S0      
317GND              VIA   -    MD0100PA00X+178726Y+157179X0193Y         S0      
317GND              VIA   -    MD0100PA00X+178831Y+156254X0193Y         S0      
317GND              VIA   -    MD0100PA00X+178811Y+155943X0193Y         S0      
317GND              VIA   -    MD0100PA00X+178868Y+158580X0200Y         S0      
317GND              VIA   -    MD0100PA00X+180469Y+155937X0200Y         S0      
317GND              VIA   -    MD0100PA00X+177269Y+154687X0200Y         S0      
317GND              VIA   -    MD0100PA00X+177269Y+154387X0200Y         S0      
317GND              VIA   -    MD0100PA00X+176869Y+154987X0200Y         S0      
317GND              VIA   -    MD0100PA00X+176869Y+155287X0200Y         S0      
317GND              VIA   -    MD0100PA00X+176919Y+154387X0200Y         S0      
317GND              VIA   -    MD0100PA00X+176919Y+154687X0200Y         S0      
317GND              VIA   -    MD0100PA00X+177619Y+154687X0200Y         S0      
317GND              VIA   -    MD0100PA00X+177619Y+154387X0200Y         S0      
317GND              VIA   -    MD0100PA00X+180169Y+154937X0200Y         S0      
317GND              VIA   -    MD0100PA00X+180169Y+155287X0200Y         S0      
317GND              VIA   -    MD0100PA00X+180169Y+155587X0200Y         S0      
317GND              VIA   -    MD0100PA00X+180169Y+154237X0193Y         S0      
317GND              VIA   -    MD0100PA00X+180169Y+154587X0200Y         S0      
317GND              VIA   -    MD0100PA00X+179063Y+155620X0193Y         S0      
317GND              VIA   -    MD0100PA00X+179383Y+155620X0193Y         S0      
317GND              VIA   -    MD0100PA00X+178811Y+155632X0193Y         S0      
317GND              VIA   -    MD0100PA00X+179684Y+155612X0193Y         S0      
317GND              VIA   -    MD0100PA00X+180469Y+154937X0200Y         S0      
317GND              VIA   -    MD0100PA00X+180469Y+155287X0200Y         S0      
317GND              VIA   -    MD0100PA00X+180469Y+155587X0200Y         S0      
317GND              VIA   -    MD0100PA00X+180469Y+154237X0200Y         S0      
317GND              VIA   -    MD0100PA00X+180469Y+154587X0200Y         S0      
317GND              VIA   -    MD0100PA00X+173774Y+154802X0200Y         S0      
317GND              VIA   -    MD0100PA00X+174059Y+154795X0200Y         S0      
317GND              VIA   -    MD0100PA00X+174319Y+154787X0200Y         S0      
317GND              VIA   -    MD0100PA00X+174319Y+154387X0200Y         S0      
317GND              VIA   -    MD0100PA00X+174006Y+153742X0200Y    R090 S0      
317GND              VIA   -    MD0100PA00X+174216Y+153962X0200Y    R090 S0      
317GND              VIA   -    MD0100PA00X+173761Y+153981X0200Y    R090 S0      
317GND              VIA   -    MD0100PA00X+174487Y+153959X0200Y    R090 S0      
317GND              VIA   -    MD0100PA00X+174133Y+148840X0200Y    R090 S0      
317GND              VIA   -    MD0100PA00X+174133Y+149140X0200Y    R090 S0      
317GND              VIA   -    MD0100PA00X+174133Y+148540X0200Y    R090 S0      
317GND              VIA   -    MD0100PA00X+174133Y+148240X0200Y    R090 S0      
317GND              VIA   -    MD0100PA00X+175633Y+148840X0200Y    R090 S0      
317GND              VIA   -    MD0100PA00X+175633Y+149140X0200Y    R090 S0      
317GND              VIA   -    MD0100PA00X+175633Y+148240X0200Y    R090 S0      
317GND              VIA   -    MD0100PA00X+175633Y+148540X0200Y    R090 S0      
317GND              VIA   -    MD0100PA00X+176403Y+148840X0200Y    R090 S0      
317GND              VIA   -    MD0100PA00X+176403Y+149140X0200Y    R090 S0      
317GND              VIA   -    MD0100PA00X+176403Y+148240X0200Y    R090 S0      
317GND              VIA   -    MD0100PA00X+176403Y+148540X0200Y    R090 S0      
317GND              VIA   -    MD0100PA00X+177903Y+148840X0200Y    R090 S0      
317GND              VIA   -    MD0100PA00X+177903Y+149140X0200Y    R090 S0      
317GND              VIA   -    MD0100PA00X+177903Y+148540X0200Y    R090 S0      
317GND              VIA   -    MD0100PA00X+177903Y+148240X0200Y    R090 S0      
317GND              VIA   -    MD0100PA00X+178803Y+148840X0200Y    R090 S0      
317GND              VIA   -    MD0100PA00X+178803Y+149140X0200Y    R090 S0      
317GND              VIA   -    MD0100PA00X+178803Y+148240X0200Y    R090 S0      
317GND              VIA   -    MD0100PA00X+178803Y+148540X0200Y    R090 S0      
317GND              VIA   -    MD0100PA00X+180303Y+148840X0200Y    R090 S0      
317GND              VIA   -    MD0100PA00X+180303Y+149140X0200Y    R090 S0      
317GND              VIA   -    MD0100PA00X+181203Y+148840X0200Y    R090 S0      
317GND              VIA   -    MD0100PA00X+181203Y+149140X0200Y    R090 S0      
317GND              VIA   -    MD0100PA00X+180303Y+148540X0200Y    R090 S0      
317GND              VIA   -    MD0100PA00X+180303Y+148240X0200Y    R090 S0      
317GND              VIA   -    MD0100PA00X+181203Y+148240X0200Y    R090 S0      
317GND              VIA   -    MD0100PA00X+181203Y+148540X0200Y    R090 S0      
317GND              VIA   -    MD0100PA00X+182703Y+148240X0200Y    R090 S0      
317GND              VIA   -    MD0100PA00X+182703Y+148540X0200Y    R090 S0      
317GND              VIA   -    MD0100PA00X+182703Y+149140X0200Y    R090 S0      
317GND              VIA   -    MD0100PA00X+182703Y+148840X0200Y    R090 S0      
327GND              U6014 -FF14M      A01X+018150Y+152808X0120Y         S1      
327GND              U6014 -FJ12M      A01X+017946Y+152926X0100Y0130R090 S1      
327GND              U6015 -FF14M      A01X+030956Y+152808X0120Y         S1      
327GND              U6015 -FA15M      A01X+031259Y+152788X0150Y         S1      
327GND              U6015 -EP13M      A01X+031732Y+152811X0120Y         S1      
327GND              U6015 -EG13M      A01X+032204Y+152811X0120Y         S1      
327GND              U6015 -DY13M      A01X+032676Y+152811X0120Y         S1      
327GND              U6015 -DN13M      A01X+033149Y+152811X0120Y         S1      
327GND              U6015 -DF13M      A01X+033621Y+152811X0120Y         S1      
327GND              U6015 -CW13M      A01X+034094Y+152811X0120Y         S1      
327GND              U6015 -CM13M      A01X+034566Y+152811X0120Y         S1      
327GND              U6015 -AC13M      A01X+037873Y+152811X0120Y         S1      
327GND              U6015 -T13 M      A01X+038346Y+152811X0120Y         S1      
327GND              U6015 -H16 M      A01X+038914Y+152689X0120Y         S1      
327GND              U6015 -E30        A01X+039119Y+151626X0120Y         S1      
327GND              U6015 -E33 M      A01X+039119Y+151390X0120Y         S1      
327GND              R752  -2   M      A01X+030400Y+155079X0120Y0150R090 S1      
327GND              R794  -2          A01X+030720Y+155079X0120Y0150R090 S1      
327GND              U6017 -V1  M      A01X+051818Y+154048X0100Y0130     S1      
327GND              U6017 -U2  M      A01X+051936Y+153843X0120Y         S1      
327GND              U6017 -AM1 M      A01X+050873Y+154048X0100Y0130     S1      
327GND              U6017 -AL2 M      A01X+050991Y+153843X0120Y         S1      
327GND              U6017 -AW1 M      A01X+050401Y+154048X0100Y0130     S1      
327GND              U6017 -AV2 M      A01X+050519Y+153843X0120Y         S1      
327GND              U6017 -BF1 M      A01X+049928Y+154048X0100Y0130     S1      
327GND              U6017 -BE2 M      A01X+050046Y+153843X0120Y         S1      
327GND              U6017 -BY1 M      A01X+048983Y+154048X0100Y0130     S1      
327GND              U6017 -BW2 M      A01X+049102Y+153843X0120Y         S1      
327GND              U6017 -CG1 M      A01X+048511Y+154048X0100Y0130     S1      
327GND              U6017 -CF2 M      A01X+048629Y+153843X0120Y         S1      
327GND              U6017 -CP1 M      A01X+048039Y+154048X0100Y0130     S1      
327GND              U6017 -CN2 M      A01X+048157Y+153843X0120Y         S1      
327GND              U6017 -DH1 M      A01X+047094Y+154048X0100Y0130     S1      
327GND              U6017 -DG2 M      A01X+047212Y+153843X0120Y         S1      
327GND              U6017 -EB1 M      A01X+046149Y+154048X0100Y0130     S1      
327GND              U6017 -EA2 M      A01X+046267Y+153843X0120Y         S1      
327GND              U6017 -EJ1 M      A01X+045676Y+154048X0100Y0130     S1      
327GND              U6017 -EH2 M      A01X+045794Y+153843X0120Y         S1      
327GND              U6017 -FD1 M      A01X+044732Y+154048X0100Y0130     S1      
327GND              U6017 -FB2 M      A01X+044850Y+153843X0120Y         S1      
327GND              U6017 -FJ12M      A01X+044363Y+152926X0100Y0130R090 S1      
327GND              U6017 -FF14M      A01X+044568Y+152808X0120Y         S1      
327GND              U6017 -FJ19M      A01X+044363Y+152453X0100Y0130R090 S1      
327GND              U6017 -FF21M      A01X+044568Y+152335X0120Y         S1      
327GND              U6017 -CN34M      A01X+048157Y+151150X0120Y         S1      
327GND              U6017 -BM34M      A01X+049574Y+151150X0120Y         S1      
327GND              U6017 -AD34M      A01X+051464Y+151150X0120Y         S1      
327GND              U6017 -L35 M      A01X+052290Y+150946X0100Y0130     S1      
327GND              U6017 -K34 M      A01X+052409Y+151150X0120Y         S1      
327GND              U6017 -B19        A01X+052935Y+152453X0100Y0130R090 S1      
327GND              U6017 -H12        A01X+052526Y+152926X0120Y         S1      
327GND              U6017 -E14 M      A01X+052730Y+152808X0120Y         S1      
327GND              C500  -2          A18X+045125Y+152865X0120Y0150R270 S2      
317GND              VIA   -    MD0080PA00X+045125Y+152885X0160Y         S0      
327GND              U6017 -EP13M      A01X+045343Y+152811X0120Y         S1      
327GND              C457  -2          A18X+045598Y+152865X0120Y0150R270 S2      
317GND              VIA   -    MD0080PA00X+045598Y+152885X0160Y         S0      
327GND              U6017 -EG13M      A01X+045815Y+152811X0120Y         S1      
327GND              C450  -2          A18X+046070Y+152865X0120Y0150R270 S2      
317GND              VIA   -    MD0080PA00X+046070Y+152885X0160Y         S0      
327GND              U6017 -DY13M      A01X+046288Y+152811X0120Y         S1      
327GND              C477  -2          A18X+046543Y+152865X0120Y0150R270 S2      
317GND              VIA   -    MD0080PA00X+046543Y+152885X0160Y         S0      
327GND              U6017 -DN13M      A01X+046760Y+152811X0120Y         S1      
327GND              C463  -2          A18X+047015Y+152865X0120Y0150R270 S2      
317GND              VIA   -    MD0080PA00X+047015Y+152885X0160Y         S0      
327GND              U6017 -DF13M      A01X+047232Y+152811X0120Y         S1      
327GND              C451  -2          A18X+047488Y+152865X0120Y0150R270 S2      
317GND              VIA   -    MD0080PA00X+047488Y+152885X0160Y         S0      
327GND              U6017 -CW13M      A01X+047705Y+152811X0120Y         S1      
327GND              C440  -2          A18X+047960Y+152865X0120Y0150R270 S2      
317GND              VIA   -    MD0080PA00X+047960Y+152885X0160Y         S0      
327GND              U6017 -CM13M      A01X+048177Y+152811X0120Y         S1      
327GND              C442  -2          A18X+048432Y+152865X0120Y0150R270 S2      
317GND              VIA   -    MD0080PA00X+048432Y+152885X0160Y         S0      
327GND              U6017 -CE13M      A01X+048650Y+152811X0120Y         S1      
327GND              C447  -2          A18X+048905Y+152865X0120Y0150R270 S2      
317GND              VIA   -    MD0080PA00X+048905Y+152885X0160Y         S0      
327GND              U6017 -BV13M      A01X+049122Y+152811X0120Y         S1      
327GND              C444  -2          A18X+049377Y+152865X0120Y0150R270 S2      
317GND              VIA   -    MD0080PA00X+049377Y+152885X0160Y         S0      
327GND              U6017 -BL13M      A01X+049595Y+152811X0120Y         S1      
327GND              C458  -2          A18X+049850Y+152865X0120Y0150R270 S2      
317GND              VIA   -    MD0080PA00X+049850Y+152885X0160Y         S0      
327GND              U6017 -BD13M      A01X+050067Y+152811X0120Y         S1      
327GND              C464  -2          A18X+050322Y+152865X0120Y0150R270 S2      
317GND              VIA   -    MD0080PA00X+050322Y+152885X0160Y         S0      
327GND              U6017 -AU13M      A01X+050540Y+152811X0120Y         S1      
327GND              C473  -2          A18X+050795Y+152865X0120Y0150R270 S2      
317GND              VIA   -    MD0080PA00X+050795Y+152885X0160Y         S0      
327GND              U6017 -AK13M      A01X+051012Y+152811X0120Y         S1      
327GND              C496  -2          A18X+051267Y+152865X0120Y0150R270 S2      
317GND              VIA   -    MD0080PA00X+051267Y+152885X0160Y         S0      
327GND              U6017 -AC13M      A01X+051484Y+152811X0120Y         S1      
327GND              C462  -2          A18X+051740Y+152865X0120Y0150R270 S2      
317GND              VIA   -    MD0080PA00X+051740Y+152885X0160Y         S0      
327GND              U6017 -T13 M      A01X+051957Y+152811X0120Y         S1      
327GND              C495  -2          A18X+052212Y+152865X0120Y0150R270 S2      
317GND              VIA   -    MD0080PA00X+052212Y+152885X0160Y         S0      
327GND              U6017 -H16 M      A01X+052526Y+152689X0120Y         S1      
327GND              U6017 -H19 M      A01X+052526Y+152453X0120Y         S1      
327GND              C455  -2          A18X+045070Y+152165X0120Y0150R090 S2      
317GND              VIA   -    MD0080PA00X+045070Y+152145X0160Y         S0      
327GND              U6017 -EP22M      A01X+045343Y+152220X0120Y         S1      
317GND              VIA   -    MD0080PA00X+045543Y+152145X0160Y         S0      
327GND              C491  -2          A18X+045543Y+152165X0120Y0150R090 S2      
327GND              U6017 -EG22M      A01X+045815Y+152220X0120Y         S1      
327GND              C452  -2          A18X+046015Y+152165X0120Y0150R090 S2      
317GND              VIA   -    MD0080PA00X+046015Y+152145X0160Y         S0      
327GND              U6017 -DY22M      A01X+046288Y+152220X0120Y         S1      
327GND              C497  -2          A18X+046488Y+152165X0120Y0150R090 S2      
317GND              VIA   -    MD0080PA00X+046488Y+152145X0160Y         S0      
327GND              U6017 -DN22M      A01X+046760Y+152220X0120Y         S1      
327GND              C456  -2          A18X+046960Y+152165X0120Y0150R090 S2      
317GND              VIA   -    MD0080PA00X+046960Y+152145X0160Y         S0      
327GND              U6017 -DF22M      A01X+047232Y+152220X0120Y         S1      
327GND              C449  -2          A18X+047432Y+152165X0120Y0150R090 S2      
317GND              VIA   -    MD0080PA00X+047432Y+152145X0160Y         S0      
327GND              U6017 -CW22M      A01X+047705Y+152220X0120Y         S1      
327GND              C446  -2          A18X+047905Y+152165X0120Y0150R090 S2      
317GND              VIA   -    MD0080PA00X+047905Y+152145X0160Y         S0      
327GND              U6017 -CM22M      A01X+048177Y+152220X0120Y         S1      
327GND              C443  -2          A18X+048377Y+152165X0120Y0150R090 S2      
317GND              VIA   -    MD0080PA00X+048377Y+152145X0160Y         S0      
327GND              U6017 -CE22M      A01X+048650Y+152220X0120Y         S1      
327GND              C445  -2          A18X+048850Y+152165X0120Y0150R090 S2      
317GND              VIA   -    MD0080PA00X+048850Y+152145X0160Y         S0      
327GND              U6017 -BV22M      A01X+049122Y+152220X0120Y         S1      
327GND              C441  -2          A18X+049322Y+152165X0120Y0150R090 S2      
317GND              VIA   -    MD0080PA00X+049322Y+152145X0160Y         S0      
327GND              U6017 -BL22M      A01X+049595Y+152220X0120Y         S1      
327GND              C493  -2          A18X+049795Y+152165X0120Y0150R090 S2      
317GND              VIA   -    MD0080PA00X+049795Y+152145X0160Y         S0      
327GND              U6017 -BD22M      A01X+050067Y+152220X0120Y         S1      
327GND              C460  -2          A18X+050267Y+152165X0120Y0150R090 S2      
317GND              VIA   -    MD0080PA00X+050267Y+152145X0160Y         S0      
327GND              U6017 -AU22M      A01X+050540Y+152220X0120Y         S1      
327GND              C453  -2          A18X+050740Y+152165X0120Y0150R090 S2      
317GND              VIA   -    MD0080PA00X+050740Y+152145X0160Y         S0      
327GND              U6017 -AK22M      A01X+051012Y+152220X0120Y         S1      
327GND              C492  -2          A18X+051212Y+152165X0120Y0150R090 S2      
317GND              VIA   -    MD0080PA00X+051212Y+152145X0160Y         S0      
327GND              U6017 -AC22M      A01X+051484Y+152220X0120Y         S1      
327GND              C470  -2          A18X+051684Y+152165X0120Y0150R090 S2      
317GND              VIA   -    MD0080PA00X+051684Y+152145X0160Y         S0      
327GND              U6017 -T22 M      A01X+051957Y+152220X0120Y         S1      
327GND              C448  -2          A18X+052157Y+152165X0120Y0150R090 S2      
317GND              VIA   -    MD0080PA00X+052157Y+152145X0160Y         S0      
327GND              U6017 -J22 M      A01X+052429Y+152220X0120Y         S1      
327GND              C485  -2          A18X+052631Y+152165X0120Y0150R090 S2      
317GND              VIA   -    MD0080PA00X+052631Y+152145X0160Y         S0      
327GND              U6017 -E27 M      A01X+052730Y+151863X0120Y         S1      
327GND              U6017 -E30        A01X+052730Y+151626X0120Y         S1      
327GND              U6017 -E33 M      A01X+052730Y+151390X0120Y         S1      
327GND              U6017 -H31 M      A01X+052526Y+151508X0120Y         S1      
327GND              U6017 -U34 M      A01X+051936Y+151150X0120Y         S1      
327GND              U6017 -T32 M      A01X+051957Y+151424X0150Y         S1      
317GND              VIA   -    MD0080PA00X+051718Y+151424X0160Y    R180 S0      
327GND              U6017 -AC32M      A01X+051484Y+151424X0150Y         S1      
327GND              U6017 -AL34M      A01X+050991Y+151150X0120Y         S1      
327GND              U6017 -AK32M      A01X+051012Y+151424X0150Y         S1      
327GND              U6017 -AV34M      A01X+050519Y+151150X0120Y         S1      
327GND              U6017 -AU32M      A01X+050540Y+151424X0150Y         S1      
327GND              U6017 -BE34M      A01X+050046Y+151150X0120Y         S1      
327GND              U6017 -BD32M      A01X+050067Y+151424X0150Y         S1      
327GND              U6017 -BL32M      A01X+049595Y+151424X0150Y         S1      
327GND              U6017 -BW34M      A01X+049102Y+151150X0120Y         S1      
327GND              U6017 -BV32M      A01X+049122Y+151424X0150Y         S1      
327GND              U6017 -CF34M      A01X+048629Y+151150X0120Y         S1      
327GND              U6017 -CE32M      A01X+048650Y+151424X0150Y         S1      
327GND              U6017 -CM32M      A01X+048177Y+151424X0150Y         S1      
327GND              U6017 -CY34M      A01X+047684Y+151150X0120Y         S1      
327GND              U6017 -CW32M      A01X+047705Y+151424X0150Y         S1      
327GND              U6017 -DG34M      A01X+047212Y+151150X0120Y         S1      
327GND              U6017 -DF32M      A01X+047232Y+151424X0150Y         S1      
327GND              U6017 -DP34M      A01X+046739Y+151150X0120Y         S1      
327GND              U6017 -DN32M      A01X+046760Y+151424X0150Y         S1      
327GND              U6017 -EA34M      A01X+046267Y+151150X0120Y         S1      
327GND              U6017 -DY32M      A01X+046288Y+151424X0150Y         S1      
327GND              U6017 -EH34M      A01X+045794Y+151150X0120Y         S1      
327GND              U6017 -EG32M      A01X+045815Y+151424X0150Y         S1      
327GND              U6017 -ER34M      A01X+045322Y+151150X0120Y         S1      
327GND              U6017 -EP32M      A01X+045343Y+151424X0150Y         S1      
327GND              U6017 -FB34M      A01X+044850Y+151150X0120Y         S1      
327GND              U6017 -FA32M      A01X+044870Y+151424X0150Y         S1      
327GND              U6017 -FC28M      A01X+044772Y+151744X0120Y         S1      
327GND              U6017 -FC25M      A01X+044772Y+151981X0120Y         S1      
327GND              U6017 -FC23M      A01X+044772Y+152217X0120Y         S1      
327GND              U6017 -FC19M      A01X+044772Y+152453X0120Y         S1      
327GND              U6017 -FA15M      A01X+044870Y+152788X0150Y         S1      
327GND              U6017 -FC9 M      A01X+044772Y+153162X0120Y         S1      
327GND              U6017 -FC6 M      A01X+044772Y+153398X0120Y         S1      
327GND              U6017 -FC3 M      A01X+044772Y+153634X0120Y         S1      
327GND              U6017 -ET1 M      A01X+045204Y+154048X0100Y0130     S1      
327GND              U6017 -ER2 M      A01X+045322Y+153843X0120Y         S1      
327GND              U6017 -EP4 M      A01X+045343Y+153606X0150Y         S1      
327GND              U6017 -EG4 M      A01X+045815Y+153606X0150Y         S1      
327GND              U6017 -DY4 M      A01X+046288Y+153606X0150Y         S1      
327GND              U6017 -DR1 M      A01X+046621Y+154048X0100Y0130     S1      
327GND              U6017 -DP2 M      A01X+046739Y+153843X0120Y         S1      
327GND              U6017 -DN4 M      A01X+046760Y+153606X0150Y         S1      
317GND              VIA   -    MD0080PA00X+046965Y+153606X0160Y    R180 S0      
327GND              U6017 -DF4 M      A01X+047232Y+153606X0150Y         S1      
317GND              VIA   -    MD0080PA00X+047438Y+153606X0160Y    R180 S0      
327GND              U6017 -DA1 M      A01X+047566Y+154048X0100Y0130     S1      
327GND              U6017 -CY2 M      A01X+047684Y+153843X0120Y         S1      
327GND              U6017 -CW4 M      A01X+047705Y+153606X0150Y         S1      
327GND              U6017 -CM4 M      A01X+048177Y+153606X0150Y         S1      
317GND              VIA   -    MD0080PA00X+048382Y+153606X0160Y    R180 S0      
327GND              U6017 -CE4 M      A01X+048650Y+153606X0150Y         S1      
327GND              U6017 -BV4 M      A01X+049122Y+153606X0150Y         S1      
317GND              VIA   -    MD0080PA00X+049327Y+153606X0160Y    R180 S0      
327GND              U6017 -BN1 M      A01X+049456Y+154048X0100Y0130     S1      
327GND              U6017 -BM2 M      A01X+049574Y+153843X0120Y         S1      
327GND              U6017 -BL4 M      A01X+049595Y+153606X0150Y         S1      
327GND              C454  -2          A18X+049800Y+153796X0120Y0150R090 S2      
317GND              VIA   -    MD0080PA00X+049800Y+153606X0160Y    R180 S0      
327GND              U6017 -BD4 M      A01X+050067Y+153606X0150Y         S1      
327GND              U6017 -AU4 M      A01X+050540Y+153606X0150Y         S1      
317GND              VIA   -    MD0080PA00X+050745Y+153606X0160Y    R180 S0      
327GND              U6017 -AK4 M      A01X+051012Y+153606X0150Y         S1      
327GND              U6017 -AE1 M      A01X+051346Y+154048X0100Y0130     S1      
327GND              U6017 -AD2 M      A01X+051464Y+153843X0120Y         S1      
327GND              U6017 -AC4 M      A01X+051484Y+153606X0150Y         S1      
317GND              VIA   -    MD0080PA00X+051690Y+153606X0160Y    R180 S0      
327GND              U6017 -T4  M      A01X+051957Y+153606X0150Y         S1      
327GND              U6017 -L1  M      A01X+052290Y+154048X0100Y0130     S1      
327GND              U6017 -K2  M      A01X+052409Y+153843X0120Y         S1      
327GND              U6017 -J4  M      A01X+052429Y+153606X0150Y         S1      
327GND              U6016 -L1  M      A01X+065097Y+154048X0100Y0130     S1      
327GND              U6016 -K2  M      A01X+065215Y+153843X0120Y         S1      
327GND              U6016 -J4  M      A01X+065236Y+153606X0150Y         S1      
327GND              U6016 -V1  M      A01X+064624Y+154048X0100Y0130     S1      
327GND              U6016 -U2  M      A01X+064742Y+153843X0120Y         S1      
327GND              U6016 -T4  M      A01X+064763Y+153606X0150Y         S1      
327GND              U6016 -CG1 M      A01X+061317Y+154048X0100Y0130     S1      
327GND              U6016 -CF2 M      A01X+061435Y+153843X0120Y         S1      
327GND              U6016 -FD1 M      A01X+057538Y+154048X0100Y0130     S1      
327GND              U6016 -FB2 M      A01X+057656Y+153843X0120Y         S1      
327GND              U6016 -FJ12M      A01X+057169Y+152926X0100Y0130R090 S1      
327GND              U6016 -FF14M      A01X+057374Y+152808X0120Y         S1      
327GND              U6016 -L35 M      A01X+065097Y+150946X0100Y0130     S1      
327GND              U6016 -K34 M      A01X+065215Y+151150X0120Y         S1      
327GND              U6016 -B19        A01X+065741Y+152453X0100Y0130R090 S1      
327GND              U6016 -H12        A01X+065332Y+152926X0120Y         S1      
327GND              U6016 -E14 M      A01X+065536Y+152808X0120Y         S1      
327GND              C421  -2          A18X+057932Y+152865X0120Y0150R270 S2      
317GND              VIA   -    MD0080PA00X+057932Y+152885X0160Y         S0      
327GND              U6016 -EP13M      A01X+058149Y+152811X0120Y         S1      
327GND              C428  -2          A18X+058404Y+152865X0120Y0150R270 S2      
317GND              VIA   -    MD0080PA00X+058404Y+152885X0160Y         S0      
327GND              U6016 -EG13M      A01X+058621Y+152811X0120Y         S1      
327GND              C411  -2          A18X+058876Y+152865X0120Y0150R270 S2      
317GND              VIA   -    MD0080PA00X+058876Y+152885X0160Y         S0      
327GND              U6016 -DY13M      A01X+059094Y+152811X0120Y         S1      
327GND              C403  -2          A18X+059349Y+152865X0120Y0150R270 S2      
317GND              VIA   -    MD0080PA00X+059349Y+152885X0160Y         S0      
327GND              U6016 -DN13M      A01X+059566Y+152811X0120Y         S1      
327GND              C396  -2          A18X+059821Y+152865X0120Y0150R270 S2      
317GND              VIA   -    MD0080PA00X+059821Y+152885X0160Y         S0      
327GND              U6016 -DF13M      A01X+060039Y+152811X0120Y         S1      
327GND              C383  -2          A18X+060294Y+152865X0120Y0150R270 S2      
317GND              VIA   -    MD0080PA00X+060294Y+152885X0160Y         S0      
327GND              U6016 -CW13M      A01X+060511Y+152811X0120Y         S1      
327GND              C374  -2          A18X+060766Y+152865X0120Y0150R270 S2      
317GND              VIA   -    MD0080PA00X+060766Y+152885X0160Y         S0      
327GND              U6016 -CM13M      A01X+060984Y+152811X0120Y         S1      
327GND              C376  -2          A18X+061239Y+152865X0120Y0150R270 S2      
317GND              VIA   -    MD0080PA00X+061239Y+152885X0160Y         S0      
327GND              U6016 -CE13M      A01X+061456Y+152811X0120Y         S1      
327GND              C379  -2          A18X+061711Y+152865X0120Y0150R270 S2      
317GND              VIA   -    MD0080PA00X+061711Y+152885X0160Y         S0      
327GND              U6016 -BV13M      A01X+061928Y+152811X0120Y         S1      
327GND              C378  -2          A18X+062184Y+152865X0120Y0150R270 S2      
317GND              VIA   -    MD0080PA00X+062184Y+152885X0160Y         S0      
327GND              U6016 -BL13M      A01X+062401Y+152811X0120Y         S1      
327GND              C388  -2          A18X+062656Y+152865X0120Y0150R270 S2      
317GND              VIA   -    MD0080PA00X+062656Y+152885X0160Y         S0      
327GND              U6016 -BD13M      A01X+062873Y+152811X0120Y         S1      
327GND              C397  -2          A18X+063128Y+152865X0120Y0150R270 S2      
317GND              VIA   -    MD0080PA00X+063128Y+152885X0160Y         S0      
327GND              U6016 -AU13M      A01X+063346Y+152811X0120Y         S1      
327GND              C427  -2          A18X+063601Y+152865X0120Y0150R270 S2      
317GND              VIA   -    MD0080PA00X+063601Y+152885X0160Y         S0      
327GND              U6016 -AK13M      A01X+063818Y+152811X0120Y         S1      
327GND              C400  -2          A18X+064073Y+152865X0120Y0150R270 S2      
317GND              VIA   -    MD0080PA00X+064073Y+152885X0160Y         S0      
327GND              U6016 -AC13M      A01X+064291Y+152811X0120Y         S1      
327GND              C430  -2          A18X+064546Y+152865X0120Y0150R270 S2      
317GND              VIA   -    MD0080PA00X+064546Y+152885X0160Y         S0      
327GND              U6016 -T13 M      A01X+064763Y+152811X0120Y         S1      
327GND              C395  -2          A18X+065018Y+152865X0120Y0150R270 S2      
317GND              VIA   -    MD0080PA00X+065018Y+152885X0160Y         S0      
327GND              U6016 -H16 M      A01X+065332Y+152689X0120Y         S1      
327GND              U6016 -H19 M      A01X+065332Y+152453X0120Y         S1      
327GND              C407  -2          A18X+057876Y+152165X0120Y0150R090 S2      
317GND              VIA   -    MD0080PA00X+057876Y+152145X0160Y         S0      
327GND              U6016 -EP22M      A01X+058149Y+152220X0120Y         S1      
327GND              C425  -2          A18X+058349Y+152165X0120Y0150R090 S2      
317GND              VIA   -    MD0080PA00X+058349Y+152145X0160Y         S0      
327GND              U6016 -EG22M      A01X+058621Y+152220X0120Y         S1      
327GND              C415  -2          A18X+058821Y+152165X0120Y0150R090 S2      
317GND              VIA   -    MD0080PA00X+058821Y+152145X0160Y         S0      
327GND              U6016 -DY22M      A01X+059094Y+152220X0120Y         S1      
327GND              C389  -2          A18X+059294Y+152165X0120Y0150R090 S2      
317GND              VIA   -    MD0080PA00X+059294Y+152145X0160Y         S0      
327GND              U6016 -DN22M      A01X+059566Y+152220X0120Y         S1      
327GND              C390  -2          A18X+059766Y+152165X0120Y0150R090 S2      
317GND              VIA   -    MD0080PA00X+059766Y+152145X0160Y         S0      
327GND              U6016 -DF22M      A01X+060039Y+152220X0120Y         S1      
327GND              C385  -2          A18X+060239Y+152165X0120Y0150R090 S2      
317GND              VIA   -    MD0080PA00X+060239Y+152145X0160Y         S0      
327GND              U6016 -CW22M      A01X+060511Y+152220X0120Y         S1      
327GND              C381  -2          A18X+060711Y+152165X0120Y0150R090 S2      
317GND              VIA   -    MD0080PA00X+060711Y+152145X0160Y         S0      
327GND              U6016 -CM22M      A01X+060984Y+152220X0120Y         S1      
327GND              C377  -2          A18X+061184Y+152165X0120Y0150R090 S2      
317GND              VIA   -    MD0080PA00X+061184Y+152145X0160Y         S0      
327GND              U6016 -CE22M      A01X+061456Y+152220X0120Y         S1      
327GND              C380  -2          A18X+061656Y+152165X0120Y0150R090 S2      
317GND              VIA   -    MD0080PA00X+061656Y+152145X0160Y         S0      
327GND              U6016 -BV22M      A01X+061928Y+152220X0120Y         S1      
327GND              C375  -2          A18X+062128Y+152165X0120Y0150R090 S2      
317GND              VIA   -    MD0080PA00X+062128Y+152145X0160Y         S0      
327GND              U6016 -BL22M      A01X+062401Y+152220X0120Y         S1      
327GND              C392  -2          A18X+062601Y+152165X0120Y0150R090 S2      
317GND              VIA   -    MD0080PA00X+062601Y+152145X0160Y         S0      
327GND              U6016 -BD22M      A01X+062873Y+152220X0120Y         S1      
327GND              C394  -2          A18X+063073Y+152165X0120Y0150R090 S2      
317GND              VIA   -    MD0080PA00X+063073Y+152145X0160Y         S0      
327GND              U6016 -AU22M      A01X+063346Y+152220X0120Y         S1      
327GND              C387  -2          A18X+063546Y+152165X0120Y0150R090 S2      
317GND              VIA   -    MD0080PA00X+063546Y+152145X0160Y         S0      
327GND              U6016 -AK22M      A01X+063818Y+152220X0120Y         S1      
327GND              C391  -2          A18X+064018Y+152165X0120Y0150R090 S2      
317GND              VIA   -    MD0080PA00X+064018Y+152145X0160Y         S0      
327GND              U6016 -AC22M      A01X+064291Y+152220X0120Y         S1      
327GND              C422  -2          A18X+064491Y+152165X0120Y0150R090 S2      
317GND              VIA   -    MD0080PA00X+064491Y+152145X0160Y         S0      
327GND              U6016 -T22 M      A01X+064763Y+152220X0120Y         S1      
327GND              C382  -2          A18X+064963Y+152165X0120Y0150R090 S2      
317GND              VIA   -    MD0080PA00X+064963Y+152145X0160Y         S0      
327GND              U6016 -J22 M      A01X+065236Y+152220X0120Y         S1      
327GND              C418  -2          A18X+065438Y+152165X0120Y0150R090 S2      
317GND              VIA   -    MD0080PA00X+065438Y+152145X0160Y         S0      
327GND              U6016 -E27 M      A01X+065536Y+151863X0120Y         S1      
327GND              U6016 -E30        A01X+065536Y+151626X0120Y         S1      
327GND              U6016 -E33 M      A01X+065536Y+151390X0120Y         S1      
327GND              U6016 -H31 M      A01X+065332Y+151508X0120Y         S1      
327GND              U6016 -U34 M      A01X+064742Y+151150X0120Y         S1      
327GND              U6016 -T32 M      A01X+064763Y+151424X0150Y         S1      
317GND              VIA   -    MD0080PA00X+064524Y+151424X0160Y    R180 S0      
327GND              U6016 -AD34M      A01X+064270Y+151150X0120Y         S1      
327GND              U6016 -AC32M      A01X+064291Y+151424X0150Y         S1      
327GND              U6016 -AL34M      A01X+063798Y+151150X0120Y         S1      
327GND              U6016 -AK32M      A01X+063818Y+151424X0150Y         S1      
327GND              U6016 -AV34M      A01X+063325Y+151150X0120Y         S1      
327GND              U6016 -AU32M      A01X+063346Y+151424X0150Y         S1      
327GND              U6016 -BE34M      A01X+062853Y+151150X0120Y         S1      
327GND              U6016 -BD32M      A01X+062873Y+151424X0150Y         S1      
327GND              U6016 -BM34M      A01X+062380Y+151150X0120Y         S1      
327GND              U6016 -BL32M      A01X+062401Y+151424X0150Y         S1      
327GND              U6016 -BW34M      A01X+061908Y+151150X0120Y         S1      
327GND              U6016 -BV32M      A01X+061928Y+151424X0150Y         S1      
327GND              U6016 -CF34M      A01X+061435Y+151150X0120Y         S1      
327GND              U6016 -CE32M      A01X+061456Y+151424X0150Y         S1      
327GND              U6016 -CN34M      A01X+060963Y+151150X0120Y         S1      
327GND              U6016 -CM32M      A01X+060984Y+151424X0150Y         S1      
327GND              U6016 -CY34M      A01X+060490Y+151150X0120Y         S1      
327GND              U6016 -CW32M      A01X+060511Y+151424X0150Y         S1      
327GND              U6016 -DG34M      A01X+060018Y+151150X0120Y         S1      
327GND              U6016 -DF32M      A01X+060039Y+151424X0150Y         S1      
327GND              U6016 -DP34M      A01X+059546Y+151150X0120Y         S1      
327GND              U6016 -DN32M      A01X+059566Y+151424X0150Y         S1      
327GND              U6016 -EA34M      A01X+059073Y+151150X0120Y         S1      
327GND              U6016 -DY32M      A01X+059094Y+151424X0150Y         S1      
327GND              U6016 -EH34M      A01X+058601Y+151150X0120Y         S1      
327GND              U6016 -EG32M      A01X+058621Y+151424X0150Y         S1      
327GND              U6016 -ER34M      A01X+058128Y+151150X0120Y         S1      
327GND              U6016 -EP32M      A01X+058149Y+151424X0150Y         S1      
327GND              U6016 -FB34M      A01X+057656Y+151150X0120Y         S1      
327GND              U6016 -FA32M      A01X+057676Y+151424X0150Y         S1      
327GND              U6016 -FC28M      A01X+057578Y+151744X0120Y         S1      
327GND              U6016 -FC25M      A01X+057578Y+151981X0120Y         S1      
327GND              U6016 -FC23M      A01X+057578Y+152217X0120Y         S1      
327GND              U6016 -FJ19M      A01X+057169Y+152453X0100Y0130R090 S1      
327GND              U6016 -FF21M      A01X+057374Y+152335X0120Y         S1      
327GND              U6016 -FC19M      A01X+057578Y+152453X0120Y         S1      
327GND              U6016 -FA15M      A01X+057676Y+152788X0150Y         S1      
327GND              U6016 -FC9 M      A01X+057578Y+153162X0120Y         S1      
327GND              U6016 -FC6 M      A01X+057578Y+153398X0120Y         S1      
327GND              U6016 -FC3 M      A01X+057578Y+153634X0120Y         S1      
327GND              U6016 -ET1 M      A01X+058010Y+154048X0100Y0130     S1      
327GND              U6016 -ER2 M      A01X+058128Y+153843X0120Y         S1      
327GND              U6016 -EP4 M      A01X+058149Y+153606X0150Y         S1      
327GND              U6016 -EJ1 M      A01X+058483Y+154048X0100Y0130     S1      
327GND              U6016 -EH2 M      A01X+058601Y+153843X0120Y         S1      
327GND              U6016 -EG4 M      A01X+058621Y+153606X0150Y         S1      
327GND              U6016 -EB1 M      A01X+058955Y+154048X0100Y0130     S1      
327GND              U6016 -EA2 M      A01X+059073Y+153843X0120Y         S1      
327GND              U6016 -DY4 M      A01X+059094Y+153606X0150Y         S1      
327GND              U6016 -DR1 M      A01X+059427Y+154048X0100Y0130     S1      
327GND              U6016 -DP2 M      A01X+059546Y+153843X0120Y         S1      
327GND              U6016 -DN4 M      A01X+059566Y+153606X0150Y         S1      
317GND              VIA   -    MD0080PA00X+059771Y+153606X0160Y    R180 S0      
327GND              U6016 -DH1 M      A01X+059900Y+154048X0100Y0130     S1      
327GND              U6016 -DG2 M      A01X+060018Y+153843X0120Y         S1      
327GND              U6016 -DF4 M      A01X+060039Y+153606X0150Y         S1      
317GND              VIA   -    MD0080PA00X+060244Y+153606X0160Y    R180 S0      
327GND              U6016 -DA1 M      A01X+060372Y+154048X0100Y0130     S1      
327GND              U6016 -CY2 M      A01X+060490Y+153843X0120Y         S1      
327GND              U6016 -CW4 M      A01X+060511Y+153606X0150Y         S1      
327GND              U6016 -CP1 M      A01X+060845Y+154048X0100Y0130     S1      
327GND              U6016 -CN2 M      A01X+060963Y+153843X0120Y         S1      
327GND              U6016 -CM4 M      A01X+060984Y+153606X0150Y         S1      
317GND              VIA   -    MD0080PA00X+061189Y+153606X0160Y    R180 S0      
327GND              U6016 -CE4 M      A01X+061456Y+153606X0150Y         S1      
327GND              U6016 -BY1 M      A01X+061790Y+154048X0100Y0130     S1      
327GND              U6016 -BW2 M      A01X+061908Y+153843X0120Y         S1      
327GND              U6016 -BV4 M      A01X+061928Y+153606X0150Y         S1      
317GND              VIA   -    MD0080PA00X+062134Y+153606X0160Y    R180 S0      
327GND              U6016 -BN1 M      A01X+062262Y+154048X0100Y0130     S1      
327GND              U6016 -BM2 M      A01X+062380Y+153843X0120Y         S1      
327GND              U6016 -BL4 M      A01X+062401Y+153606X0150Y         S1      
327GND              C423  -2          A18X+062606Y+153796X0120Y0150R090 S2      
317GND              VIA   -    MD0080PA00X+062606Y+153606X0160Y    R180 S0      
327GND              U6016 -BF1 M      A01X+062734Y+154048X0100Y0130     S1      
327GND              U6016 -BE2 M      A01X+062853Y+153843X0120Y         S1      
327GND              U6016 -BD4 M      A01X+062873Y+153606X0150Y         S1      
327GND              U6016 -AW1 M      A01X+063207Y+154048X0100Y0130     S1      
327GND              U6016 -AV2 M      A01X+063325Y+153843X0120Y         S1      
327GND              U6016 -AU4 M      A01X+063346Y+153606X0150Y         S1      
317GND              VIA   -    MD0080PA00X+063551Y+153606X0160Y    R180 S0      
327GND              U6016 -AM1 M      A01X+063679Y+154048X0100Y0130     S1      
327GND              U6016 -AL2 M      A01X+063798Y+153843X0120Y         S1      
327GND              U6016 -AK4 M      A01X+063818Y+153606X0150Y         S1      
327GND              U6016 -AE1 M      A01X+064152Y+154048X0100Y0130     S1      
327GND              U6016 -AD2 M      A01X+064270Y+153843X0120Y         S1      
327GND              U6016 -AC4 M      A01X+064291Y+153606X0150Y         S1      
317GND              VIA   -    MD0080PA00X+064496Y+153606X0160Y    R180 S0      
327GND              U6010 -V1  M      A01X+126188Y+157348X0100Y0130     S1      
327GND              U6010 -U2  M      A01X+126306Y+157143X0120Y         S1      
327GND              U6010 -AM1 M      A01X+125243Y+157348X0100Y0130     S1      
327GND              U6010 -AL2 M      A01X+125361Y+157143X0120Y         S1      
327GND              U6010 -AW1 M      A01X+124771Y+157348X0100Y0130     S1      
327GND              U6010 -AV2 M      A01X+124889Y+157143X0120Y         S1      
327GND              U6010 -BF1 M      A01X+124298Y+157348X0100Y0130     S1      
327GND              U6010 -BE2 M      A01X+124416Y+157143X0120Y         S1      
327GND              U6010 -BY1 M      A01X+123353Y+157348X0100Y0130     S1      
327GND              U6010 -BW2 M      A01X+123472Y+157143X0120Y         S1      
327GND              U6010 -CG1 M      A01X+122881Y+157348X0100Y0130     S1      
327GND              U6010 -CF2 M      A01X+122999Y+157143X0120Y         S1      
327GND              U6010 -CP1 M      A01X+122409Y+157348X0100Y0130     S1      
327GND              U6010 -CN2 M      A01X+122527Y+157143X0120Y         S1      
327GND              U6010 -DH1 M      A01X+121464Y+157348X0100Y0130     S1      
327GND              U6010 -DG2 M      A01X+121582Y+157143X0120Y         S1      
327GND              U6010 -EB1 M      A01X+120519Y+157348X0100Y0130     S1      
327GND              U6010 -EA2 M      A01X+120637Y+157143X0120Y         S1      
327GND              U6010 -EJ1 M      A01X+120046Y+157348X0100Y0130     S1      
327GND              U6010 -EH2 M      A01X+120164Y+157143X0120Y         S1      
327GND              U6010 -FD1 M      A01X+119102Y+157348X0100Y0130     S1      
327GND              U6010 -FB2 M      A01X+119220Y+157143X0120Y         S1      
327GND              U6010 -FJ12M      A01X+118733Y+156226X0100Y0130R090 S1      
327GND              U6010 -FF14M      A01X+118938Y+156108X0120Y         S1      
327GND              U6010 -FJ19M      A01X+118733Y+155753X0100Y0130R090 S1      
327GND              U6010 -FF21M      A01X+118938Y+155635X0120Y         S1      
327GND              U6010 -CN34M      A01X+122527Y+154450X0120Y         S1      
327GND              U6010 -BM34M      A01X+123944Y+154450X0120Y         S1      
327GND              U6010 -AD34M      A01X+125834Y+154450X0120Y         S1      
327GND              U6010 -L35 M      A01X+126660Y+154246X0100Y0130     S1      
327GND              U6010 -K34 M      A01X+126779Y+154450X0120Y         S1      
327GND              U6010 -B19        A01X+127305Y+155753X0100Y0130R090 S1      
327GND              U6010 -H12        A01X+126896Y+156226X0120Y         S1      
327GND              U6010 -E14 M      A01X+127100Y+156108X0120Y         S1      
327GND              C580  -2          A18X+119495Y+156165X0120Y0150R270 S2      
317GND              VIA   -    MD0080PA00X+119495Y+156185X0160Y         S0      
327GND              U6010 -EP13M      A01X+119713Y+156111X0120Y         S1      
327GND              C523  -2          A18X+119968Y+156165X0120Y0150R270 S2      
317GND              VIA   -    MD0080PA00X+119968Y+156185X0160Y         S0      
327GND              U6010 -EG13M      A01X+120185Y+156111X0120Y         S1      
327GND              C543  -2          A18X+120440Y+156165X0120Y0150R270 S2      
317GND              VIA   -    MD0080PA00X+120440Y+156185X0160Y         S0      
327GND              U6010 -DY13M      A01X+120658Y+156111X0120Y         S1      
327GND              C558  -2          A18X+120913Y+156165X0120Y0150R270 S2      
317GND              VIA   -    MD0080PA00X+120913Y+156185X0160Y         S0      
327GND              U6010 -DN13M      A01X+121130Y+156111X0120Y         S1      
327GND              C538  -2          A18X+121385Y+156165X0120Y0150R270 S2      
317GND              VIA   -    MD0080PA00X+121385Y+156185X0160Y         S0      
327GND              U6010 -DF13M      A01X+121602Y+156111X0120Y         S1      
327GND              C522  -2          A18X+121858Y+156165X0120Y0150R270 S2      
317GND              VIA   -    MD0080PA00X+121858Y+156185X0160Y         S0      
327GND              U6010 -CW13M      A01X+122075Y+156111X0120Y         S1      
327GND              C512  -2          A18X+122330Y+156165X0120Y0150R270 S2      
317GND              VIA   -    MD0080PA00X+122330Y+156185X0160Y         S0      
327GND              U6010 -CM13M      A01X+122547Y+156111X0120Y         S1      
327GND              C514  -2          A18X+122802Y+156165X0120Y0150R270 S2      
317GND              VIA   -    MD0080PA00X+122802Y+156185X0160Y         S0      
327GND              U6010 -CE13M      A01X+123020Y+156111X0120Y         S1      
327GND              C519  -2          A18X+123275Y+156165X0120Y0150R270 S2      
317GND              VIA   -    MD0080PA00X+123275Y+156185X0160Y         S0      
327GND              U6010 -BV13M      A01X+123492Y+156111X0120Y         S1      
327GND              C516  -2          A18X+123747Y+156165X0120Y0150R270 S2      
317GND              VIA   -    MD0080PA00X+123747Y+156185X0160Y         S0      
327GND              U6010 -BL13M      A01X+123965Y+156111X0120Y         S1      
327GND              C524  -2          A18X+124220Y+156165X0120Y0150R270 S2      
317GND              VIA   -    MD0080PA00X+124220Y+156185X0160Y         S0      
327GND              U6010 -BD13M      A01X+124437Y+156111X0120Y         S1      
327GND              C544  -2          A18X+124692Y+156165X0120Y0150R270 S2      
317GND              VIA   -    MD0080PA00X+124692Y+156185X0160Y         S0      
327GND              U6010 -AU13M      A01X+124910Y+156111X0120Y         S1      
327GND              C583  -2          A18X+125165Y+156165X0120Y0150R270 S2      
317GND              VIA   -    MD0080PA00X+125165Y+156185X0160Y         S0      
327GND              U6010 -AK13M      A01X+125382Y+156111X0120Y         S1      
327GND              C582  -2          A18X+125637Y+156165X0120Y0150R270 S2      
317GND              VIA   -    MD0080PA00X+125637Y+156185X0160Y         S0      
327GND              U6010 -AC13M      A01X+125854Y+156111X0120Y         S1      
327GND              C541  -2          A18X+126110Y+156165X0120Y0150R270 S2      
317GND              VIA   -    MD0080PA00X+126110Y+156185X0160Y         S0      
327GND              U6010 -T13 M      A01X+126327Y+156111X0120Y         S1      
327GND              C585  -2          A18X+126582Y+156165X0120Y0150R270 S2      
317GND              VIA   -    MD0080PA00X+126582Y+156185X0160Y         S0      
327GND              U6010 -H16 M      A01X+126896Y+155989X0120Y         S1      
327GND              U6010 -H19 M      A01X+126896Y+155753X0120Y         S1      
327GND              C521  -2          A18X+119440Y+155465X0120Y0150R090 S2      
317GND              VIA   -    MD0080PA00X+119440Y+155445X0160Y         S0      
327GND              U6010 -EP22M      A01X+119713Y+155520X0120Y         S1      
317GND              VIA   -    MD0080PA00X+119913Y+155445X0160Y         S0      
327GND              C562  -2          A18X+119913Y+155465X0120Y0150R090 S2      
327GND              U6010 -EG22M      A01X+120185Y+155520X0120Y         S1      
327GND              C526  -2          A18X+120385Y+155465X0120Y0150R090 S2      
317GND              VIA   -    MD0080PA00X+120385Y+155445X0160Y         S0      
327GND              U6010 -DY22M      A01X+120658Y+155520X0120Y         S1      
327GND              C581  -2          A18X+120858Y+155465X0120Y0150R090 S2      
317GND              VIA   -    MD0080PA00X+120858Y+155445X0160Y         S0      
327GND              U6010 -DN22M      A01X+121130Y+155520X0120Y         S1      
327GND              C542  -2          A18X+121330Y+155465X0120Y0150R090 S2      
317GND              VIA   -    MD0080PA00X+121330Y+155445X0160Y         S0      
327GND              U6010 -DF22M      A01X+121602Y+155520X0120Y         S1      
327GND              C540  -2          A18X+121802Y+155465X0120Y0150R090 S2      
317GND              VIA   -    MD0080PA00X+121802Y+155445X0160Y         S0      
327GND              U6010 -CW22M      A01X+122075Y+155520X0120Y         S1      
327GND              C520  -2          A18X+122275Y+155465X0120Y0150R090 S2      
317GND              VIA   -    MD0080PA00X+122275Y+155445X0160Y         S0      
327GND              U6010 -CM22M      A01X+122547Y+155520X0120Y         S1      
327GND              C517  -2          A18X+122747Y+155465X0120Y0150R090 S2      
317GND              VIA   -    MD0080PA00X+122747Y+155445X0160Y         S0      
327GND              U6010 -CE22M      A01X+123020Y+155520X0120Y         S1      
327GND              C515  -2          A18X+123220Y+155465X0120Y0150R090 S2      
317GND              VIA   -    MD0080PA00X+123220Y+155445X0160Y         S0      
327GND              U6010 -BV22M      A01X+123492Y+155520X0120Y         S1      
327GND              C513  -2          A18X+123692Y+155465X0120Y0150R090 S2      
317GND              VIA   -    MD0080PA00X+123692Y+155445X0160Y         S0      
327GND              U6010 -BL22M      A01X+123965Y+155520X0120Y         S1      
327GND              C578  -2          A18X+124165Y+155465X0120Y0150R090 S2      
317GND              VIA   -    MD0080PA00X+124165Y+155445X0160Y         S0      
327GND              U6010 -BD22M      A01X+124437Y+155520X0120Y         S1      
327GND              C545  -2          A18X+124637Y+155465X0120Y0150R090 S2      
317GND              VIA   -    MD0080PA00X+124637Y+155445X0160Y         S0      
327GND              U6010 -AU22M      A01X+124910Y+155520X0120Y         S1      
327GND              C529  -2          A18X+125110Y+155465X0120Y0150R090 S2      
317GND              VIA   -    MD0080PA00X+125110Y+155445X0160Y         S0      
327GND              U6010 -AK22M      A01X+125382Y+155520X0120Y         S1      
327GND              C570  -2          A18X+125582Y+155465X0120Y0150R090 S2      
317GND              VIA   -    MD0080PA00X+125582Y+155445X0160Y         S0      
327GND              U6010 -AC22M      A01X+125854Y+155520X0120Y         S1      
327GND              C573  -2          A18X+126054Y+155465X0120Y0150R090 S2      
317GND              VIA   -    MD0080PA00X+126054Y+155445X0160Y         S0      
327GND              U6010 -T22 M      A01X+126327Y+155520X0120Y         S1      
327GND              C525  -2          A18X+126527Y+155465X0120Y0150R090 S2      
317GND              VIA   -    MD0080PA00X+126527Y+155445X0160Y         S0      
327GND              U6010 -J22 M      A01X+126799Y+155520X0120Y         S1      
327GND              C577  -2          A18X+127001Y+155465X0120Y0150R090 S2      
317GND              VIA   -    MD0080PA00X+127001Y+155445X0160Y         S0      
327GND              U6010 -E27 M      A01X+127100Y+155163X0120Y         S1      
327GND              U6010 -E30        A01X+127100Y+154926X0120Y         S1      
327GND              U6010 -E33 M      A01X+127100Y+154690X0120Y         S1      
327GND              U6010 -H31 M      A01X+126896Y+154808X0120Y         S1      
327GND              U6010 -U34 M      A01X+126306Y+154450X0120Y         S1      
327GND              U6010 -T32 M      A01X+126327Y+154724X0150Y         S1      
317GND              VIA   -    MD0080PA00X+126088Y+154724X0160Y    R180 S0      
327GND              U6010 -AC32M      A01X+125854Y+154724X0150Y         S1      
327GND              U6010 -AL34M      A01X+125361Y+154450X0120Y         S1      
327GND              U6010 -AK32M      A01X+125382Y+154724X0150Y         S1      
327GND              U6010 -AV34M      A01X+124889Y+154450X0120Y         S1      
327GND              U6010 -AU32M      A01X+124910Y+154724X0150Y         S1      
327GND              U6010 -BE34M      A01X+124416Y+154450X0120Y         S1      
327GND              U6010 -BD32M      A01X+124437Y+154724X0150Y         S1      
327GND              U6010 -BL32M      A01X+123965Y+154724X0150Y         S1      
327GND              U6010 -BW34M      A01X+123472Y+154450X0120Y         S1      
327GND              U6010 -BV32M      A01X+123492Y+154724X0150Y         S1      
327GND              U6010 -CF34M      A01X+122999Y+154450X0120Y         S1      
327GND              U6010 -CE32M      A01X+123020Y+154724X0150Y         S1      
327GND              U6010 -CM32M      A01X+122547Y+154724X0150Y         S1      
327GND              U6010 -CY34M      A01X+122054Y+154450X0120Y         S1      
327GND              U6010 -CW32M      A01X+122075Y+154724X0150Y         S1      
327GND              U6010 -DG34M      A01X+121582Y+154450X0120Y         S1      
327GND              U6010 -DF32M      A01X+121602Y+154724X0150Y         S1      
327GND              U6010 -DP34M      A01X+121109Y+154450X0120Y         S1      
327GND              U6010 -DN32M      A01X+121130Y+154724X0150Y         S1      
327GND              U6010 -EA34M      A01X+120637Y+154450X0120Y         S1      
327GND              U6010 -DY32M      A01X+120658Y+154724X0150Y         S1      
327GND              U6010 -EH34M      A01X+120164Y+154450X0120Y         S1      
327GND              U6010 -EG32M      A01X+120185Y+154724X0150Y         S1      
327GND              U6010 -ER34M      A01X+119692Y+154450X0120Y         S1      
327GND              U6010 -EP32M      A01X+119713Y+154724X0150Y         S1      
327GND              U6010 -FB34M      A01X+119220Y+154450X0120Y         S1      
327GND              U6010 -FA32M      A01X+119240Y+154724X0150Y         S1      
327GND              U6010 -FC28M      A01X+119142Y+155044X0120Y         S1      
327GND              U6010 -FC25M      A01X+119142Y+155281X0120Y         S1      
327GND              U6010 -FC23M      A01X+119142Y+155517X0120Y         S1      
327GND              U6010 -FC19M      A01X+119142Y+155753X0120Y         S1      
327GND              U6010 -FA15M      A01X+119240Y+156088X0150Y         S1      
327GND              U6010 -FC9 M      A01X+119142Y+156462X0120Y         S1      
327GND              U6010 -FC6 M      A01X+119142Y+156698X0120Y         S1      
327GND              U6010 -FC3 M      A01X+119142Y+156934X0120Y         S1      
327GND              U6010 -ET1 M      A01X+119574Y+157348X0100Y0130     S1      
327GND              U6010 -ER2 M      A01X+119692Y+157143X0120Y         S1      
327GND              U6010 -EP4 M      A01X+119713Y+156906X0150Y         S1      
327GND              U6010 -EG4 M      A01X+120185Y+156906X0150Y         S1      
327GND              U6010 -DY4 M      A01X+120658Y+156906X0150Y         S1      
327GND              U6010 -DR1 M      A01X+120991Y+157348X0100Y0130     S1      
327GND              U6010 -DP2 M      A01X+121109Y+157143X0120Y         S1      
327GND              U6010 -DN4 M      A01X+121130Y+156906X0150Y         S1      
317GND              VIA   -    MD0080PA00X+121335Y+156906X0160Y    R180 S0      
327GND              U6010 -DF4 M      A01X+121602Y+156906X0150Y         S1      
317GND              VIA   -    MD0080PA00X+121808Y+156906X0160Y    R180 S0      
327GND              U6010 -DA1 M      A01X+121936Y+157348X0100Y0130     S1      
327GND              U6010 -CY2 M      A01X+122054Y+157143X0120Y         S1      
327GND              U6010 -CW4 M      A01X+122075Y+156906X0150Y         S1      
327GND              U6010 -CM4 M      A01X+122547Y+156906X0150Y         S1      
317GND              VIA   -    MD0080PA00X+122752Y+156906X0160Y    R180 S0      
327GND              U6010 -CE4 M      A01X+123020Y+156906X0150Y         S1      
327GND              U6010 -BV4 M      A01X+123492Y+156906X0150Y         S1      
317GND              VIA   -    MD0080PA00X+123697Y+156906X0160Y    R180 S0      
327GND              U6010 -BN1 M      A01X+123826Y+157348X0100Y0130     S1      
327GND              U6010 -BM2 M      A01X+123944Y+157143X0120Y         S1      
327GND              U6010 -BL4 M      A01X+123965Y+156906X0150Y         S1      
327GND              C528  -2          A18X+124170Y+157096X0120Y0150R090 S2      
317GND              VIA   -    MD0080PA00X+124170Y+156906X0160Y    R180 S0      
327GND              U6010 -BD4 M      A01X+124437Y+156906X0150Y         S1      
327GND              U6010 -AU4 M      A01X+124910Y+156906X0150Y         S1      
317GND              VIA   -    MD0080PA00X+125115Y+156906X0160Y    R180 S0      
327GND              U6010 -AK4 M      A01X+125382Y+156906X0150Y         S1      
327GND              U6010 -AE1 M      A01X+125716Y+157348X0100Y0130     S1      
327GND              U6010 -AD2 M      A01X+125834Y+157143X0120Y         S1      
327GND              U6010 -AC4 M      A01X+125854Y+156906X0150Y         S1      
317GND              VIA   -    MD0080PA00X+126060Y+156906X0160Y    R180 S0      
327GND              U6010 -T4  M      A01X+126327Y+156906X0150Y         S1      
327GND              U6010 -L1  M      A01X+126660Y+157348X0100Y0130     S1      
327GND              U6010 -K2  M      A01X+126779Y+157143X0120Y         S1      
327GND              U6010 -J4  M      A01X+126799Y+156906X0150Y         S1      
327GND              U6011 -L1  M      A01X+139467Y+157348X0100Y0130     S1      
327GND              U6011 -K2  M      A01X+139585Y+157143X0120Y         S1      
327GND              U6011 -J4  M      A01X+139606Y+156906X0150Y         S1      
327GND              U6011 -V1  M      A01X+138994Y+157348X0100Y0130     S1      
327GND              U6011 -U2  M      A01X+139112Y+157143X0120Y         S1      
327GND              U6011 -T4  M      A01X+139133Y+156906X0150Y         S1      
327GND              U6011 -CG1 M      A01X+135687Y+157348X0100Y0130     S1      
327GND              U6011 -CF2 M      A01X+135805Y+157143X0120Y         S1      
327GND              U6011 -FD1 M      A01X+131908Y+157348X0100Y0130     S1      
327GND              U6011 -FB2 M      A01X+132026Y+157143X0120Y         S1      
327GND              U6011 -FJ12M      A01X+131539Y+156226X0100Y0130R090 S1      
327GND              U6011 -FF14M      A01X+131744Y+156108X0120Y         S1      
327GND              U6011 -L35 M      A01X+139467Y+154246X0100Y0130     S1      
327GND              U6011 -K34 M      A01X+139585Y+154450X0120Y         S1      
327GND              U6011 -B19        A01X+140111Y+155753X0100Y0130R090 S1      
327GND              U6011 -H12        A01X+139702Y+156226X0120Y         S1      
327GND              U6011 -E14 M      A01X+139906Y+156108X0120Y         S1      
327GND              C657  -2          A18X+132302Y+156165X0120Y0150R270 S2      
317GND              VIA   -    MD0080PA00X+132302Y+156185X0160Y         S0      
327GND              U6011 -EP13M      A01X+132519Y+156111X0120Y         S1      
327GND              C650  -2          A18X+132774Y+156165X0120Y0150R270 S2      
317GND              VIA   -    MD0080PA00X+132774Y+156185X0160Y         S0      
327GND              U6011 -EG13M      A01X+132991Y+156111X0120Y         S1      
327GND              C635  -2          A18X+133246Y+156165X0120Y0150R270 S2      
317GND              VIA   -    MD0080PA00X+133246Y+156185X0160Y         S0      
327GND              U6011 -DY13M      A01X+133464Y+156111X0120Y         S1      
327GND              C662  -2          A18X+133719Y+156165X0120Y0150R270 S2      
317GND              VIA   -    MD0080PA00X+133719Y+156185X0160Y         S0      
327GND              U6011 -DN13M      A01X+133936Y+156111X0120Y         S1      
327GND              C617  -2          A18X+134191Y+156165X0120Y0150R270 S2      
317GND              VIA   -    MD0080PA00X+134191Y+156185X0160Y         S0      
327GND              U6011 -DF13M      A01X+134409Y+156111X0120Y         S1      
327GND              C608  -2          A18X+134664Y+156165X0120Y0150R270 S2      
317GND              VIA   -    MD0080PA00X+134664Y+156185X0160Y         S0      
327GND              U6011 -CW13M      A01X+134881Y+156111X0120Y         S1      
327GND              C597  -2          A18X+135136Y+156165X0120Y0150R270 S2      
317GND              VIA   -    MD0080PA00X+135136Y+156185X0160Y         S0      
327GND              U6011 -CM13M      A01X+135354Y+156111X0120Y         S1      
327GND              C599  -2          A18X+135609Y+156165X0120Y0150R270 S2      
317GND              VIA   -    MD0080PA00X+135609Y+156185X0160Y         S0      
327GND              U6011 -CE13M      A01X+135826Y+156111X0120Y         S1      
327GND              C606  -2          A18X+136081Y+156165X0120Y0150R270 S2      
317GND              VIA   -    MD0080PA00X+136081Y+156185X0160Y         S0      
327GND              U6011 -BV13M      A01X+136298Y+156111X0120Y         S1      
327GND              C601  -2          A18X+136554Y+156165X0120Y0150R270 S2      
317GND              VIA   -    MD0080PA00X+136554Y+156185X0160Y         S0      
327GND              U6011 -BL13M      A01X+136771Y+156111X0120Y         S1      
327GND              C615  -2          A18X+137026Y+156165X0120Y0150R270 S2      
317GND              VIA   -    MD0080PA00X+137026Y+156185X0160Y         S0      
327GND              U6011 -BD13M      A01X+137243Y+156111X0120Y         S1      
327GND              C623  -2          A18X+137498Y+156165X0120Y0150R270 S2      
317GND              VIA   -    MD0080PA00X+137498Y+156185X0160Y         S0      
327GND              U6011 -AU13M      A01X+137716Y+156111X0120Y         S1      
327GND              C627  -2          A18X+137971Y+156165X0120Y0150R270 S2      
317GND              VIA   -    MD0080PA00X+137971Y+156185X0160Y         S0      
327GND              U6011 -AK13M      A01X+138188Y+156111X0120Y         S1      
327GND              C659  -2          A18X+138443Y+156165X0120Y0150R270 S2      
317GND              VIA   -    MD0080PA00X+138443Y+156185X0160Y         S0      
327GND              U6011 -AC13M      A01X+138661Y+156111X0120Y         S1      
327GND              C631  -2          A18X+138916Y+156165X0120Y0150R270 S2      
317GND              VIA   -    MD0080PA00X+138916Y+156185X0160Y         S0      
327GND              U6011 -T13 M      A01X+139133Y+156111X0120Y         S1      
327GND              C614  -2          A18X+139388Y+156165X0120Y0150R270 S2      
317GND              VIA   -    MD0080PA00X+139388Y+156185X0160Y         S0      
327GND              U6011 -H16 M      A01X+139702Y+155989X0120Y         S1      
327GND              U6011 -H19 M      A01X+139702Y+155753X0120Y         S1      
327GND              C660  -2          A18X+132246Y+155465X0120Y0150R090 S2      
317GND              VIA   -    MD0080PA00X+132246Y+155445X0160Y         S0      
327GND              U6011 -EP22M      A01X+132519Y+155520X0120Y         S1      
327GND              C647  -2          A18X+132719Y+155465X0120Y0150R090 S2      
317GND              VIA   -    MD0080PA00X+132719Y+155445X0160Y         S0      
327GND              U6011 -EG22M      A01X+132991Y+155520X0120Y         S1      
327GND              C654  -2          A18X+133191Y+155465X0120Y0150R090 S2      
317GND              VIA   -    MD0080PA00X+133191Y+155445X0160Y         S0      
327GND              U6011 -DY22M      A01X+133464Y+155520X0120Y         S1      
327GND              C607  -2          A18X+133664Y+155465X0120Y0150R090 S2      
317GND              VIA   -    MD0080PA00X+133664Y+155445X0160Y         S0      
327GND              U6011 -DN22M      A01X+133936Y+155520X0120Y         S1      
327GND              C621  -2          A18X+134136Y+155465X0120Y0150R090 S2      
317GND              VIA   -    MD0080PA00X+134136Y+155445X0160Y         S0      
327GND              U6011 -DF22M      A01X+134409Y+155520X0120Y         S1      
327GND              C610  -2          A18X+134609Y+155465X0120Y0150R090 S2      
317GND              VIA   -    MD0080PA00X+134609Y+155445X0160Y         S0      
327GND              U6011 -CW22M      A01X+134881Y+155520X0120Y         S1      
327GND              C600  -2          A18X+135081Y+155465X0120Y0150R090 S2      
317GND              VIA   -    MD0080PA00X+135081Y+155445X0160Y         S0      
327GND              U6011 -CM22M      A01X+135354Y+155520X0120Y         S1      
327GND              C603  -2          A18X+135554Y+155465X0120Y0150R090 S2      
317GND              VIA   -    MD0080PA00X+135554Y+155445X0160Y         S0      
327GND              U6011 -CE22M      A01X+135826Y+155520X0120Y         S1      
327GND              C602  -2          A18X+136026Y+155465X0120Y0150R090 S2      
317GND              VIA   -    MD0080PA00X+136026Y+155445X0160Y         S0      
327GND              U6011 -BV22M      A01X+136298Y+155520X0120Y         S1      
327GND              C598  -2          A18X+136498Y+155465X0120Y0150R090 S2      
317GND              VIA   -    MD0080PA00X+136498Y+155445X0160Y         S0      
327GND              U6011 -BL22M      A01X+136771Y+155520X0120Y         S1      
327GND              C619  -2          A18X+136971Y+155465X0120Y0150R090 S2      
317GND              VIA   -    MD0080PA00X+136971Y+155445X0160Y         S0      
327GND              U6011 -BD22M      A01X+137243Y+155520X0120Y         S1      
327GND              C624  -2          A18X+137443Y+155465X0120Y0150R090 S2      
317GND              VIA   -    MD0080PA00X+137443Y+155445X0160Y         S0      
327GND              U6011 -AU22M      A01X+137716Y+155520X0120Y         S1      
327GND              C618  -2          A18X+137916Y+155465X0120Y0150R090 S2      
317GND              VIA   -    MD0080PA00X+137916Y+155445X0160Y         S0      
327GND              U6011 -AK22M      A01X+138188Y+155520X0120Y         S1      
327GND              C613  -2          A18X+138388Y+155465X0120Y0150R090 S2      
317GND              VIA   -    MD0080PA00X+138388Y+155445X0160Y         S0      
327GND              U6011 -AC22M      A01X+138661Y+155520X0120Y         S1      
327GND              C643  -2          A18X+138861Y+155465X0120Y0150R090 S2      
317GND              VIA   -    MD0080PA00X+138861Y+155445X0160Y         S0      
327GND              U6011 -T22 M      A01X+139133Y+155520X0120Y         S1      
327GND              C609  -2          A18X+139333Y+155465X0120Y0150R090 S2      
317GND              VIA   -    MD0080PA00X+139333Y+155445X0160Y         S0      
327GND              U6011 -J22 M      A01X+139606Y+155520X0120Y         S1      
327GND              C653  -2          A18X+139808Y+155465X0120Y0150R090 S2      
317GND              VIA   -    MD0080PA00X+139808Y+155445X0160Y         S0      
327GND              U6011 -E27 M      A01X+139906Y+155163X0120Y         S1      
327GND              U6011 -E30        A01X+139906Y+154926X0120Y         S1      
327GND              U6011 -E33 M      A01X+139906Y+154690X0120Y         S1      
327GND              U6011 -H31 M      A01X+139702Y+154808X0120Y         S1      
327GND              U6011 -U34 M      A01X+139112Y+154450X0120Y         S1      
327GND              U6011 -T32 M      A01X+139133Y+154724X0150Y         S1      
317GND              VIA   -    MD0080PA00X+138894Y+154724X0160Y    R180 S0      
327GND              U6011 -AD34M      A01X+138640Y+154450X0120Y         S1      
327GND              U6011 -AC32M      A01X+138661Y+154724X0150Y         S1      
327GND              U6011 -AL34M      A01X+138168Y+154450X0120Y         S1      
327GND              U6011 -AK32M      A01X+138188Y+154724X0150Y         S1      
327GND              U6011 -AV34M      A01X+137695Y+154450X0120Y         S1      
327GND              U6011 -AU32M      A01X+137716Y+154724X0150Y         S1      
327GND              U6011 -BE34M      A01X+137223Y+154450X0120Y         S1      
327GND              U6011 -BD32M      A01X+137243Y+154724X0150Y         S1      
327GND              U6011 -BM34M      A01X+136750Y+154450X0120Y         S1      
327GND              U6011 -BL32M      A01X+136771Y+154724X0150Y         S1      
327GND              U6011 -BW34M      A01X+136278Y+154450X0120Y         S1      
327GND              U6011 -BV32M      A01X+136298Y+154724X0150Y         S1      
327GND              U6011 -CF34M      A01X+135805Y+154450X0120Y         S1      
327GND              U6011 -CE32M      A01X+135826Y+154724X0150Y         S1      
327GND              U6011 -CN34M      A01X+135333Y+154450X0120Y         S1      
327GND              U6011 -CM32M      A01X+135354Y+154724X0150Y         S1      
327GND              U6011 -CY34M      A01X+134860Y+154450X0120Y         S1      
327GND              U6011 -CW32M      A01X+134881Y+154724X0150Y         S1      
327GND              U6011 -DG34M      A01X+134388Y+154450X0120Y         S1      
327GND              U6011 -DF32M      A01X+134409Y+154724X0150Y         S1      
327GND              U6011 -DP34M      A01X+133916Y+154450X0120Y         S1      
327GND              U6011 -DN32M      A01X+133936Y+154724X0150Y         S1      
327GND              U6011 -EA34M      A01X+133443Y+154450X0120Y         S1      
327GND              U6011 -DY32M      A01X+133464Y+154724X0150Y         S1      
327GND              U6011 -EH34M      A01X+132971Y+154450X0120Y         S1      
327GND              U6011 -EG32M      A01X+132991Y+154724X0150Y         S1      
327GND              U6011 -ER34M      A01X+132498Y+154450X0120Y         S1      
327GND              U6011 -EP32M      A01X+132519Y+154724X0150Y         S1      
327GND              U6011 -FB34M      A01X+132026Y+154450X0120Y         S1      
327GND              U6011 -FA32M      A01X+132046Y+154724X0150Y         S1      
327GND              U6011 -FC28M      A01X+131948Y+155044X0120Y         S1      
327GND              U6011 -FC25M      A01X+131948Y+155281X0120Y         S1      
327GND              U6011 -FC23M      A01X+131948Y+155517X0120Y         S1      
327GND              U6011 -FJ19M      A01X+131539Y+155753X0100Y0130R090 S1      
327GND              U6011 -FF21M      A01X+131744Y+155635X0120Y         S1      
327GND              U6011 -FC19M      A01X+131948Y+155753X0120Y         S1      
327GND              U6011 -FA15M      A01X+132046Y+156088X0150Y         S1      
327GND              U6011 -FC9 M      A01X+131948Y+156462X0120Y         S1      
327GND              U6011 -FC6 M      A01X+131948Y+156698X0120Y         S1      
327GND              U6011 -FC3 M      A01X+131948Y+156934X0120Y         S1      
327GND              U6011 -ET1 M      A01X+132380Y+157348X0100Y0130     S1      
327GND              U6011 -ER2 M      A01X+132498Y+157143X0120Y         S1      
327GND              U6011 -EP4 M      A01X+132519Y+156906X0150Y         S1      
327GND              U6011 -EJ1 M      A01X+132853Y+157348X0100Y0130     S1      
327GND              U6011 -EH2 M      A01X+132971Y+157143X0120Y         S1      
327GND              U6011 -EG4 M      A01X+132991Y+156906X0150Y         S1      
327GND              U6011 -EB1 M      A01X+133325Y+157348X0100Y0130     S1      
327GND              U6011 -EA2 M      A01X+133443Y+157143X0120Y         S1      
327GND              U6011 -DY4 M      A01X+133464Y+156906X0150Y         S1      
327GND              U6011 -DR1 M      A01X+133797Y+157348X0100Y0130     S1      
327GND              U6011 -DP2 M      A01X+133916Y+157143X0120Y         S1      
327GND              U6011 -DN4 M      A01X+133936Y+156906X0150Y         S1      
317GND              VIA   -    MD0080PA00X+134141Y+156906X0160Y    R180 S0      
327GND              U6011 -DH1 M      A01X+134270Y+157348X0100Y0130     S1      
327GND              U6011 -DG2 M      A01X+134388Y+157143X0120Y         S1      
327GND              U6011 -DF4 M      A01X+134409Y+156906X0150Y         S1      
317GND              VIA   -    MD0080PA00X+134614Y+156906X0160Y    R180 S0      
327GND              U6011 -DA1 M      A01X+134742Y+157348X0100Y0130     S1      
327GND              U6011 -CY2 M      A01X+134860Y+157143X0120Y         S1      
327GND              U6011 -CW4 M      A01X+134881Y+156906X0150Y         S1      
327GND              U6011 -CP1 M      A01X+135215Y+157348X0100Y0130     S1      
327GND              U6011 -CN2 M      A01X+135333Y+157143X0120Y         S1      
327GND              U6011 -CM4 M      A01X+135354Y+156906X0150Y         S1      
317GND              VIA   -    MD0080PA00X+135559Y+156906X0160Y    R180 S0      
327GND              U6011 -CE4 M      A01X+135826Y+156906X0150Y         S1      
327GND              U6011 -BY1 M      A01X+136160Y+157348X0100Y0130     S1      
327GND              U6011 -BW2 M      A01X+136278Y+157143X0120Y         S1      
327GND              U6011 -BV4 M      A01X+136298Y+156906X0150Y         S1      
317GND              VIA   -    MD0080PA00X+136504Y+156906X0160Y    R180 S0      
327GND              U6011 -BN1 M      A01X+136632Y+157348X0100Y0130     S1      
327GND              U6011 -BM2 M      A01X+136750Y+157143X0120Y         S1      
327GND              U6011 -BL4 M      A01X+136771Y+156906X0150Y         S1      
327GND              C655  -2          A18X+136976Y+157096X0120Y0150R090 S2      
317GND              VIA   -    MD0080PA00X+136976Y+156906X0160Y    R180 S0      
327GND              U6011 -BF1 M      A01X+137104Y+157348X0100Y0130     S1      
327GND              U6011 -BE2 M      A01X+137223Y+157143X0120Y         S1      
327GND              U6011 -BD4 M      A01X+137243Y+156906X0150Y         S1      
327GND              U6011 -AW1 M      A01X+137577Y+157348X0100Y0130     S1      
327GND              U6011 -AV2 M      A01X+137695Y+157143X0120Y         S1      
327GND              U6011 -AU4 M      A01X+137716Y+156906X0150Y         S1      
317GND              VIA   -    MD0080PA00X+137921Y+156906X0160Y    R180 S0      
327GND              U6011 -AM1 M      A01X+138049Y+157348X0100Y0130     S1      
327GND              U6011 -AL2 M      A01X+138168Y+157143X0120Y         S1      
327GND              U6011 -AK4 M      A01X+138188Y+156906X0150Y         S1      
327GND              U6011 -AE1 M      A01X+138522Y+157348X0100Y0130     S1      
327GND              U6011 -AD2 M      A01X+138640Y+157143X0120Y         S1      
327GND              U6011 -AC4 M      A01X+138661Y+156906X0150Y         S1      
317GND              VIA   -    MD0080PA00X+138866Y+156906X0160Y    R180 S0      
327GND              U6013 -V1  M      A01X+152606Y+157348X0100Y0130     S1      
327GND              U6013 -U2  M      A01X+152724Y+157143X0120Y         S1      
327GND              U6013 -AM1 M      A01X+151661Y+157348X0100Y0130     S1      
327GND              U6013 -AL2 M      A01X+151779Y+157143X0120Y         S1      
327GND              U6013 -AW1 M      A01X+151188Y+157348X0100Y0130     S1      
327GND              U6013 -AV2 M      A01X+151306Y+157143X0120Y         S1      
327GND              U6013 -BF1 M      A01X+150716Y+157348X0100Y0130     S1      
327GND              U6013 -BE2 M      A01X+150834Y+157143X0120Y         S1      
327GND              U6013 -BY1 M      A01X+149771Y+157348X0100Y0130     S1      
327GND              U6013 -BW2 M      A01X+149889Y+157143X0120Y         S1      
327GND              U6013 -CG1 M      A01X+149298Y+157348X0100Y0130     S1      
327GND              U6013 -CF2 M      A01X+149416Y+157143X0120Y         S1      
327GND              U6013 -CP1 M      A01X+148826Y+157348X0100Y0130     S1      
327GND              U6013 -CN2 M      A01X+148944Y+157143X0120Y         S1      
327GND              U6013 -DH1 M      A01X+147881Y+157348X0100Y0130     S1      
327GND              U6013 -DG2 M      A01X+147999Y+157143X0120Y         S1      
327GND              U6013 -EB1 M      A01X+146936Y+157348X0100Y0130     S1      
327GND              U6013 -EA2 M      A01X+147054Y+157143X0120Y         S1      
327GND              U6013 -EJ1 M      A01X+146464Y+157348X0100Y0130     S1      
327GND              U6013 -EH2 M      A01X+146582Y+157143X0120Y         S1      
327GND              U6013 -FD1 M      A01X+145519Y+157348X0100Y0130     S1      
327GND              U6013 -FB2 M      A01X+145637Y+157143X0120Y         S1      
327GND              U6013 -FJ12M      A01X+145150Y+156226X0100Y0130R090 S1      
327GND              U6013 -FF14M      A01X+145355Y+156108X0120Y         S1      
327GND              U6013 -FJ19M      A01X+145150Y+155753X0100Y0130R090 S1      
327GND              U6013 -FF21M      A01X+145355Y+155635X0120Y         S1      
327GND              U6013 -CN34M      A01X+148944Y+154450X0120Y         S1      
327GND              U6013 -BM34M      A01X+150361Y+154450X0120Y         S1      
327GND              U6013 -AD34M      A01X+152251Y+154450X0120Y         S1      
327GND              U6013 -L35 M      A01X+153078Y+154246X0100Y0130     S1      
327GND              U6013 -K34 M      A01X+153196Y+154450X0120Y         S1      
327GND              U6013 -B19        A01X+153722Y+155753X0100Y0130R090 S1      
327GND              U6013 -H12        A01X+153313Y+156226X0120Y         S1      
327GND              U6013 -E14 M      A01X+153518Y+156108X0120Y         S1      
327GND              C1052 -2          A18X+145913Y+156165X0120Y0150R270 S2      
317GND              VIA   -    MD0080PA00X+145913Y+156185X0160Y         S0      
327GND              U6013 -EP13M      A01X+146130Y+156111X0120Y         S1      
327GND              C1008 -2          A18X+146385Y+156165X0120Y0150R270 S2      
317GND              VIA   -    MD0080PA00X+146385Y+156185X0160Y         S0      
327GND              U6013 -EG13M      A01X+146603Y+156111X0120Y         S1      
327GND              C1011 -2          A18X+146858Y+156165X0120Y0150R270 S2      
317GND              VIA   -    MD0080PA00X+146858Y+156185X0160Y         S0      
327GND              U6013 -DY13M      A01X+147075Y+156111X0120Y         S1      
327GND              C1035 -2          A18X+147330Y+156165X0120Y0150R270 S2      
317GND              VIA   -    MD0080PA00X+147330Y+156185X0160Y         S0      
327GND              U6013 -DN13M      A01X+147548Y+156111X0120Y         S1      
327GND              C1021 -2          A18X+147802Y+156165X0120Y0150R270 S2      
317GND              VIA   -    MD0080PA00X+147802Y+156185X0160Y         S0      
327GND              U6013 -DF13M      A01X+148020Y+156111X0120Y         S1      
327GND              C1009 -2          A18X+148275Y+156165X0120Y0150R270 S2      
317GND              VIA   -    MD0080PA00X+148275Y+156185X0160Y         S0      
327GND              U6013 -CW13M      A01X+148492Y+156111X0120Y         S1      
327GND              C1000 -2          A18X+148747Y+156165X0120Y0150R270 S2      
317GND              VIA   -    MD0080PA00X+148747Y+156185X0160Y         S0      
327GND              U6013 -CM13M      A01X+148965Y+156111X0120Y         S1      
327GND              C998  -2          A18X+149220Y+156165X0120Y0150R270 S2      
317GND              VIA   -    MD0080PA00X+149220Y+156185X0160Y         S0      
327GND              U6013 -CE13M      A01X+149437Y+156111X0120Y         S1      
327GND              C1005 -2          A18X+149692Y+156165X0120Y0150R270 S2      
317GND              VIA   -    MD0080PA00X+149692Y+156185X0160Y         S0      
327GND              U6013 -BV13M      A01X+149910Y+156111X0120Y         S1      
327GND              C1002 -2          A18X+150165Y+156165X0120Y0150R270 S2      
317GND              VIA   -    MD0080PA00X+150165Y+156185X0160Y         S0      
327GND              U6013 -BL13M      A01X+150382Y+156111X0120Y         S1      
327GND              C1012 -2          A18X+150637Y+156165X0120Y0150R270 S2      
317GND              VIA   -    MD0080PA00X+150637Y+156185X0160Y         S0      
327GND              U6013 -BD13M      A01X+150854Y+156111X0120Y         S1      
327GND              C1014 -2          A18X+151110Y+156165X0120Y0150R270 S2      
317GND              VIA   -    MD0080PA00X+151110Y+156185X0160Y         S0      
327GND              U6013 -AU13M      A01X+151327Y+156111X0120Y         S1      
327GND              C1055 -2          A18X+151582Y+156165X0120Y0150R270 S2      
317GND              VIA   -    MD0080PA00X+151582Y+156185X0160Y         S0      
327GND              U6013 -AK13M      A01X+151799Y+156111X0120Y         S1      
327GND              C1051 -2          A18X+152054Y+156165X0120Y0150R270 S2      
317GND              VIA   -    MD0080PA00X+152054Y+156185X0160Y         S0      
327GND              U6013 -AC13M      A01X+152272Y+156111X0120Y         S1      
327GND              C1010 -2          A18X+152527Y+156165X0120Y0150R270 S2      
317GND              VIA   -    MD0080PA00X+152527Y+156185X0160Y         S0      
327GND              U6013 -T13 M      A01X+152744Y+156111X0120Y         S1      
327GND              C1043 -2          A18X+152999Y+156165X0120Y0150R270 S2      
317GND              VIA   -    MD0080PA00X+152999Y+156185X0160Y         S0      
327GND              U6013 -H16 M      A01X+153313Y+155989X0120Y         S1      
327GND              U6013 -H19 M      A01X+153313Y+155753X0120Y         S1      
327GND              C1017 -2          A18X+145858Y+155465X0120Y0150R090 S2      
317GND              VIA   -    MD0080PA00X+145858Y+155445X0160Y         S0      
327GND              U6013 -EP22M      A01X+146130Y+155520X0120Y         S1      
317GND              VIA   -    MD0080PA00X+146330Y+155445X0160Y         S0      
327GND              C1031 -2          A18X+146330Y+155465X0120Y0150R090 S2      
327GND              U6013 -EG22M      A01X+146603Y+155520X0120Y         S1      
327GND              C1013 -2          A18X+146803Y+155465X0120Y0150R090 S2      
317GND              VIA   -    MD0080PA00X+146803Y+155445X0160Y         S0      
327GND              U6013 -DY22M      A01X+147075Y+155520X0120Y         S1      
327GND              C1024 -2          A18X+147275Y+155465X0120Y0150R090 S2      
317GND              VIA   -    MD0080PA00X+147275Y+155445X0160Y         S0      
327GND              U6013 -DN22M      A01X+147548Y+155520X0120Y         S1      
327GND              C1020 -2          A18X+147747Y+155465X0120Y0150R090 S2      
317GND              VIA   -    MD0080PA00X+147747Y+155445X0160Y         S0      
327GND              U6013 -DF22M      A01X+148020Y+155520X0120Y         S1      
327GND              C1007 -2          A18X+148220Y+155465X0120Y0150R090 S2      
317GND              VIA   -    MD0080PA00X+148220Y+155445X0160Y         S0      
327GND              U6013 -CW22M      A01X+148492Y+155520X0120Y         S1      
327GND              C1001 -2          A18X+148692Y+155465X0120Y0150R090 S2      
317GND              VIA   -    MD0080PA00X+148692Y+155445X0160Y         S0      
327GND              U6013 -CM22M      A01X+148965Y+155520X0120Y         S1      
327GND              C1004 -2          A18X+149165Y+155465X0120Y0150R090 S2      
317GND              VIA   -    MD0080PA00X+149165Y+155445X0160Y         S0      
327GND              U6013 -CE22M      A01X+149437Y+155520X0120Y         S1      
327GND              C1003 -2          A18X+149637Y+155465X0120Y0150R090 S2      
317GND              VIA   -    MD0080PA00X+149637Y+155445X0160Y         S0      
327GND              U6013 -BV22M      A01X+149910Y+155520X0120Y         S1      
327GND              C999  -2          A18X+150110Y+155465X0120Y0150R090 S2      
317GND              VIA   -    MD0080PA00X+150110Y+155445X0160Y         S0      
327GND              U6013 -BL22M      A01X+150382Y+155520X0120Y         S1      
327GND              C1048 -2          A18X+150582Y+155465X0120Y0150R090 S2      
317GND              VIA   -    MD0080PA00X+150582Y+155445X0160Y         S0      
327GND              U6013 -BD22M      A01X+150854Y+155520X0120Y         S1      
327GND              C1018 -2          A18X+151054Y+155465X0120Y0150R090 S2      
317GND              VIA   -    MD0080PA00X+151054Y+155445X0160Y         S0      
327GND              U6013 -AU22M      A01X+151327Y+155520X0120Y         S1      
327GND              C1015 -2          A18X+151527Y+155465X0120Y0150R090 S2      
317GND              VIA   -    MD0080PA00X+151527Y+155445X0160Y         S0      
327GND              U6013 -AK22M      A01X+151799Y+155520X0120Y         S1      
327GND              C1039 -2          A18X+151999Y+155465X0120Y0150R090 S2      
317GND              VIA   -    MD0080PA00X+151999Y+155445X0160Y         S0      
327GND              U6013 -AC22M      A01X+152272Y+155520X0120Y         S1      
327GND              C1027 -2          A18X+152472Y+155465X0120Y0150R090 S2      
317GND              VIA   -    MD0080PA00X+152472Y+155445X0160Y         S0      
327GND              U6013 -T22 M      A01X+152744Y+155520X0120Y         S1      
327GND              C1019 -2          A18X+152944Y+155465X0120Y0150R090 S2      
317GND              VIA   -    MD0080PA00X+152944Y+155445X0160Y         S0      
327GND              U6013 -J22 M      A01X+153217Y+155520X0120Y         S1      
327GND              C1046 -2          A18X+153419Y+155465X0120Y0150R090 S2      
317GND              VIA   -    MD0080PA00X+153419Y+155445X0160Y         S0      
327GND              U6013 -E27 M      A01X+153518Y+155163X0120Y         S1      
327GND              U6013 -E30        A01X+153518Y+154926X0120Y         S1      
327GND              U6013 -E33 M      A01X+153518Y+154690X0120Y         S1      
327GND              U6013 -H31 M      A01X+153313Y+154808X0120Y         S1      
327GND              U6013 -U34 M      A01X+152724Y+154450X0120Y         S1      
327GND              U6013 -T32 M      A01X+152744Y+154724X0150Y         S1      
317GND              VIA   -    MD0080PA00X+152505Y+154724X0160Y    R180 S0      
327GND              U6013 -AC32M      A01X+152272Y+154724X0150Y         S1      
327GND              U6013 -AL34M      A01X+151779Y+154450X0120Y         S1      
327GND              U6013 -AK32M      A01X+151799Y+154724X0150Y         S1      
327GND              U6013 -AV34M      A01X+151306Y+154450X0120Y         S1      
327GND              U6013 -AU32M      A01X+151327Y+154724X0150Y         S1      
327GND              U6013 -BE34M      A01X+150834Y+154450X0120Y         S1      
327GND              U6013 -BD32M      A01X+150854Y+154724X0150Y         S1      
327GND              U6013 -BL32M      A01X+150382Y+154724X0150Y         S1      
327GND              U6013 -BW34M      A01X+149889Y+154450X0120Y         S1      
327GND              U6013 -BV32M      A01X+149910Y+154724X0150Y         S1      
327GND              U6013 -CF34M      A01X+149416Y+154450X0120Y         S1      
327GND              U6013 -CE32M      A01X+149437Y+154724X0150Y         S1      
327GND              U6013 -CM32M      A01X+148965Y+154724X0150Y         S1      
327GND              U6013 -CY34M      A01X+148472Y+154450X0120Y         S1      
327GND              U6013 -CW32M      A01X+148492Y+154724X0150Y         S1      
327GND              U6013 -DG34M      A01X+147999Y+154450X0120Y         S1      
327GND              U6013 -DF32M      A01X+148020Y+154724X0150Y         S1      
327GND              U6013 -DP34M      A01X+147527Y+154450X0120Y         S1      
327GND              U6013 -DN32M      A01X+147548Y+154724X0150Y         S1      
327GND              U6013 -EA34M      A01X+147054Y+154450X0120Y         S1      
327GND              U6013 -DY32M      A01X+147075Y+154724X0150Y         S1      
327GND              U6013 -EH34M      A01X+146582Y+154450X0120Y         S1      
327GND              U6013 -EG32M      A01X+146603Y+154724X0150Y         S1      
327GND              U6013 -ER34M      A01X+146109Y+154450X0120Y         S1      
327GND              U6013 -EP32M      A01X+146130Y+154724X0150Y         S1      
327GND              U6013 -FB34M      A01X+145637Y+154450X0120Y         S1      
327GND              U6013 -FA32M      A01X+145658Y+154724X0150Y         S1      
327GND              U6013 -FC28M      A01X+145560Y+155044X0120Y         S1      
327GND              U6013 -FC25M      A01X+145560Y+155281X0120Y         S1      
327GND              U6013 -FC23M      A01X+145560Y+155517X0120Y         S1      
327GND              U6013 -FC19M      A01X+145560Y+155753X0120Y         S1      
327GND              U6013 -FA15M      A01X+145658Y+156088X0150Y         S1      
327GND              U6013 -FC9 M      A01X+145560Y+156462X0120Y         S1      
327GND              U6013 -FC6 M      A01X+145560Y+156698X0120Y         S1      
327GND              U6013 -FC3 M      A01X+145560Y+156934X0120Y         S1      
327GND              U6013 -ET1 M      A01X+145991Y+157348X0100Y0130     S1      
327GND              U6013 -ER2 M      A01X+146109Y+157143X0120Y         S1      
327GND              U6013 -EP4 M      A01X+146130Y+156906X0150Y         S1      
327GND              U6013 -EG4 M      A01X+146603Y+156906X0150Y         S1      
327GND              U6013 -DY4 M      A01X+147075Y+156906X0150Y         S1      
327GND              U6013 -DR1 M      A01X+147409Y+157348X0100Y0130     S1      
327GND              U6013 -DP2 M      A01X+147527Y+157143X0120Y         S1      
327GND              U6013 -DN4 M      A01X+147548Y+156906X0150Y         S1      
317GND              VIA   -    MD0080PA00X+147752Y+156906X0160Y    R180 S0      
327GND              U6013 -DF4 M      A01X+148020Y+156906X0150Y         S1      
317GND              VIA   -    MD0080PA00X+148225Y+156906X0160Y    R180 S0      
327GND              U6013 -DA1 M      A01X+148354Y+157348X0100Y0130     S1      
327GND              U6013 -CY2 M      A01X+148472Y+157143X0120Y         S1      
327GND              U6013 -CW4 M      A01X+148492Y+156906X0150Y         S1      
327GND              U6013 -CM4 M      A01X+148965Y+156906X0150Y         S1      
317GND              VIA   -    MD0080PA00X+149170Y+156906X0160Y    R180 S0      
327GND              U6013 -CE4 M      A01X+149437Y+156906X0150Y         S1      
327GND              U6013 -BV4 M      A01X+149910Y+156906X0150Y         S1      
317GND              VIA   -    MD0080PA00X+150115Y+156906X0160Y    R180 S0      
327GND              U6013 -BN1 M      A01X+150243Y+157348X0100Y0130     S1      
327GND              U6013 -BM2 M      A01X+150361Y+157143X0120Y         S1      
327GND              U6013 -BL4 M      A01X+150382Y+156906X0150Y         S1      
327GND              C1016 -2          A18X+150587Y+157096X0120Y0150R090 S2      
317GND              VIA   -    MD0080PA00X+150587Y+156906X0160Y    R180 S0      
327GND              U6013 -BD4 M      A01X+150854Y+156906X0150Y         S1      
327GND              U6013 -AU4 M      A01X+151327Y+156906X0150Y         S1      
317GND              VIA   -    MD0080PA00X+151532Y+156906X0160Y    R180 S0      
327GND              U6013 -AK4 M      A01X+151799Y+156906X0150Y         S1      
327GND              U6013 -AE1 M      A01X+152133Y+157348X0100Y0130     S1      
327GND              U6013 -AD2 M      A01X+152251Y+157143X0120Y         S1      
327GND              U6013 -AC4 M      A01X+152272Y+156906X0150Y         S1      
317GND              VIA   -    MD0080PA00X+152477Y+156906X0160Y    R180 S0      
327GND              U6013 -T4  M      A01X+152744Y+156906X0150Y         S1      
327GND              U6013 -L1  M      A01X+153078Y+157348X0100Y0130     S1      
327GND              U6013 -K2  M      A01X+153196Y+157143X0120Y         S1      
327GND              U6013 -J4  M      A01X+153217Y+156906X0150Y         S1      
327GND              U6012 -L1  M      A01X+165884Y+157348X0100Y0130     S1      
327GND              U6012 -K2  M      A01X+166002Y+157143X0120Y         S1      
327GND              U6012 -J4  M      A01X+166023Y+156906X0150Y         S1      
327GND              U6012 -V1  M      A01X+165412Y+157348X0100Y0130     S1      
327GND              U6012 -U2  M      A01X+165530Y+157143X0120Y         S1      
327GND              U6012 -T4  M      A01X+165550Y+156906X0150Y         S1      
327GND              U6012 -CG1 M      A01X+162105Y+157348X0100Y0130     S1      
327GND              U6012 -CF2 M      A01X+162223Y+157143X0120Y         S1      
327GND              U6012 -FD1 M      A01X+158325Y+157348X0100Y0130     S1      
327GND              U6012 -FB2 M      A01X+158443Y+157143X0120Y         S1      
327GND              U6012 -FJ12M      A01X+157957Y+156226X0100Y0130R090 S1      
327GND              U6012 -FF14M      A01X+158161Y+156108X0120Y         S1      
327GND              U6012 -L35 M      A01X+165884Y+154246X0100Y0130     S1      
327GND              U6012 -K34 M      A01X+166002Y+154450X0120Y         S1      
327GND              U6012 -B19        A01X+166528Y+155753X0100Y0130R090 S1      
327GND              U6012 -H12        A01X+166119Y+156226X0120Y         S1      
327GND              U6012 -E14 M      A01X+166324Y+156108X0120Y         S1      
327GND              C968  -2          A18X+158719Y+156165X0120Y0150R270 S2      
317GND              VIA   -    MD0080PA00X+158719Y+156185X0160Y         S0      
327GND              U6012 -EP13M      A01X+158936Y+156111X0120Y         S1      
327GND              C800  -2          A18X+159191Y+156165X0120Y0150R270 S2      
317GND              VIA   -    MD0080PA00X+159191Y+156185X0160Y         S0      
327GND              U6012 -EG13M      A01X+159409Y+156111X0120Y         S1      
327GND              C972  -2          A18X+159664Y+156165X0120Y0150R270 S2      
317GND              VIA   -    MD0080PA00X+159664Y+156185X0160Y         S0      
327GND              U6012 -DY13M      A01X+159881Y+156111X0120Y         S1      
327GND              C985  -2          A18X+160136Y+156165X0120Y0150R270 S2      
317GND              VIA   -    MD0080PA00X+160136Y+156185X0160Y         S0      
327GND              U6012 -DN13M      A01X+160354Y+156111X0120Y         S1      
327GND              C791  -2          A18X+160609Y+156165X0120Y0150R270 S2      
317GND              VIA   -    MD0080PA00X+160609Y+156185X0160Y         S0      
327GND              U6012 -DF13M      A01X+160826Y+156111X0120Y         S1      
327GND              C782  -2          A18X+161081Y+156165X0120Y0150R270 S2      
317GND              VIA   -    MD0080PA00X+161081Y+156185X0160Y         S0      
327GND              U6012 -CW13M      A01X+161298Y+156111X0120Y         S1      
327GND              C677  -2          A18X+161554Y+156165X0120Y0150R270 S2      
317GND              VIA   -    MD0080PA00X+161554Y+156185X0160Y         S0      
327GND              U6012 -CM13M      A01X+161771Y+156111X0120Y         S1      
327GND              C673  -2          A18X+162026Y+156165X0120Y0150R270 S2      
317GND              VIA   -    MD0080PA00X+162026Y+156185X0160Y         S0      
327GND              U6012 -CE13M      A01X+162243Y+156111X0120Y         S1      
327GND              C776  -2          A18X+162498Y+156165X0120Y0150R270 S2      
317GND              VIA   -    MD0080PA00X+162498Y+156185X0160Y         S0      
327GND              U6012 -BV13M      A01X+162716Y+156111X0120Y         S1      
327GND              C775  -2          A18X+162971Y+156165X0120Y0150R270 S2      
317GND              VIA   -    MD0080PA00X+162971Y+156185X0160Y         S0      
327GND              U6012 -BL13M      A01X+163188Y+156111X0120Y         S1      
327GND              C785  -2          A18X+163443Y+156165X0120Y0150R270 S2      
317GND              VIA   -    MD0080PA00X+163443Y+156185X0160Y         S0      
327GND              U6012 -BD13M      A01X+163661Y+156111X0120Y         S1      
327GND              C794  -2          A18X+163916Y+156165X0120Y0150R270 S2      
317GND              VIA   -    MD0080PA00X+163916Y+156185X0160Y         S0      
327GND              U6012 -AU13M      A01X+164133Y+156111X0120Y         S1      
327GND              C982  -2          A18X+164388Y+156165X0120Y0150R270 S2      
317GND              VIA   -    MD0080PA00X+164388Y+156185X0160Y         S0      
327GND              U6012 -AK13M      A01X+164606Y+156111X0120Y         S1      
327GND              C804  -2          A18X+164861Y+156165X0120Y0150R270 S2      
317GND              VIA   -    MD0080PA00X+164861Y+156185X0160Y         S0      
327GND              U6012 -AC13M      A01X+165078Y+156111X0120Y         S1      
327GND              C984  -2          A18X+165333Y+156165X0120Y0150R270 S2      
317GND              VIA   -    MD0080PA00X+165333Y+156185X0160Y         S0      
327GND              U6012 -T13 M      A01X+165550Y+156111X0120Y         S1      
327GND              C790  -2          A18X+165806Y+156165X0120Y0150R270 S2      
317GND              VIA   -    MD0080PA00X+165806Y+156185X0160Y         S0      
327GND              U6012 -H16 M      A01X+166119Y+155989X0120Y         S1      
327GND              U6012 -H19 M      A01X+166119Y+155753X0120Y         S1      
327GND              C983  -2          A18X+158664Y+155465X0120Y0150R090 S2      
317GND              VIA   -    MD0080PA00X+158664Y+155445X0160Y         S0      
327GND              U6012 -EP22M      A01X+158936Y+155520X0120Y         S1      
327GND              C797  -2          A18X+159136Y+155465X0120Y0150R090 S2      
317GND              VIA   -    MD0080PA00X+159136Y+155445X0160Y         S0      
327GND              U6012 -EG22M      A01X+159409Y+155520X0120Y         S1      
327GND              C978  -2          A18X+159609Y+155465X0120Y0150R090 S2      
317GND              VIA   -    MD0080PA00X+159609Y+155445X0160Y         S0      
327GND              U6012 -DY22M      A01X+159881Y+155520X0120Y         S1      
327GND              C783  -2          A18X+160081Y+155465X0120Y0150R090 S2      
317GND              VIA   -    MD0080PA00X+160081Y+155445X0160Y         S0      
327GND              U6012 -DN22M      A01X+160354Y+155520X0120Y         S1      
327GND              C787  -2          A18X+160554Y+155465X0120Y0150R090 S2      
317GND              VIA   -    MD0080PA00X+160554Y+155445X0160Y         S0      
327GND              U6012 -DF22M      A01X+160826Y+155520X0120Y         S1      
327GND              C780  -2          A18X+161026Y+155465X0120Y0150R090 S2      
317GND              VIA   -    MD0080PA00X+161026Y+155445X0160Y         S0      
327GND              U6012 -CW22M      A01X+161298Y+155520X0120Y         S1      
327GND              C778  -2          A18X+161498Y+155465X0120Y0150R090 S2      
317GND              VIA   -    MD0080PA00X+161498Y+155445X0160Y         S0      
327GND              U6012 -CM22M      A01X+161771Y+155520X0120Y         S1      
327GND              C774  -2          A18X+161971Y+155465X0120Y0150R090 S2      
317GND              VIA   -    MD0080PA00X+161971Y+155445X0160Y         S0      
327GND              U6012 -CE22M      A01X+162243Y+155520X0120Y         S1      
327GND              C777  -2          A18X+162443Y+155465X0120Y0150R090 S2      
317GND              VIA   -    MD0080PA00X+162443Y+155445X0160Y         S0      
327GND              U6012 -BV22M      A01X+162716Y+155520X0120Y         S1      
327GND              C676  -2          A18X+162916Y+155465X0120Y0150R090 S2      
317GND              VIA   -    MD0080PA00X+162916Y+155445X0160Y         S0      
327GND              U6012 -BL22M      A01X+163188Y+155520X0120Y         S1      
327GND              C789  -2          A18X+163388Y+155465X0120Y0150R090 S2      
317GND              VIA   -    MD0080PA00X+163388Y+155445X0160Y         S0      
327GND              U6012 -BD22M      A01X+163661Y+155520X0120Y         S1      
327GND              C793  -2          A18X+163861Y+155465X0120Y0150R090 S2      
317GND              VIA   -    MD0080PA00X+163861Y+155445X0160Y         S0      
327GND              U6012 -AU22M      A01X+164133Y+155520X0120Y         S1      
327GND              C792  -2          A18X+164333Y+155465X0120Y0150R090 S2      
317GND              VIA   -    MD0080PA00X+164333Y+155445X0160Y         S0      
327GND              U6012 -AK22M      A01X+164606Y+155520X0120Y         S1      
327GND              C788  -2          A18X+164806Y+155465X0120Y0150R090 S2      
317GND              VIA   -    MD0080PA00X+164806Y+155445X0160Y         S0      
327GND              U6012 -AC22M      A01X+165078Y+155520X0120Y         S1      
327GND              C975  -2          A18X+165278Y+155465X0120Y0150R090 S2      
317GND              VIA   -    MD0080PA00X+165278Y+155445X0160Y         S0      
327GND              U6012 -T22 M      A01X+165550Y+155520X0120Y         S1      
327GND              C786  -2          A18X+165750Y+155465X0120Y0150R090 S2      
317GND              VIA   -    MD0080PA00X+165750Y+155445X0160Y         S0      
327GND              U6012 -J22 M      A01X+166023Y+155520X0120Y         S1      
327GND              C979  -2          A18X+166225Y+155465X0120Y0150R090 S2      
317GND              VIA   -    MD0080PA00X+166225Y+155445X0160Y         S0      
327GND              U6012 -E27 M      A01X+166324Y+155163X0120Y         S1      
327GND              U6012 -E30        A01X+166324Y+154926X0120Y         S1      
327GND              U6012 -E33 M      A01X+166324Y+154690X0120Y         S1      
327GND              U6012 -H31 M      A01X+166119Y+154808X0120Y         S1      
327GND              U6012 -U34 M      A01X+165530Y+154450X0120Y         S1      
327GND              U6012 -T32 M      A01X+165550Y+154724X0150Y         S1      
317GND              VIA   -    MD0080PA00X+165311Y+154724X0160Y    R180 S0      
327GND              U6012 -AD34M      A01X+165057Y+154450X0120Y         S1      
327GND              U6012 -AC32M      A01X+165078Y+154724X0150Y         S1      
327GND              U6012 -AL34M      A01X+164585Y+154450X0120Y         S1      
327GND              U6012 -AK32M      A01X+164606Y+154724X0150Y         S1      
327GND              U6012 -AV34M      A01X+164112Y+154450X0120Y         S1      
327GND              U6012 -AU32M      A01X+164133Y+154724X0150Y         S1      
327GND              U6012 -BE34M      A01X+163640Y+154450X0120Y         S1      
327GND              U6012 -BD32M      A01X+163661Y+154724X0150Y         S1      
327GND              U6012 -BM34M      A01X+163168Y+154450X0120Y         S1      
327GND              U6012 -BL32M      A01X+163188Y+154724X0150Y         S1      
327GND              U6012 -BW34M      A01X+162695Y+154450X0120Y         S1      
327GND              U6012 -BV32M      A01X+162716Y+154724X0150Y         S1      
327GND              U6012 -CF34M      A01X+162223Y+154450X0120Y         S1      
327GND              U6012 -CE32M      A01X+162243Y+154724X0150Y         S1      
327GND              U6012 -CN34M      A01X+161750Y+154450X0120Y         S1      
327GND              U6012 -CM32M      A01X+161771Y+154724X0150Y         S1      
327GND              U6012 -CY34M      A01X+161278Y+154450X0120Y         S1      
327GND              U6012 -CW32M      A01X+161298Y+154724X0150Y         S1      
327GND              U6012 -DG34M      A01X+160805Y+154450X0120Y         S1      
327GND              U6012 -DF32M      A01X+160826Y+154724X0150Y         S1      
327GND              U6012 -DP34M      A01X+160333Y+154450X0120Y         S1      
327GND              U6012 -DN32M      A01X+160354Y+154724X0150Y         S1      
327GND              U6012 -EA34M      A01X+159860Y+154450X0120Y         S1      
327GND              U6012 -DY32M      A01X+159881Y+154724X0150Y         S1      
327GND              U6012 -EH34M      A01X+159388Y+154450X0120Y         S1      
327GND              U6012 -EG32M      A01X+159409Y+154724X0150Y         S1      
327GND              U6012 -ER34M      A01X+158916Y+154450X0120Y         S1      
327GND              U6012 -EP32M      A01X+158936Y+154724X0150Y         S1      
327GND              U6012 -FB34M      A01X+158443Y+154450X0120Y         S1      
327GND              U6012 -FA32M      A01X+158464Y+154724X0150Y         S1      
327GND              U6012 -FC28M      A01X+158366Y+155044X0120Y         S1      
327GND              U6012 -FC25M      A01X+158366Y+155281X0120Y         S1      
327GND              U6012 -FC23M      A01X+158366Y+155517X0120Y         S1      
327GND              U6012 -FJ19M      A01X+157957Y+155753X0100Y0130R090 S1      
327GND              U6012 -FF21M      A01X+158161Y+155635X0120Y         S1      
327GND              U6012 -FC19M      A01X+158366Y+155753X0120Y         S1      
327GND              U6012 -FA15M      A01X+158464Y+156088X0150Y         S1      
327GND              U6012 -FC9 M      A01X+158366Y+156462X0120Y         S1      
327GND              U6012 -FC6 M      A01X+158366Y+156698X0120Y         S1      
327GND              U6012 -FC3 M      A01X+158366Y+156934X0120Y         S1      
327GND              U6012 -ET1 M      A01X+158798Y+157348X0100Y0130     S1      
327GND              U6012 -ER2 M      A01X+158916Y+157143X0120Y         S1      
327GND              U6012 -EP4 M      A01X+158936Y+156906X0150Y         S1      
327GND              U6012 -EJ1 M      A01X+159270Y+157348X0100Y0130     S1      
327GND              U6012 -EH2 M      A01X+159388Y+157143X0120Y         S1      
327GND              U6012 -EG4 M      A01X+159409Y+156906X0150Y         S1      
327GND              U6012 -EB1 M      A01X+159742Y+157348X0100Y0130     S1      
327GND              U6012 -EA2 M      A01X+159860Y+157143X0120Y         S1      
327GND              U6012 -DY4 M      A01X+159881Y+156906X0150Y         S1      
327GND              U6012 -DR1 M      A01X+160215Y+157348X0100Y0130     S1      
327GND              U6012 -DP2 M      A01X+160333Y+157143X0120Y         S1      
327GND              U6012 -DN4 M      A01X+160354Y+156906X0150Y         S1      
317GND              VIA   -    MD0080PA00X+160559Y+156906X0160Y    R180 S0      
327GND              U6012 -DH1 M      A01X+160687Y+157348X0100Y0130     S1      
327GND              U6012 -DG2 M      A01X+160805Y+157143X0120Y         S1      
327GND              U6012 -DF4 M      A01X+160826Y+156906X0150Y         S1      
317GND              VIA   -    MD0080PA00X+161031Y+156906X0160Y    R180 S0      
327GND              U6012 -DA1 M      A01X+161160Y+157348X0100Y0130     S1      
327GND              U6012 -CY2 M      A01X+161278Y+157143X0120Y         S1      
327GND              U6012 -CW4 M      A01X+161298Y+156906X0150Y         S1      
327GND              U6012 -CP1 M      A01X+161632Y+157348X0100Y0130     S1      
327GND              U6012 -CN2 M      A01X+161750Y+157143X0120Y         S1      
327GND              U6012 -CM4 M      A01X+161771Y+156906X0150Y         S1      
317GND              VIA   -    MD0080PA00X+161976Y+156906X0160Y    R180 S0      
327GND              U6012 -CE4 M      A01X+162243Y+156906X0150Y         S1      
327GND              U6012 -BY1 M      A01X+162577Y+157348X0100Y0130     S1      
327GND              U6012 -BW2 M      A01X+162695Y+157143X0120Y         S1      
327GND              U6012 -BV4 M      A01X+162716Y+156906X0150Y         S1      
317GND              VIA   -    MD0080PA00X+162921Y+156906X0160Y    R180 S0      
327GND              U6012 -BN1 M      A01X+163050Y+157348X0100Y0130     S1      
327GND              U6012 -BM2 M      A01X+163168Y+157143X0120Y         S1      
327GND              U6012 -BL4 M      A01X+163188Y+156906X0150Y         S1      
327GND              C980  -2          A18X+163393Y+157096X0120Y0150R090 S2      
317GND              VIA   -    MD0080PA00X+163393Y+156906X0160Y    R180 S0      
327GND              U6012 -BF1 M      A01X+163522Y+157348X0100Y0130     S1      
327GND              U6012 -BE2 M      A01X+163640Y+157143X0120Y         S1      
327GND              U6012 -BD4 M      A01X+163661Y+156906X0150Y         S1      
327GND              U6012 -AW1 M      A01X+163994Y+157348X0100Y0130     S1      
327GND              U6012 -AV2 M      A01X+164112Y+157143X0120Y         S1      
327GND              U6012 -AU4 M      A01X+164133Y+156906X0150Y         S1      
317GND              VIA   -    MD0080PA00X+164338Y+156906X0160Y    R180 S0      
327GND              U6012 -AM1 M      A01X+164467Y+157348X0100Y0130     S1      
327GND              U6012 -AL2 M      A01X+164585Y+157143X0120Y         S1      
327GND              U6012 -AK4 M      A01X+164606Y+156906X0150Y         S1      
327GND              U6012 -AE1 M      A01X+164939Y+157348X0100Y0130     S1      
327GND              U6012 -AD2 M      A01X+165057Y+157143X0120Y         S1      
327GND              U6012 -AC4 M      A01X+165078Y+156906X0150Y         S1      
317GND              VIA   -    MD0080PA00X+165283Y+156906X0160Y    R180 S0      
317GND              VIA   -    MD0100PA00X+005064Y+155745X0200Y    R090 S0      
317GND              VIA   -    MD0100PA00X+006130Y+158000X0200Y         S0      
317GND              VIA   -    MD0100PA00X+005860Y+158000X0200Y         S0      
317GND              VIA   -    MD0100PA00X+006399Y+156473X0200Y    R090 S0      
317GND              VIA   -    MD0100PA00X+006399Y+156763X0200Y    R090 S0      
317GND              VIA   -    MD0100PA00X+006399Y+157043X0200Y    R090 S0      
317GND              VIA   -    MD0100PA00X+006399Y+156218X0200Y    R090 S0      
317GND              VIA   -    MD0100PA00X+006380Y+158000X0200Y         S0      
317GND              VIA   -    MD0100PA00X+007881Y+152284X0200Y         S0      
327GND              PU6512-7_9-M      A01X+010095Y+152639X0827Y2126R090 S1      
317GND              VIA   -    MD0100PA00X+009302Y+152329X0193Y         S0      
317GND              VIA   -    MD0100PA00X+008870Y+152377X0200Y         S0      
317GND              VIA   -    MD0100PA00X+008890Y+151384X0200Y         S0      
317GND              VIA   -    MD0100PA00X+008887Y+151128X0200Y         S0      
317GND              VIA   -    MD0100PA00X+008540Y+151384X0200Y         S0      
317GND              VIA   -    MD0100PA00X+008537Y+151128X0200Y         S0      
317GND              VIA   -    MD0100PA00X+008140Y+152284X0200Y         S0      
317GND              VIA   -    MD0100PA00X+008140Y+151984X0200Y         S0      
317GND              VIA   -    MD0100PA00X+008190Y+151384X0200Y         S0      
317GND              VIA   -    MD0100PA00X+008140Y+151684X0200Y         S0      
317GND              VIA   -    MD0100PA00X+008187Y+151128X0200Y         S0      
317GND              VIA   -    MD0100PA00X+009302Y+152639X0193Y         S0      
317GND              VIA   -    MD0100PA00X+008870Y+152677X0200Y         S0      
317GND              VIA   -    MD0100PA00X+008270Y+152910X0200Y         S0      
317GND              VIA   -    MD0100PA00X+009502Y+153875X0193Y         S0      
327GND              PU6512-40  M      A01X+009750Y+153594X0690Y0770     S1      
317GND              VIA   -    MD0100PA00X+009502Y+153315X0193Y         S0      
317GND              VIA   -    MD0100PA00X+008297Y+155205X0200Y    R090 S0      
317GND              VIA   -    MD0100PA00X+008562Y+155197X0200Y    R090 S0      
317GND              VIA   -    MD0100PA00X+010351Y+152310X0193Y         S0      
317GND              VIA   -    MD0100PA00X+010671Y+152310X0193Y         S0      
317GND              VIA   -    MD0100PA00X+010964Y+152316X0193Y         S0      
317GND              VIA   -    MD0100PA00X+010092Y+152329X0193Y         S0      
317GND              VIA   -    MD0100PA00X+009562Y+152329X0193Y         S0      
317GND              VIA   -    MD0100PA00X+009849Y+152329X0193Y         S0      
317GND              VIA   -    MD0100PA00X+010102Y+152950X0193Y         S0      
317GND              VIA   -    MD0100PA00X+010092Y+152639X0193Y         S0      
317GND              VIA   -    MD0100PA00X+009562Y+152639X0193Y         S0      
317GND              VIA   -    MD0100PA00X+009842Y+152950X0193Y         S0      
317GND              VIA   -    MD0100PA00X+009849Y+152639X0193Y         S0      
317GND              VIA   -    MD0100PA00X+009750Y+153875X0193Y         S0      
317GND              VIA   -    MD0100PA00X+009750Y+153315X0193Y         S0      
317GND              VIA   -    MD0100PA00X+009998Y+153875X0193Y         S0      
317GND              VIA   -    MD0100PA00X+009998Y+153315X0193Y         S0      
317GND              VIA   -    MD0100PA00X+010140Y+155277X0200Y         S0      
317GND              VIA   -    MD0100PA00X+010210Y+155544X0200Y    R090 S0      
317GND              VIA   -    MD0100PA00X+011690Y+150934X0200Y         S0      
317GND              VIA   -    MD0100PA00X+011690Y+151634X0200Y         S0      
317GND              VIA   -    MD0100PA00X+011690Y+151284X0200Y         S0      
317GND              VIA   -    MD0100PA00X+011690Y+151984X0200Y         S0      
317GND              VIA   -    MD0100PA00X+011690Y+152284X0200Y         S0      
317GND              VIA   -    MD0100PA00X+011440Y+152284X0200Y         S0      
317GND              VIA   -    MD0100PA00X+011440Y+151984X0200Y         S0      
317GND              VIA   -    MD0100PA00X+011440Y+151284X0200Y         S0      
317GND              VIA   -    MD0100PA00X+011440Y+151634X0200Y         S0      
317GND              VIA   -    MD0100PA00X+011440Y+150934X0193Y         S0      
317GND              VIA   -    MD0100PA00X+011690Y+152634X0200Y         S0      
327GND              PU6511-7_9-M      A01X+006520Y+152639X0827Y2126R090 S1      
317GND              VIA   -    MD0100PA00X+006348Y+152329X0193Y         S0      
317GND              VIA   -    MD0100PA00X+005988Y+152329X0193Y         S0      
317GND              VIA   -    MD0100PA00X+006608Y+152329X0193Y         S0      
317GND              VIA   -    MD0100PA00X+005728Y+152329X0193Y         S0      
317GND              VIA   -    MD0100PA00X+005290Y+152334X0200Y         S0      
327GND              PU6511-40  M      A01X+006176Y+153594X0690Y0770     S1      
317GND              VIA   -    MD0100PA00X+005928Y+153875X0193Y         S0      
317GND              VIA   -    MD0100PA00X+006176Y+153875X0193Y         S0      
317GND              VIA   -    MD0100PA00X+006424Y+153875X0193Y         S0      
317GND              VIA   -    MD0100PA00X+005928Y+153315X0193Y         S0      
317GND              VIA   -    MD0100PA00X+006176Y+153315X0193Y         S0      
317GND              VIA   -    MD0100PA00X+006424Y+153315X0193Y         S0      
317GND              VIA   -    MD0100PA00X+006268Y+152950X0193Y         S0      
317GND              VIA   -    MD0100PA00X+006348Y+152639X0193Y         S0      
317GND              VIA   -    MD0100PA00X+005988Y+152639X0193Y         S0      
317GND              VIA   -    MD0100PA00X+006528Y+152950X0193Y         S0      
317GND              VIA   -    MD0100PA00X+006608Y+152639X0193Y         S0      
317GND              VIA   -    MD0100PA00X+005728Y+152639X0193Y         S0      
317GND              VIA   -    MD0100PA00X+005280Y+152647X0200Y         S0      
317GND              VIA   -    MD0100PA00X+007136Y+152319X0193Y         S0      
317GND              VIA   -    MD0100PA00X+006887Y+152315X0193Y         S0      
317GND              VIA   -    MD0100PA00X+007432Y+152330X0193Y         S0      
317GND              VIA   -    MD0100PA00X+007446Y+152966X0193Y         S0      
317GND              VIA   -    MD0100PA00X+007444Y+152638X0193Y         S0      
317GND              VIA   -    MD0100PA00X+006720Y+155287X0200Y         S0      
317GND              VIA   -    MD0100PA00X+004940Y+151484X0200Y         S0      
317GND              VIA   -    MD0100PA00X+005590Y+151484X0200Y         S0      
317GND              VIA   -    MD0100PA00X+005576Y+151188X0200Y         S0      
317GND              VIA   -    MD0100PA00X+005240Y+151484X0200Y         S0      
317GND              VIA   -    MD0100PA00X+004709Y+151027X0200Y    R090 S0      
317GND              VIA   -    MD0100PA00X+004714Y+151307X0200Y    R090 S0      
317GND              VIA   -    MD0100PA00X+003767Y+151521X0200Y    R090 S0      
317GND              VIA   -    MD0100PA00X+003382Y+145608X0200Y    R090 S0      
317GND              VIA   -    MD0100PA00X+003382Y+146508X0200Y    R090 S0      
317GND              VIA   -    MD0100PA00X+003382Y+145908X0200Y    R090 S0      
317GND              VIA   -    MD0100PA00X+003382Y+146208X0200Y    R090 S0      
317GND              VIA   -    MD0100PA00X+004282Y+145608X0200Y    R090 S0      
317GND              VIA   -    MD0100PA00X+004282Y+146508X0200Y    R090 S0      
317GND              VIA   -    MD0100PA00X+004282Y+145908X0200Y    R090 S0      
317GND              VIA   -    MD0100PA00X+004282Y+146208X0200Y    R090 S0      
317GND              VIA   -    MD0100PA00X+005782Y+145608X0200Y    R090 S0      
317GND              VIA   -    MD0100PA00X+005782Y+146508X0200Y    R090 S0      
317GND              VIA   -    MD0100PA00X+005782Y+145908X0200Y    R090 S0      
317GND              VIA   -    MD0100PA00X+005782Y+146208X0200Y    R090 S0      
317GND              VIA   -    MD0100PA00X+006682Y+145608X0200Y    R090 S0      
317GND              VIA   -    MD0100PA00X+006682Y+146508X0200Y    R090 S0      
317GND              VIA   -    MD0100PA00X+006682Y+145908X0200Y    R090 S0      
317GND              VIA   -    MD0100PA00X+006682Y+146208X0200Y    R090 S0      
317GND              VIA   -    MD0100PA00X+008572Y+145608X0200Y    R090 S0      
317GND              VIA   -    MD0100PA00X+008872Y+145608X0200Y    R090 S0      
317GND              VIA   -    MD0100PA00X+008182Y+145608X0200Y    R090 S0      
317GND              VIA   -    MD0100PA00X+008572Y+146208X0200Y    R090 S0      
317GND              VIA   -    MD0100PA00X+008572Y+146508X0200Y    R090 S0      
317GND              VIA   -    MD0100PA00X+008872Y+146508X0200Y    R090 S0      
317GND              VIA   -    MD0100PA00X+008872Y+146208X0200Y    R090 S0      
317GND              VIA   -    MD0100PA00X+008182Y+146508X0200Y    R090 S0      
317GND              VIA   -    MD0100PA00X+008182Y+146208X0200Y    R090 S0      
317GND              H5    -1   MD1470PA00X+013728Y+153323X2440Y         S3      
327GND              C8362 -2          A01X+009592Y+142600X0198Y0197R180 S1      
327GND              PC363 -2   M      A01X+009592Y+143050X0198Y0197R180 S1      
327GND              R746  -2   M      A01X+041426Y+152385X0120Y0150R270 S1      
327GND              R906  -2   M      A01X+055037Y+152385X0120Y0150R270 S1      
327GND              R1100 -2   M      A01X+155825Y+155685X0120Y0150R270 S1      
327GND              R967  -2   M      A01X+129407Y+155685X0120Y0150R270 S1      
327GND              R707  -2   M      A01X+017139Y+151804X0120Y0150R180 S1      
327GND              C7501 -2   M      A01X+041132Y+156352X0120Y0150R180 S1      
327GND              U12   -7          A01X+041038Y+156980X0350Y0500R180 S1      
327GND              U20   -7          A01X+064928Y+165833X0350Y0500R180 S1      
327GND              C7503 -2   M      A01X+064975Y+165240X0120Y0150R180 S1      
327GND              C8356 -2   M      A01X+007638Y+140908X0198Y0197R270 S1      
327GND              R6088 -2          A01X+007238Y+140908X0198Y0197R270 S1      
327GND              R11   -2          A18X+065904Y+041479X0198Y0197R090 S2      
327GND              Q9003 -1          A01X+063224Y+041644X0170Y0200R270 S1      
327GND              U21   -4          A01X+066297Y+167902X0350Y0500R180 S1      
327GND              R6791 -2   M      A01X+066521Y+168906X0120Y0150     S1      
327GND              R979  -2   M      A01X+117926Y+155104X0120Y0150R180 S1      
327GND              R623  -2          A01X+117931Y+155433X0120Y0150R090 S1      
327GND              U45   -5          A01X+038280Y+158091X0130Y0250     S1      
327GND              R1215 -1   M      A01X+038367Y+157645X0120Y0150     S1      
327GND              U19   -7   M      A01X+043537Y+156980X0350Y0500R180 S1      
327GND              Q132  -1          A18X+065572Y+170958X0170Y0200R090 S2      
327GND              R4122 -2   M      A18X+064726Y+170770X0198Y0197R090 S2      
327GND              C14   -2          A18X+064726Y+170384X0198Y0197R270 S2      
327GND              R751  -1          A18X+153978Y+123851X0198Y0197R090 S2      
327GND              PU45  -2   M      A01X+074349Y+139034X0090Y0240R090 S1      
327GND              R5029 -1          A18X+158552Y+125669X0198Y0197     S2      
327GND              PC78  -2          A01X+124493Y+142236X0198Y0197     S1      
327GND              PC77  -2   M      A01X+124489Y+141846X0198Y0197     S1      
327GND              PC67  -2          A01X+124886Y+141992X0198Y0197R270 S1      
327GND              PR54  -2   M      A01X+125286Y+141992X0198Y0197R270 S1      
327GND              U6010 -FD35M      A01X+119102Y+154246X0100Y0130     S1      
327GND              R1404 -2          A01X+167634Y+153360X0120Y0150R090 S1      
327GND              U6011 -FD35M      A01X+131908Y+154246X0100Y0130     S1      
327GND              U6012 -FD35M      A01X+158325Y+154246X0100Y0130     S1      
327GND              U6016 -FD35M      A01X+057538Y+150946X0100Y0130     S1      
327GND              U6015 -FD35M      A01X+031120Y+150946X0100Y0130     S1      
327GND              PR6602-2          A01X+003467Y+150221X0198Y0197     S1      
327GND              C7007 -2   M      A01X+029275Y+158572X0400Y0500R270 S1      
317m8807            VIA   -    MD0080PA01X+048447Y+093065X0160Y    R180 S0      
317m8807            VIA   -    MD0080PA01X+137182Y+093065X0160Y    R180 S0      
327m8807            U25   -W50        A01X+137365Y+093169X0177Y    R180 S1      
327m8807            U26   -W26        A01X+048263Y+093169X0177Y    R180 S1      
317m8808            VIA   -    MD0080PA01X+047336Y+091789X0160Y    R180 S0      
317m8808            VIA   -    MD0080PA01X+138292Y+091789X0160Y    R180 S0      
327m8808            U25   -R47        A01X+138476Y+091894X0177Y    R180 S1      
327m8808            U26   -R29        A01X+047153Y+091894X0177Y    R180 S1      
317m8809            VIA   -    MD0080PA01X+047336Y+091151X0160Y    R180 S0      
317m8809            VIA   -    MD0080PA01X+138292Y+091151X0160Y    R180 S0      
327m8809            U25   -N47        A01X+138476Y+091256X0177Y    R180 S1      
327m8809            U26   -N29        A01X+047153Y+091256X0177Y    R180 S1      
317m8810            VIA   -    MD0080PA01X+047336Y+092427X0160Y    R180 S0      
317m8810            VIA   -    MD0080PA01X+138292Y+092427X0160Y    R180 S0      
327m8810            U25   -U47        A01X+138476Y+092532X0177Y    R180 S1      
327m8810            U26   -U29        A01X+047153Y+092532X0177Y    R180 S1      
317m8811            VIA   -    MD0080PA01X+046226Y+091789X0160Y    R180 S0      
317m8811            VIA   -    MD0080PA01X+139402Y+091789X0160Y    R180 S0      
327m8811            U25   -R44        A01X+139586Y+091894X0177Y    R180 S1      
327m8811            U26   -R32        A01X+046042Y+091894X0177Y    R180 S1      
317m8812            VIA   -    MD0080PA01X+046226Y+091151X0160Y    R180 S0      
317m8812            VIA   -    MD0080PA01X+139402Y+091151X0160Y    R180 S0      
327m8812            U25   -N44        A01X+139586Y+091256X0177Y    R180 S1      
327m8812            U26   -N32        A01X+046042Y+091256X0177Y    R180 S1      
317m8813            VIA   -    MD0080PA01X+046226Y+092427X0160Y    R180 S0      
317m8813            VIA   -    MD0080PA01X+139402Y+092427X0160Y    R180 S0      
327m8813            U25   -U44        A01X+139586Y+092532X0177Y    R180 S1      
327m8813            U26   -U32        A01X+046042Y+092532X0177Y    R180 S1      
317m8814            VIA   -    MD0080PA01X+045301Y+091470X0160Y    R180 S0      
317m8814            VIA   -    MD0080PA01X+140327Y+091470X0160Y    R180 S0      
327m8814            U25   -P41        A01X+140511Y+091575X0177Y    R180 S1      
327m8814            U26   -P35        A01X+045117Y+091575X0177Y    R180 S1      
317m8815            VIA   -    MD0080PA01X+045301Y+092108X0160Y    R180 S0      
317m8815            VIA   -    MD0080PA01X+140327Y+092108X0160Y    R180 S0      
327m8815            U25   -T41        A01X+140511Y+092213X0177Y    R180 S1      
327m8815            U26   -T35        A01X+045117Y+092213X0177Y    R180 S1      
317m8816            VIA   -    MD0080PA01X+049557Y+092427X0160Y    R180 S0      
317m8816            VIA   -    MD0080PA01X+136071Y+092427X0160Y    R180 S0      
327m8816            U25   -U53        A01X+136255Y+092532X0177Y    R180 S1      
327m8816            U26   -U23        A01X+049373Y+092532X0177Y    R180 S1      
317m8817            VIA   -    MD0080PA01X+049557Y+091789X0160Y    R180 S0      
317m8817            VIA   -    MD0080PA01X+136071Y+091789X0160Y    R180 S0      
327m8817            U25   -R53        A01X+136255Y+091894X0177Y    R180 S1      
327m8817            U26   -R23        A01X+049373Y+091894X0177Y    R180 S1      
317m8818            VIA   -    MD0080PA01X+049557Y+093065X0160Y    R180 S0      
317m8818            VIA   -    MD0080PA01X+136071Y+093065X0160Y    R180 S0      
327m8818            U25   -W53        A01X+136255Y+093169X0177Y    R180 S1      
327m8818            U26   -W23        A01X+049373Y+093169X0177Y    R180 S1      
317m8819            VIA   -    MD0080PA01X+048447Y+092427X0160Y    R180 S0      
317m8819            VIA   -    MD0080PA01X+137182Y+092427X0160Y    R180 S0      
327m8819            U25   -U50        A01X+137365Y+092532X0177Y    R180 S1      
327m8819            U26   -U26        A01X+048263Y+092532X0177Y    R180 S1      
317m8820            VIA   -    MD0080PA01X+048447Y+091789X0160Y    R180 S0      
317m8820            VIA   -    MD0080PA01X+137182Y+091789X0160Y    R180 S0      
327m8820            U25   -R50        A01X+137365Y+091894X0177Y    R180 S1      
327m8820            U26   -R26        A01X+048263Y+091894X0177Y    R180 S1      
317m8821            VIA   -    MD0080PA01X+048447Y+091151X0160Y    R180 S0      
317m8821            VIA   -    MD0080PA01X+137182Y+091151X0160Y    R180 S0      
327m8821            U25   -N50        A01X+137365Y+091256X0177Y    R180 S1      
327m8821            U26   -N26        A01X+048263Y+091256X0177Y    R180 S1      
317m8822            VIA   -    MD0080PA01X+045301Y+092746X0160Y    R180 S0      
317m8822            VIA   -    MD0080PA01X+140327Y+092746X0160Y    R180 S0      
327m8822            U25   -V41        A01X+140511Y+092850X0177Y    R180 S1      
327m8822            U26   -V35        A01X+045117Y+092850X0177Y    R180 S1      
317m8823            VIA   -    MD0080PA01X+048077Y+093065X0160Y    R180 S0      
317m8823            VIA   -    MD0080PA01X+137552Y+093065X0160Y    R180 S0      
327m8823            U25   -W49        A01X+137735Y+093169X0177Y    R180 S1      
327m8823            U26   -W27        A01X+047893Y+093169X0177Y    R180 S1      
317m8824            VIA   -    MD0080PA01X+046966Y+091789X0160Y    R180 S0      
317m8824            VIA   -    MD0080PA01X+138662Y+091789X0160Y    R180 S0      
327m8824            U25   -R46        A01X+138846Y+091894X0177Y    R180 S1      
327m8824            U26   -R30        A01X+046783Y+091894X0177Y    R180 S1      
317m8825            VIA   -    MD0080PA01X+046966Y+091151X0160Y    R180 S0      
317m8825            VIA   -    MD0080PA01X+138662Y+091151X0160Y    R180 S0      
327m8825            U25   -N46        A01X+138846Y+091256X0177Y    R180 S1      
327m8825            U26   -N30        A01X+046783Y+091256X0177Y    R180 S1      
317m8826            VIA   -    MD0080PA01X+046966Y+092427X0160Y    R180 S0      
317m8826            VIA   -    MD0080PA01X+138662Y+092427X0160Y    R180 S0      
327m8826            U25   -U46        A01X+138846Y+092532X0177Y    R180 S1      
327m8826            U26   -U30        A01X+046783Y+092532X0177Y    R180 S1      
317m8827            VIA   -    MD0080PA01X+045856Y+091789X0160Y    R180 S0      
317m8827            VIA   -    MD0080PA01X+139772Y+091789X0160Y    R180 S0      
327m8827            U25   -R43        A01X+139956Y+091894X0177Y    R180 S1      
327m8827            U26   -R33        A01X+045672Y+091894X0177Y    R180 S1      
317m8828            VIA   -    MD0080PA01X+045856Y+091151X0160Y    R180 S0      
317m8828            VIA   -    MD0080PA01X+139772Y+091151X0160Y    R180 S0      
327m8828            U25   -N43        A01X+139956Y+091256X0177Y    R180 S1      
327m8828            U26   -N33        A01X+045672Y+091256X0177Y    R180 S1      
317m8829            VIA   -    MD0080PA01X+045856Y+092427X0160Y    R180 S0      
317m8829            VIA   -    MD0080PA01X+139772Y+092427X0160Y    R180 S0      
327m8829            U25   -U43        A01X+139956Y+092532X0177Y    R180 S1      
327m8829            U26   -U33        A01X+045672Y+092532X0177Y    R180 S1      
317m8830            VIA   -    MD0080PA01X+044931Y+091470X0160Y    R180 S0      
317m8830            VIA   -    MD0080PA01X+140697Y+091470X0160Y    R180 S0      
327m8830            U25   -P40        A01X+140881Y+091575X0177Y    R180 S1      
327m8830            U26   -P36        A01X+044747Y+091575X0177Y    R180 S1      
317m8831            VIA   -    MD0080PA01X+044931Y+092108X0160Y    R180 S0      
317m8831            VIA   -    MD0080PA01X+140697Y+092108X0160Y    R180 S0      
327m8831            U25   -T40        A01X+140881Y+092213X0177Y    R180 S1      
327m8831            U26   -T36        A01X+044747Y+092213X0177Y    R180 S1      
317m8832            VIA   -    MD0080PA01X+049187Y+092427X0160Y    R180 S0      
317m8832            VIA   -    MD0080PA01X+136441Y+092427X0160Y    R180 S0      
327m8832            U25   -U52        A01X+136625Y+092532X0177Y    R180 S1      
327m8832            U26   -U24        A01X+049003Y+092532X0177Y    R180 S1      
317m8833            VIA   -    MD0080PA01X+049187Y+091789X0160Y    R180 S0      
317m8833            VIA   -    MD0080PA01X+136441Y+091789X0160Y    R180 S0      
327m8833            U25   -R52        A01X+136625Y+091894X0177Y    R180 S1      
327m8833            U26   -R24        A01X+049003Y+091894X0177Y    R180 S1      
317m8834            VIA   -    MD0080PA01X+049187Y+093065X0160Y    R180 S0      
317m8834            VIA   -    MD0080PA01X+136441Y+093065X0160Y    R180 S0      
327m8834            U25   -W52        A01X+136625Y+093169X0177Y    R180 S1      
327m8834            U26   -W24        A01X+049003Y+093169X0177Y    R180 S1      
317m8835            VIA   -    MD0080PA01X+048077Y+092427X0160Y    R180 S0      
317m8835            VIA   -    MD0080PA01X+137552Y+092427X0160Y    R180 S0      
327m8835            U25   -U49        A01X+137735Y+092532X0177Y    R180 S1      
327m8835            U26   -U27        A01X+047893Y+092532X0177Y    R180 S1      
317m8836            VIA   -    MD0080PA01X+048077Y+091789X0160Y    R180 S0      
317m8836            VIA   -    MD0080PA01X+137552Y+091789X0160Y    R180 S0      
327m8836            U25   -R49        A01X+137735Y+091894X0177Y    R180 S1      
327m8836            U26   -R27        A01X+047893Y+091894X0177Y    R180 S1      
317m8837            VIA   -    MD0080PA01X+048077Y+091151X0160Y    R180 S0      
317m8837            VIA   -    MD0080PA01X+137552Y+091151X0160Y    R180 S0      
327m8837            U25   -N49        A01X+137735Y+091256X0177Y    R180 S1      
327m8837            U26   -N27        A01X+047893Y+091256X0177Y    R180 S1      
317m8838            VIA   -    MD0080PA01X+044931Y+092746X0160Y    R180 S0      
317m8838            VIA   -    MD0080PA01X+140697Y+092746X0160Y    R180 S0      
327m8838            U25   -V40        A01X+140881Y+092850X0177Y    R180 S1      
327m8838            U26   -V36        A01X+044747Y+092850X0177Y    R180 S1      
317m8839            VIA   -    MD0080PA01X+048447Y+090514X0160Y    R180 S0      
317m8839            VIA   -    MD0080PA01X+137182Y+090513X0160Y    R180 S0      
327m8839            U25   -L50        A01X+137365Y+090618X0177Y    R180 S1      
327m8839            U26   -L26        A01X+048263Y+090618X0177Y    R180 S1      
317m8840            VIA   -    MD0080PA01X+047336Y+089876X0160Y    R180 S0      
317m8840            VIA   -    MD0080PA01X+138292Y+089876X0160Y    R180 S0      
327m8840            U25   -J47        A01X+138476Y+089980X0177Y    R180 S1      
327m8840            U26   -J29        A01X+047153Y+089980X0177Y    R180 S1      
317m8841            VIA   -    MD0080PA01X+047336Y+089238X0160Y    R180 S0      
317m8841            VIA   -    MD0080PA01X+138292Y+089238X0160Y    R180 S0      
327m8841            U25   -G47        A01X+138476Y+089343X0177Y    R180 S1      
327m8841            U26   -G29        A01X+047153Y+089343X0177Y    R180 S1      
317m8842            VIA   -    MD0080PA01X+047336Y+090514X0160Y    R180 S0      
317m8842            VIA   -    MD0080PA01X+138292Y+090513X0160Y    R180 S0      
327m8842            U25   -L47        A01X+138476Y+090618X0177Y    R180 S1      
327m8842            U26   -L29        A01X+047153Y+090618X0177Y    R180 S1      
317m8843            VIA   -    MD0080PA01X+046226Y+089876X0160Y    R180 S0      
317m8843            VIA   -    MD0080PA01X+139402Y+089876X0160Y    R180 S0      
327m8843            U25   -J44        A01X+139586Y+089980X0177Y    R180 S1      
327m8843            U26   -J32        A01X+046042Y+089980X0177Y    R180 S1      
317m8844            VIA   -    MD0080PA01X+046226Y+089238X0160Y    R180 S0      
317m8844            VIA   -    MD0080PA01X+139402Y+089238X0160Y    R180 S0      
327m8844            U25   -G44        A01X+139586Y+089343X0177Y    R180 S1      
327m8844            U26   -G32        A01X+046042Y+089343X0177Y    R180 S1      
317m8845            VIA   -    MD0080PA01X+046226Y+090514X0160Y    R180 S0      
317m8845            VIA   -    MD0080PA01X+139402Y+090513X0160Y    R180 S0      
327m8845            U25   -L44        A01X+139586Y+090618X0177Y    R180 S1      
327m8845            U26   -L32        A01X+046042Y+090618X0177Y    R180 S1      
317m8846            VIA   -    MD0080PA01X+045301Y+089557X0160Y    R180 S0      
317m8846            VIA   -    MD0080PA01X+140327Y+089557X0160Y    R180 S0      
327m8846            U25   -H41        A01X+140511Y+089662X0177Y    R180 S1      
327m8846            U26   -H35        A01X+045117Y+089662X0177Y    R180 S1      
317m8847            VIA   -    MD0080PA01X+045301Y+090195X0160Y    R180 S0      
317m8847            VIA   -    MD0080PA01X+140327Y+090195X0160Y    R180 S0      
327m8847            U25   -K41        A01X+140511Y+090299X0177Y    R180 S1      
327m8847            U26   -K35        A01X+045117Y+090299X0177Y    R180 S1      
317m8848            VIA   -    MD0080PA01X+049557Y+091151X0160Y    R180 S0      
317m8848            VIA   -    MD0080PA01X+136071Y+091151X0160Y    R180 S0      
327m8848            U25   -N53        A01X+136255Y+091256X0177Y    R180 S1      
327m8848            U26   -N23        A01X+049373Y+091256X0177Y    R180 S1      
317m8849            VIA   -    MD0080PA01X+049557Y+089876X0160Y    R180 S0      
317m8849            VIA   -    MD0080PA01X+136071Y+089876X0160Y    R180 S0      
327m8849            U25   -J53        A01X+136255Y+089980X0177Y    R180 S1      
327m8849            U26   -J23        A01X+049373Y+089980X0177Y    R180 S1      
317m8850            VIA   -    MD0080PA01X+049557Y+089238X0160Y    R180 S0      
317m8850            VIA   -    MD0080PA01X+136071Y+089238X0160Y    R180 S0      
327m8850            U25   -G53        A01X+136255Y+089343X0177Y    R180 S1      
327m8850            U26   -G23        A01X+049373Y+089343X0177Y    R180 S1      
317m8851            VIA   -    MD0080PA01X+049557Y+090514X0160Y    R180 S0      
317m8851            VIA   -    MD0080PA01X+136071Y+090513X0160Y    R180 S0      
327m8851            U25   -L53        A01X+136255Y+090618X0177Y    R180 S1      
327m8851            U26   -L23        A01X+049373Y+090618X0177Y    R180 S1      
317m8852            VIA   -    MD0080PA01X+048447Y+089876X0160Y    R180 S0      
317m8852            VIA   -    MD0080PA01X+137182Y+089876X0160Y    R180 S0      
327m8852            U25   -J50        A01X+137365Y+089980X0177Y    R180 S1      
327m8852            U26   -J26        A01X+048263Y+089980X0177Y    R180 S1      
317m8853            VIA   -    MD0080PA01X+048447Y+089238X0160Y    R180 S0      
317m8853            VIA   -    MD0080PA01X+137182Y+089238X0160Y    R180 S0      
327m8853            U25   -G50        A01X+137365Y+089343X0177Y    R180 S1      
327m8853            U26   -G26        A01X+048263Y+089343X0177Y    R180 S1      
317m8854            VIA   -    MD0080PA01X+045301Y+090832X0160Y    R180 S0      
317m8854            VIA   -    MD0080PA01X+140327Y+090832X0160Y    R180 S0      
327m8854            U25   -M41        A01X+140511Y+090937X0177Y    R180 S1      
327m8854            U26   -M35        A01X+045117Y+090937X0177Y    R180 S1      
317m8855            VIA   -    MD0080PA01X+048077Y+090514X0160Y    R180 S0      
317m8855            VIA   -    MD0080PA01X+137552Y+090513X0160Y    R180 S0      
327m8855            U25   -L49        A01X+137735Y+090618X0177Y    R180 S1      
327m8855            U26   -L27        A01X+047893Y+090618X0177Y    R180 S1      
317m8856            VIA   -    MD0080PA01X+046966Y+089876X0160Y    R180 S0      
317m8856            VIA   -    MD0080PA01X+138662Y+089876X0160Y    R180 S0      
327m8856            U25   -J46        A01X+138846Y+089980X0177Y    R180 S1      
327m8856            U26   -J30        A01X+046783Y+089980X0177Y    R180 S1      
317m8857            VIA   -    MD0080PA01X+046966Y+089238X0160Y    R180 S0      
317m8857            VIA   -    MD0080PA01X+138662Y+089238X0160Y    R180 S0      
327m8857            U25   -G46        A01X+138846Y+089343X0177Y    R180 S1      
327m8857            U26   -G30        A01X+046783Y+089343X0177Y    R180 S1      
317m8858            VIA   -    MD0080PA01X+046966Y+090514X0160Y    R180 S0      
317m8858            VIA   -    MD0080PA01X+138662Y+090513X0160Y    R180 S0      
327m8858            U25   -L46        A01X+138846Y+090618X0177Y    R180 S1      
327m8858            U26   -L30        A01X+046783Y+090618X0177Y    R180 S1      
317m8859            VIA   -    MD0080PA01X+045856Y+089876X0160Y    R180 S0      
317m8859            VIA   -    MD0080PA01X+139772Y+089876X0160Y    R180 S0      
327m8859            U25   -J43        A01X+139956Y+089980X0177Y    R180 S1      
327m8859            U26   -J33        A01X+045672Y+089980X0177Y    R180 S1      
317m8860            VIA   -    MD0080PA01X+045856Y+089238X0160Y    R180 S0      
317m8860            VIA   -    MD0080PA01X+139772Y+089238X0160Y    R180 S0      
327m8860            U25   -G43        A01X+139956Y+089343X0177Y    R180 S1      
327m8860            U26   -G33        A01X+045672Y+089343X0177Y    R180 S1      
317m8861            VIA   -    MD0080PA01X+045856Y+090514X0160Y    R180 S0      
317m8861            VIA   -    MD0080PA01X+139772Y+090513X0160Y    R180 S0      
327m8861            U25   -L43        A01X+139956Y+090618X0177Y    R180 S1      
327m8861            U26   -L33        A01X+045672Y+090618X0177Y    R180 S1      
317m8862            VIA   -    MD0080PA01X+044931Y+089557X0160Y    R180 S0      
317m8862            VIA   -    MD0080PA01X+140697Y+089557X0160Y    R180 S0      
327m8862            U25   -H40        A01X+140881Y+089662X0177Y    R180 S1      
327m8862            U26   -H36        A01X+044747Y+089662X0177Y    R180 S1      
317m8863            VIA   -    MD0080PA01X+044931Y+090195X0160Y    R180 S0      
317m8863            VIA   -    MD0080PA01X+140697Y+090195X0160Y    R180 S0      
327m8863            U25   -K40        A01X+140881Y+090299X0177Y    R180 S1      
327m8863            U26   -K36        A01X+044747Y+090299X0177Y    R180 S1      
317m8864            VIA   -    MD0080PA01X+049187Y+091151X0160Y    R180 S0      
317m8864            VIA   -    MD0080PA01X+136441Y+091151X0160Y    R180 S0      
327m8864            U25   -N52        A01X+136625Y+091256X0177Y    R180 S1      
327m8864            U26   -N24        A01X+049003Y+091256X0177Y    R180 S1      
317m8865            VIA   -    MD0080PA01X+049187Y+089876X0160Y    R180 S0      
317m8865            VIA   -    MD0080PA01X+136441Y+089876X0160Y    R180 S0      
327m8865            U25   -J52        A01X+136625Y+089980X0177Y    R180 S1      
327m8865            U26   -J24        A01X+049003Y+089980X0177Y    R180 S1      
317m8866            VIA   -    MD0080PA01X+049187Y+089238X0160Y    R180 S0      
317m8866            VIA   -    MD0080PA01X+136441Y+089238X0160Y    R180 S0      
327m8866            U25   -G52        A01X+136625Y+089343X0177Y    R180 S1      
327m8866            U26   -G24        A01X+049003Y+089343X0177Y    R180 S1      
317m8867            VIA   -    MD0080PA01X+049187Y+090514X0160Y    R180 S0      
317m8867            VIA   -    MD0080PA01X+136441Y+090513X0160Y    R180 S0      
327m8867            U25   -L52        A01X+136625Y+090618X0177Y    R180 S1      
327m8867            U26   -L24        A01X+049003Y+090618X0177Y    R180 S1      
317m8868            VIA   -    MD0080PA01X+048077Y+089876X0160Y    R180 S0      
317m8868            VIA   -    MD0080PA01X+137552Y+089876X0160Y    R180 S0      
327m8868            U25   -J49        A01X+137735Y+089980X0177Y    R180 S1      
327m8868            U26   -J27        A01X+047893Y+089980X0177Y    R180 S1      
317m8869            VIA   -    MD0080PA01X+048077Y+089238X0160Y    R180 S0      
317m8869            VIA   -    MD0080PA01X+137552Y+089238X0160Y    R180 S0      
327m8869            U25   -G49        A01X+137735Y+089343X0177Y    R180 S1      
327m8869            U26   -G27        A01X+047893Y+089343X0177Y    R180 S1      
317m8870            VIA   -    MD0080PA01X+044931Y+090832X0160Y    R180 S0      
317m8870            VIA   -    MD0080PA01X+140697Y+090832X0160Y    R180 S0      
327m8870            U25   -M40        A01X+140881Y+090937X0177Y    R180 S1      
327m8870            U26   -M36        A01X+044747Y+090937X0177Y    R180 S1      
317m8871            VIA   -    MD0080PA01X+042158Y+094978X0160Y    R180 S0      
317m8871            VIA   -    MD0080PA01X+143470Y+094978X0160Y    R180 S0      
327m8871            U25   -AE33       A01X+143287Y+095083X0177Y    R180 S1      
327m8871            U26   -AE43       A01X+042342Y+095083X0177Y    R180 S1      
317m8872            VIA   -    MD0080PA01X+041048Y+095616X0160Y    R180 S0      
317m8872            VIA   -    MD0080PA01X+144581Y+095616X0160Y    R180 S0      
327m8872            U25   -AG30       A01X+144397Y+095720X0177Y    R180 S1      
327m8872            U26   -AG46       A01X+041232Y+095721X0177Y    R180 S1      
317m8873            VIA   -    MD0080PA01X+041048Y+094340X0160Y    R180 S0      
317m8873            VIA   -    MD0080PA01X+144581Y+094340X0160Y    R180 S0      
327m8873            U25   -AC30       A01X+144397Y+094445X0177Y    R180 S1      
327m8873            U26   -AC46       A01X+041232Y+094445X0177Y    R180 S1      
317m8874            VIA   -    MD0080PA01X+041048Y+094978X0160Y    R180 S0      
317m8874            VIA   -    MD0080PA01X+144581Y+094978X0160Y    R180 S0      
327m8874            U25   -AE30       A01X+144397Y+095083X0177Y    R180 S1      
327m8874            U26   -AE46       A01X+041232Y+095083X0177Y    R180 S1      
317m8875            VIA   -    MD0080PA01X+039937Y+095616X0160Y    R180 S0      
317m8875            VIA   -    MD0080PA01X+145691Y+095616X0160Y    R180 S0      
327m8875            U25   -AG27       A01X+145507Y+095720X0177Y    R180 S1      
327m8875            U26   -AG49       A01X+040121Y+095721X0177Y    R180 S1      
317m8876            VIA   -    MD0080PA01X+039937Y+094340X0160Y    R180 S0      
317m8876            VIA   -    MD0080PA01X+145691Y+094340X0160Y    R180 S0      
327m8876            U25   -AC27       A01X+145507Y+094445X0177Y    R180 S1      
327m8876            U26   -AC49       A01X+040121Y+094445X0177Y    R180 S1      
317m8877            VIA   -    MD0080PA01X+039937Y+094978X0160Y    R180 S0      
317m8877            VIA   -    MD0080PA01X+145691Y+094978X0160Y    R180 S0      
327m8877            U25   -AE27       A01X+145507Y+095083X0177Y    R180 S1      
327m8877            U26   -AE49       A01X+040121Y+095083X0177Y    R180 S1      
317m8878            VIA   -    MD0080PA01X+038827Y+095616X0160Y    R180 S0      
317m8878            VIA   -    MD0080PA01X+146801Y+095616X0160Y    R180 S0      
327m8878            U25   -AG24       A01X+146617Y+095720X0177Y    R180 S1      
327m8878            U26   -AG52       A01X+039011Y+095721X0177Y    R180 S1      
317m8879            VIA   -    MD0080PA01X+038827Y+094340X0160Y    R180 S0      
317m8879            VIA   -    MD0080PA01X+146801Y+094340X0160Y    R180 S0      
327m8879            U25   -AC24       A01X+146617Y+094445X0177Y    R180 S1      
327m8879            U26   -AC52       A01X+039011Y+094445X0177Y    R180 S1      
317m8880            VIA   -    MD0080PA01X+043083Y+095297X0160Y    R180 S0      
317m8880            VIA   -    MD0080PA01X+142545Y+095297X0160Y    R180 S0      
327m8880            U25   -AF36       A01X+142361Y+095402X0177Y    R180 S1      
327m8880            U26   -AF40       A01X+043267Y+095402X0177Y    R180 S1      
317m8881            VIA   -    MD0080PA01X+043083Y+094659X0160Y    R180 S0      
317m8881            VIA   -    MD0080PA01X+142545Y+094659X0160Y    R180 S0      
327m8881            U25   -AD36       A01X+142361Y+094764X0177Y    R180 S1      
327m8881            U26   -AD40       A01X+043267Y+094764X0177Y    R180 S1      
317m8882            VIA   -    MD0080PA01X+043083Y+094021X0160Y    R180 S0      
317m8882            VIA   -    MD0080PA01X+142545Y+094021X0160Y    R180 S0      
327m8882            U25   -AB36       A01X+142361Y+094126X0177Y    R180 S1      
327m8882            U26   -AB40       A01X+043267Y+094126X0177Y    R180 S1      
317m8883            VIA   -    MD0080PA01X+042158Y+095616X0160Y    R180 S0      
317m8883            VIA   -    MD0080PA01X+143470Y+095616X0160Y    R180 S0      
327m8883            U25   -AG33       A01X+143287Y+095720X0177Y    R180 S1      
327m8883            U26   -AG43       A01X+042342Y+095721X0177Y    R180 S1      
317m8884            VIA   -    MD0080PA01X+042158Y+093702X0160Y    R180 S0      
317m8884            VIA   -    MD0080PA01X+143470Y+093702X0160Y    R180 S0      
327m8884            U25   -AA33       A01X+143287Y+093807X0177Y    R180 S1      
327m8884            U26   -AA43       A01X+042342Y+093807X0177Y    R180 S1      
317m8885            VIA   -    MD0080PA01X+042158Y+094340X0160Y    R180 S0      
317m8885            VIA   -    MD0080PA01X+143470Y+094340X0160Y    R180 S0      
327m8885            U25   -AC33       A01X+143287Y+094445X0177Y    R180 S1      
327m8885            U26   -AC43       A01X+042342Y+094445X0177Y    R180 S1      
317m8886            VIA   -    MD0080PA01X+038827Y+094978X0160Y    R180 S0      
317m8886            VIA   -    MD0080PA01X+146801Y+094978X0160Y    R180 S0      
327m8886            U25   -AE24       A01X+146617Y+095083X0177Y    R180 S1      
327m8886            U26   -AE52       A01X+039011Y+095083X0177Y    R180 S1      
317m8887            VIA   -    MD0080PA01X+041788Y+094978X0160Y    R180 S0      
317m8887            VIA   -    MD0080PA01X+143840Y+094978X0160Y    R180 S0      
327m8887            U25   -AE32       A01X+143657Y+095083X0177Y    R180 S1      
327m8887            U26   -AE44       A01X+041972Y+095083X0177Y    R180 S1      
317m8888            VIA   -    MD0080PA01X+040678Y+095616X0160Y    R180 S0      
317m8888            VIA   -    MD0080PA01X+144951Y+095616X0160Y    R180 S0      
327m8888            U25   -AG29       A01X+144767Y+095720X0177Y    R180 S1      
327m8888            U26   -AG47       A01X+040861Y+095721X0177Y    R180 S1      
317m8889            VIA   -    MD0080PA01X+040678Y+094340X0160Y    R180 S0      
317m8889            VIA   -    MD0080PA01X+144951Y+094340X0160Y    R180 S0      
327m8889            U25   -AC29       A01X+144767Y+094445X0177Y    R180 S1      
327m8889            U26   -AC47       A01X+040861Y+094445X0177Y    R180 S1      
317m8890            VIA   -    MD0080PA01X+040678Y+094978X0160Y    R180 S0      
317m8890            VIA   -    MD0080PA01X+144951Y+094978X0160Y    R180 S0      
327m8890            U25   -AE29       A01X+144767Y+095083X0177Y    R180 S1      
327m8890            U26   -AE47       A01X+040861Y+095083X0177Y    R180 S1      
317m8891            VIA   -    MD0080PA01X+039567Y+095616X0160Y    R180 S0      
317m8891            VIA   -    MD0080PA01X+146061Y+095616X0160Y    R180 S0      
327m8891            U25   -AG26       A01X+145877Y+095720X0177Y    R180 S1      
327m8891            U26   -AG50       A01X+039751Y+095721X0177Y    R180 S1      
317m8892            VIA   -    MD0080PA01X+039567Y+094340X0160Y    R180 S0      
317m8892            VIA   -    MD0080PA01X+146061Y+094340X0160Y    R180 S0      
327m8892            U25   -AC26       A01X+145877Y+094445X0177Y    R180 S1      
327m8892            U26   -AC50       A01X+039751Y+094445X0177Y    R180 S1      
317m8893            VIA   -    MD0080PA01X+039567Y+094978X0160Y    R180 S0      
317m8893            VIA   -    MD0080PA01X+146061Y+094978X0160Y    R180 S0      
327m8893            U25   -AE26       A01X+145877Y+095083X0177Y    R180 S1      
327m8893            U26   -AE50       A01X+039751Y+095083X0177Y    R180 S1      
317m8894            VIA   -    MD0080PA01X+038457Y+095616X0160Y    R180 S0      
317m8894            VIA   -    MD0080PA01X+147171Y+095616X0160Y    R180 S0      
327m8894            U25   -AG23       A01X+146987Y+095720X0177Y    R180 S1      
327m8894            U26   -AG53       A01X+038641Y+095721X0177Y    R180 S1      
317m8895            VIA   -    MD0080PA01X+038457Y+094340X0160Y    R180 S0      
317m8895            VIA   -    MD0080PA01X+147171Y+094340X0160Y    R180 S0      
327m8895            U25   -AC23       A01X+146987Y+094445X0177Y    R180 S1      
327m8895            U26   -AC53       A01X+038641Y+094445X0177Y    R180 S1      
317m8896            VIA   -    MD0080PA01X+042713Y+095297X0160Y    R180 S0      
317m8896            VIA   -    MD0080PA01X+142915Y+095297X0160Y    R180 S0      
327m8896            U25   -AF35       A01X+142732Y+095402X0177Y    R180 S1      
327m8896            U26   -AF41       A01X+042897Y+095402X0177Y    R180 S1      
317m8897            VIA   -    MD0080PA01X+042713Y+094659X0160Y    R180 S0      
317m8897            VIA   -    MD0080PA01X+142915Y+094659X0160Y    R180 S0      
327m8897            U25   -AD35       A01X+142732Y+094764X0177Y    R180 S1      
327m8897            U26   -AD41       A01X+042897Y+094764X0177Y    R180 S1      
317m8898            VIA   -    MD0080PA01X+042713Y+094021X0160Y    R180 S0      
317m8898            VIA   -    MD0080PA01X+142915Y+094021X0160Y    R180 S0      
327m8898            U25   -AB35       A01X+142732Y+094126X0177Y    R180 S1      
327m8898            U26   -AB41       A01X+042897Y+094126X0177Y    R180 S1      
317m8899            VIA   -    MD0080PA01X+041788Y+095616X0160Y    R180 S0      
317m8899            VIA   -    MD0080PA01X+143840Y+095616X0160Y    R180 S0      
327m8899            U25   -AG32       A01X+143657Y+095720X0177Y    R180 S1      
327m8899            U26   -AG44       A01X+041972Y+095721X0177Y    R180 S1      
317m8900            VIA   -    MD0080PA01X+041788Y+093702X0160Y    R180 S0      
317m8900            VIA   -    MD0080PA01X+143840Y+093702X0160Y    R180 S0      
327m8900            U25   -AA32       A01X+143657Y+093807X0177Y    R180 S1      
327m8900            U26   -AA44       A01X+041972Y+093807X0177Y    R180 S1      
317m8901            VIA   -    MD0080PA01X+041788Y+094340X0160Y    R180 S0      
317m8901            VIA   -    MD0080PA01X+143840Y+094340X0160Y    R180 S0      
327m8901            U25   -AC32       A01X+143657Y+094445X0177Y    R180 S1      
327m8901            U26   -AC44       A01X+041972Y+094445X0177Y    R180 S1      
317m8902            VIA   -    MD0080PA01X+038457Y+094978X0160Y    R180 S0      
317m8902            VIA   -    MD0080PA01X+147171Y+094978X0160Y    R180 S0      
327m8902            U25   -AE23       A01X+146987Y+095083X0177Y    R180 S1      
327m8902            U26   -AE53       A01X+038641Y+095083X0177Y    R180 S1      
317m8903            VIA   -    MD0080PA01X+040678Y+092427X0160Y    R180 S0      
327m8903            U26   -U47        A01X+040861Y+092532X0177Y    R180 S1      
327m8903            J35   -A37        A01X+016085Y+003276X0150Y0570R180 S1      
317m8903            VIA   -    MD0100PA01X+016036Y+001954X0200Y         S0      
317m8904            VIA   -    MD0080PA01X+040678Y+091151X0160Y    R180 S0      
327m8904            U26   -N47        A01X+040861Y+091256X0177Y    R180 S1      
327m8904            J35   -A40        A01X+015377Y+003276X0150Y0570R180 S1      
317m8904            VIA   -    MD0100PA01X+015325Y+002648X0200Y         S0      
317m8905            VIA   -    MD0080PA01X+040678Y+091789X0160Y    R180 S0      
327m8905            U26   -R47        A01X+040861Y+091894X0177Y    R180 S1      
327m8905            J35   -A45        A01X+012499Y+003276X0150Y0570R180 S1      
317m8905            VIA   -    MD0100PA01X+012449Y+001954X0200Y         S0      
317m8906            VIA   -    MD0080PA01X+039567Y+093065X0160Y    R180 S0      
327m8906            U26   -W50        A01X+039751Y+093169X0177Y    R180 S1      
327m8906            J35   -A48        A01X+011790Y+003276X0150Y0570R180 S1      
317m8906            VIA   -    MD0100PA01X+011738Y+002648X0200Y         S0      
317m8907            VIA   -    MD0080PA01X+039567Y+091151X0160Y    R180 S0      
327m8907            U26   -N50        A01X+039751Y+091256X0177Y    R180 S1      
317m8907            VIA   -    MD0100PA01X+011032Y+001954X0200Y         S0      
327m8907            J35   -A51        A01X+011082Y+003276X0150Y0570R180 S1      
317m8908            VIA   -    MD0080PA01X+039567Y+091789X0160Y    R180 S0      
327m8908            U26   -R50        A01X+039751Y+091894X0177Y    R180 S1      
317m8908            VIA   -    MD0100PA01X+010321Y+002648X0200Y         S0      
327m8908            J35   -A54        A01X+010373Y+003276X0150Y0570R180 S1      
317m8909            VIA   -    MD0080PA01X+039567Y+092427X0160Y    R180 S0      
327m8909            U26   -U50        A01X+039751Y+092532X0177Y    R180 S1      
317m8909            VIA   -    MD0100PA01X+009614Y+001954X0200Y         S0      
327m8909            J35   -A57        A01X+009664Y+003276X0150Y0570R180 S1      
317m8910            VIA   -    MD0080PA01X+038457Y+093065X0160Y    R180 S0      
327m8910            U26   -W53        A01X+038641Y+093169X0177Y    R180 S1      
317m8910            VIA   -    MD0100PA01X+008904Y+002648X0200Y         S0      
327m8910            J35   -A60        A01X+008956Y+003276X0150Y0570R180 S1      
317m8911            VIA   -    MD0080PA01X+038457Y+091789X0160Y    R180 S0      
327m8911            U26   -R53        A01X+038641Y+091894X0177Y    R180 S1      
317m8911            VIA   -    MD0100PA01X+008197Y+001954X0200Y         S0      
327m8911            J35   -A63        A01X+008247Y+003276X0150Y0570R180 S1      
317m8912            VIA   -    MD0080PA01X+042713Y+092746X0160Y    R180 S0      
327m8912            U26   -V41        A01X+042897Y+092850X0177Y    R180 S1      
327m8912            J35   -A18        A01X+021916Y+003276X0150Y0570R180 S1      
317m8912            VIA   -    MD0100PA01X+021866Y+001954X0200Y         S0      
317m8913            VIA   -    MD0080PA01X+042713Y+092108X0160Y    R180 S0      
327m8913            U26   -T41        A01X+042897Y+092213X0177Y    R180 S1      
317m8913            VIA   -    MD0100PA01X+021156Y+002648X0200Y         S0      
327m8913            J35   -A21        A01X+021208Y+003276X0150Y0570R180 S1      
317m8914            VIA   -    MD0080PA01X+042713Y+091470X0160Y    R180 S0      
327m8914            U26   -P41        A01X+042897Y+091575X0177Y    R180 S1      
327m8914            J35   -A24        A01X+020499Y+003276X0150Y0570R180 S1      
317m8914            VIA   -    MD0100PA01X+020449Y+001954X0200Y         S0      
317m8915            VIA   -    MD0080PA01X+041788Y+092427X0160Y    R180 S0      
327m8915            U26   -U44        A01X+041972Y+092532X0177Y    R180 S1      
327m8915            J35   -A27        A01X+019790Y+003276X0150Y0570R180 S1      
317m8915            VIA   -    MD0100PA01X+019738Y+002648X0200Y         S0      
317m8916            VIA   -    MD0080PA01X+041788Y+091151X0160Y    R180 S0      
327m8916            U26   -N44        A01X+041972Y+091256X0177Y    R180 S1      
327m8916            J35   -A31        A01X+017503Y+003276X0150Y0570R180 S1      
317m8916            VIA   -    MD0100PA01X+017453Y+001954X0200Y         S0      
317m8917            VIA   -    MD0080PA01X+041788Y+091789X0160Y    R180 S0      
327m8917            U26   -R44        A01X+041972Y+091894X0177Y    R180 S1      
327m8917            J35   -A34        A01X+016794Y+003276X0150Y0570R180 S1      
317m8917            VIA   -    MD0100PA01X+016742Y+002648X0200Y         S0      
317m8918            VIA   -    MD0080PA01X+038457Y+092427X0160Y    R180 S0      
327m8918            U26   -U53        A01X+038641Y+092532X0177Y    R180 S1      
317m8918            VIA   -    MD0100PA01X+007486Y+002648X0200Y         S0      
327m8918            J35   -A66        A01X+007538Y+003276X0150Y0570R180 S1      
317m8919            VIA   -    MD0080PA01X+041048Y+092427X0160Y    R180 S0      
327m8919            U26   -U46        A01X+041232Y+092532X0177Y    R180 S1      
327m8919            J35   -A36        A01X+016322Y+003276X0150Y0570R180 S1      
317m8919            VIA   -    MD0100PA01X+016376Y+001954X0200Y         S0      
317m8920            VIA   -    MD0080PA01X+041048Y+091151X0160Y    R180 S0      
327m8920            U26   -N46        A01X+041232Y+091256X0177Y    R180 S1      
327m8920            J35   -A39        A01X+015613Y+003276X0150Y0570R180 S1      
317m8920            VIA   -    MD0100PA01X+015665Y+002648X0200Y         S0      
317m8921            VIA   -    MD0080PA01X+041048Y+091789X0160Y    R180 S0      
327m8921            U26   -R46        A01X+041232Y+091894X0177Y    R180 S1      
327m8921            J35   -A44        A01X+012735Y+003276X0150Y0570R180 S1      
317m8921            VIA   -    MD0100PA01X+012789Y+001954X0200Y         S0      
317m8922            VIA   -    MD0080PA01X+039937Y+093065X0160Y    R180 S0      
327m8922            U26   -W49        A01X+040121Y+093169X0177Y    R180 S1      
327m8922            J35   -A47        A01X+012026Y+003276X0150Y0570R180 S1      
317m8922            VIA   -    MD0100PA01X+012078Y+002648X0200Y         S0      
317m8923            VIA   -    MD0080PA01X+039937Y+091151X0160Y    R180 S0      
327m8923            U26   -N49        A01X+040121Y+091256X0177Y    R180 S1      
317m8923            VIA   -    MD0100PA01X+011372Y+001954X0200Y         S0      
327m8923            J35   -A50        A01X+011318Y+003276X0150Y0570R180 S1      
317m8924            VIA   -    MD0080PA01X+039937Y+091789X0160Y    R180 S0      
327m8924            U26   -R49        A01X+040121Y+091894X0177Y    R180 S1      
317m8924            VIA   -    MD0100PA01X+010661Y+002648X0200Y         S0      
327m8924            J35   -A53        A01X+010609Y+003276X0150Y0570R180 S1      
317m8925            VIA   -    MD0080PA01X+039937Y+092427X0160Y    R180 S0      
327m8925            U26   -U49        A01X+040121Y+092532X0177Y    R180 S1      
317m8925            VIA   -    MD0100PA01X+009954Y+001954X0200Y         S0      
327m8925            J35   -A56        A01X+009900Y+003276X0150Y0570R180 S1      
317m8926            VIA   -    MD0080PA01X+038827Y+093065X0160Y    R180 S0      
327m8926            U26   -W52        A01X+039011Y+093169X0177Y    R180 S1      
317m8926            VIA   -    MD0100PA01X+009244Y+002648X0200Y         S0      
327m8926            J35   -A59        A01X+009192Y+003276X0150Y0570R180 S1      
317m8927            VIA   -    MD0080PA01X+038827Y+091789X0160Y    R180 S0      
327m8927            U26   -R52        A01X+039011Y+091894X0177Y    R180 S1      
317m8927            VIA   -    MD0100PA01X+008537Y+001954X0200Y         S0      
327m8927            J35   -A62        A01X+008483Y+003276X0150Y0570R180 S1      
317m8928            VIA   -    MD0080PA01X+043083Y+092746X0160Y    R180 S0      
327m8928            U26   -V40        A01X+043267Y+092850X0177Y    R180 S1      
327m8928            J35   -A17        A01X+022152Y+003276X0150Y0570R180 S1      
317m8928            VIA   -    MD0100PA01X+022206Y+001954X0200Y         S0      
317m8929            VIA   -    MD0080PA01X+043083Y+092108X0160Y    R180 S0      
327m8929            U26   -T40        A01X+043267Y+092213X0177Y    R180 S1      
327m8929            J35   -A20        A01X+021444Y+003276X0150Y0570R180 S1      
317m8929            VIA   -    MD0100PA01X+021496Y+002648X0200Y         S0      
317m8930            VIA   -    MD0080PA01X+043083Y+091470X0160Y    R180 S0      
327m8930            U26   -P40        A01X+043267Y+091575X0177Y    R180 S1      
327m8930            J35   -A23        A01X+020735Y+003276X0150Y0570R180 S1      
317m8930            VIA   -    MD0100PA01X+020789Y+001954X0200Y         S0      
317m8931            VIA   -    MD0080PA01X+042158Y+092427X0160Y    R180 S0      
327m8931            U26   -U43        A01X+042342Y+092532X0177Y    R180 S1      
327m8931            J35   -A26        A01X+020026Y+003276X0150Y0570R180 S1      
317m8931            VIA   -    MD0100PA01X+020078Y+002648X0200Y         S0      
317m8932            VIA   -    MD0080PA01X+042158Y+091151X0160Y    R180 S0      
327m8932            U26   -N43        A01X+042342Y+091256X0177Y    R180 S1      
327m8932            J35   -A30        A01X+017739Y+003276X0150Y0570R180 S1      
317m8932            VIA   -    MD0100PA01X+017793Y+001954X0200Y         S0      
317m8933            VIA   -    MD0080PA01X+042158Y+091789X0160Y    R180 S0      
327m8933            U26   -R43        A01X+042342Y+091894X0177Y    R180 S1      
327m8933            J35   -A33        A01X+017030Y+003276X0150Y0570R180 S1      
317m8933            VIA   -    MD0100PA01X+017082Y+002648X0200Y         S0      
317m8934            VIA   -    MD0080PA01X+038827Y+092427X0160Y    R180 S0      
327m8934            U26   -U52        A01X+039011Y+092532X0177Y    R180 S1      
317m8934            VIA   -    MD0100PA01X+007826Y+002648X0200Y         S0      
327m8934            J35   -A65        A01X+007774Y+003276X0150Y0570R180 S1      
317m8935            VIA   -    MD0080PA01X+040678Y+090514X0160Y    R180 S0      
317m8935            VIA   -    MD0080PA01X+144951Y+090513X0160Y    R180 S0      
327m8935            U25   -L29        A01X+144767Y+090618X0177Y    R180 S1      
327m8935            U26   -L47        A01X+040861Y+090618X0177Y    R180 S1      
317m8936            VIA   -    MD0080PA01X+040678Y+089238X0160Y    R180 S0      
317m8936            VIA   -    MD0080PA01X+144951Y+089238X0160Y    R180 S0      
327m8936            U25   -G29        A01X+144767Y+089343X0177Y    R180 S1      
327m8936            U26   -G47        A01X+040861Y+089343X0177Y    R180 S1      
317m8937            VIA   -    MD0080PA01X+040678Y+089876X0160Y    R180 S0      
317m8937            VIA   -    MD0080PA01X+144951Y+089876X0160Y    R180 S0      
327m8937            U25   -J29        A01X+144767Y+089980X0177Y    R180 S1      
327m8937            U26   -J47        A01X+040861Y+089980X0177Y    R180 S1      
317m8938            VIA   -    MD0080PA01X+039567Y+090514X0160Y    R180 S0      
317m8938            VIA   -    MD0080PA01X+146061Y+090513X0160Y    R180 S0      
327m8938            U25   -L26        A01X+145877Y+090618X0177Y    R180 S1      
327m8938            U26   -L50        A01X+039751Y+090618X0177Y    R180 S1      
317m8939            VIA   -    MD0080PA01X+039567Y+089238X0160Y    R180 S0      
317m8939            VIA   -    MD0080PA01X+146061Y+089238X0160Y    R180 S0      
327m8939            U25   -G26        A01X+145877Y+089343X0177Y    R180 S1      
327m8939            U26   -G50        A01X+039751Y+089343X0177Y    R180 S1      
317m8940            VIA   -    MD0080PA01X+039567Y+089876X0160Y    R180 S0      
317m8940            VIA   -    MD0080PA01X+146061Y+089876X0160Y    R180 S0      
327m8940            U25   -J26        A01X+145877Y+089980X0177Y    R180 S1      
327m8940            U26   -J50        A01X+039751Y+089980X0177Y    R180 S1      
317m8941            VIA   -    MD0080PA01X+038457Y+090514X0160Y    R180 S0      
317m8941            VIA   -    MD0080PA01X+147171Y+090513X0160Y    R180 S0      
327m8941            U25   -L23        A01X+146987Y+090618X0177Y    R180 S1      
327m8941            U26   -L53        A01X+038641Y+090618X0177Y    R180 S1      
317m8942            VIA   -    MD0080PA01X+038457Y+089238X0160Y    R180 S0      
317m8942            VIA   -    MD0080PA01X+147171Y+089238X0160Y    R180 S0      
327m8942            U25   -G23        A01X+146987Y+089343X0177Y    R180 S1      
327m8942            U26   -G53        A01X+038641Y+089343X0177Y    R180 S1      
317m8943            VIA   -    MD0080PA01X+038457Y+089876X0160Y    R180 S0      
317m8943            VIA   -    MD0080PA01X+147171Y+089876X0160Y    R180 S0      
327m8943            U25   -J23        A01X+146987Y+089980X0177Y    R180 S1      
327m8943            U26   -J53        A01X+038641Y+089980X0177Y    R180 S1      
317m8944            VIA   -    MD0080PA01X+042713Y+090832X0160Y    R180 S0      
317m8944            VIA   -    MD0080PA01X+142915Y+090832X0160Y    R180 S0      
327m8944            U25   -M35        A01X+142732Y+090937X0177Y    R180 S1      
327m8944            U26   -M41        A01X+042897Y+090937X0177Y    R180 S1      
317m8945            VIA   -    MD0080PA01X+042713Y+090195X0160Y    R180 S0      
317m8945            VIA   -    MD0080PA01X+142915Y+090195X0160Y    R180 S0      
327m8945            U25   -K35        A01X+142732Y+090299X0177Y    R180 S1      
327m8945            U26   -K41        A01X+042897Y+090299X0177Y    R180 S1      
317m8946            VIA   -    MD0080PA01X+042713Y+089557X0160Y    R180 S0      
317m8946            VIA   -    MD0080PA01X+142915Y+089557X0160Y    R180 S0      
327m8946            U25   -H35        A01X+142732Y+089662X0177Y    R180 S1      
327m8946            U26   -H41        A01X+042897Y+089662X0177Y    R180 S1      
317m8947            VIA   -    MD0080PA01X+041788Y+090514X0160Y    R180 S0      
317m8947            VIA   -    MD0080PA01X+143840Y+090513X0160Y    R180 S0      
327m8947            U25   -L32        A01X+143657Y+090618X0177Y    R180 S1      
327m8947            U26   -L44        A01X+041972Y+090618X0177Y    R180 S1      
317m8948            VIA   -    MD0080PA01X+041788Y+089238X0160Y    R180 S0      
317m8948            VIA   -    MD0080PA01X+143840Y+089238X0160Y    R180 S0      
327m8948            U25   -G32        A01X+143657Y+089343X0177Y    R180 S1      
327m8948            U26   -G44        A01X+041972Y+089343X0177Y    R180 S1      
317m8949            VIA   -    MD0080PA01X+041788Y+089876X0160Y    R180 S0      
317m8949            VIA   -    MD0080PA01X+143840Y+089876X0160Y    R180 S0      
327m8949            U25   -J32        A01X+143657Y+089980X0177Y    R180 S1      
327m8949            U26   -J44        A01X+041972Y+089980X0177Y    R180 S1      
317m8950            VIA   -    MD0080PA01X+038457Y+091151X0160Y    R180 S0      
317m8950            VIA   -    MD0080PA01X+147171Y+091151X0160Y    R180 S0      
327m8950            U25   -N23        A01X+146987Y+091256X0177Y    R180 S1      
327m8950            U26   -N53        A01X+038641Y+091256X0177Y    R180 S1      
317m8951            VIA   -    MD0080PA01X+041048Y+090514X0160Y    R180 S0      
317m8951            VIA   -    MD0080PA01X+144581Y+090513X0160Y    R180 S0      
327m8951            U25   -L30        A01X+144397Y+090618X0177Y    R180 S1      
327m8951            U26   -L46        A01X+041232Y+090618X0177Y    R180 S1      
317m8952            VIA   -    MD0080PA01X+041048Y+089238X0160Y    R180 S0      
317m8952            VIA   -    MD0080PA01X+144581Y+089238X0160Y    R180 S0      
327m8952            U25   -G30        A01X+144397Y+089343X0177Y    R180 S1      
327m8952            U26   -G46        A01X+041232Y+089343X0177Y    R180 S1      
317m8953            VIA   -    MD0080PA01X+041048Y+089876X0160Y    R180 S0      
317m8953            VIA   -    MD0080PA01X+144581Y+089876X0160Y    R180 S0      
327m8953            U25   -J30        A01X+144397Y+089980X0177Y    R180 S1      
327m8953            U26   -J46        A01X+041232Y+089980X0177Y    R180 S1      
317m8954            VIA   -    MD0080PA01X+039937Y+090514X0160Y    R180 S0      
317m8954            VIA   -    MD0080PA01X+145691Y+090513X0160Y    R180 S0      
327m8954            U25   -L27        A01X+145507Y+090618X0177Y    R180 S1      
327m8954            U26   -L49        A01X+040121Y+090618X0177Y    R180 S1      
317m8955            VIA   -    MD0080PA01X+039937Y+089238X0160Y    R180 S0      
317m8955            VIA   -    MD0080PA01X+145691Y+089238X0160Y    R180 S0      
327m8955            U25   -G27        A01X+145507Y+089343X0177Y    R180 S1      
327m8955            U26   -G49        A01X+040121Y+089343X0177Y    R180 S1      
317m8956            VIA   -    MD0080PA01X+039937Y+089876X0160Y    R180 S0      
317m8956            VIA   -    MD0080PA01X+145691Y+089876X0160Y    R180 S0      
327m8956            U25   -J27        A01X+145507Y+089980X0177Y    R180 S1      
327m8956            U26   -J49        A01X+040121Y+089980X0177Y    R180 S1      
317m8957            VIA   -    MD0080PA01X+038827Y+090514X0160Y    R180 S0      
317m8957            VIA   -    MD0080PA01X+146801Y+090513X0160Y    R180 S0      
327m8957            U25   -L24        A01X+146617Y+090618X0177Y    R180 S1      
327m8957            U26   -L52        A01X+039011Y+090618X0177Y    R180 S1      
317m8958            VIA   -    MD0080PA01X+038827Y+089238X0160Y    R180 S0      
317m8958            VIA   -    MD0080PA01X+146801Y+089238X0160Y    R180 S0      
327m8958            U25   -G24        A01X+146617Y+089343X0177Y    R180 S1      
327m8958            U26   -G52        A01X+039011Y+089343X0177Y    R180 S1      
317m8959            VIA   -    MD0080PA01X+038827Y+089876X0160Y    R180 S0      
317m8959            VIA   -    MD0080PA01X+146801Y+089876X0160Y    R180 S0      
327m8959            U25   -J24        A01X+146617Y+089980X0177Y    R180 S1      
327m8959            U26   -J52        A01X+039011Y+089980X0177Y    R180 S1      
317m8960            VIA   -    MD0080PA01X+043083Y+090832X0160Y    R180 S0      
317m8960            VIA   -    MD0080PA01X+142545Y+090832X0160Y    R180 S0      
327m8960            U25   -M36        A01X+142361Y+090937X0177Y    R180 S1      
327m8960            U26   -M40        A01X+043267Y+090937X0177Y    R180 S1      
317m8961            VIA   -    MD0080PA01X+043083Y+090195X0160Y    R180 S0      
317m8961            VIA   -    MD0080PA01X+142545Y+090195X0160Y    R180 S0      
327m8961            U25   -K36        A01X+142361Y+090299X0177Y    R180 S1      
327m8961            U26   -K40        A01X+043267Y+090299X0177Y    R180 S1      
317m8962            VIA   -    MD0080PA01X+043083Y+089557X0160Y    R180 S0      
317m8962            VIA   -    MD0080PA01X+142545Y+089557X0160Y    R180 S0      
327m8962            U25   -H36        A01X+142361Y+089662X0177Y    R180 S1      
327m8962            U26   -H40        A01X+043267Y+089662X0177Y    R180 S1      
317m8963            VIA   -    MD0080PA01X+042158Y+090514X0160Y    R180 S0      
317m8963            VIA   -    MD0080PA01X+143470Y+090513X0160Y    R180 S0      
327m8963            U25   -L33        A01X+143287Y+090618X0177Y    R180 S1      
327m8963            U26   -L43        A01X+042342Y+090618X0177Y    R180 S1      
317m8964            VIA   -    MD0080PA01X+042158Y+089238X0160Y    R180 S0      
317m8964            VIA   -    MD0080PA01X+143470Y+089238X0160Y    R180 S0      
327m8964            U25   -G33        A01X+143287Y+089343X0177Y    R180 S1      
327m8964            U26   -G43        A01X+042342Y+089343X0177Y    R180 S1      
317m8965            VIA   -    MD0080PA01X+042158Y+089876X0160Y    R180 S0      
317m8965            VIA   -    MD0080PA01X+143470Y+089876X0160Y    R180 S0      
327m8965            U25   -J33        A01X+143287Y+089980X0177Y    R180 S1      
327m8965            U26   -J43        A01X+042342Y+089980X0177Y    R180 S1      
317m8966            VIA   -    MD0080PA01X+038827Y+091151X0160Y    R180 S0      
317m8966            VIA   -    MD0080PA01X+146801Y+091151X0160Y    R180 S0      
327m8966            U25   -N24        A01X+146617Y+091256X0177Y    R180 S1      
327m8966            U26   -N52        A01X+039011Y+091256X0177Y    R180 S1      
317m8967            VIA   -    MD0080PA01X+046966Y+096892X0160Y    R180 S0      
317m8967            VIA   -    MD0080PA01X+138662Y+096891X0160Y    R180 S0      
327m8967            U25   -AL46       A01X+138846Y+096996X0177Y    R180 S1      
327m8967            U26   -AL30       A01X+046783Y+096996X0177Y    R180 S1      
317m8968            VIA   -    MD0080PA01X+046966Y+096254X0160Y    R180 S0      
317m8968            VIA   -    MD0080PA01X+138662Y+096254X0160Y    R180 S0      
327m8968            U25   -AJ46       A01X+138846Y+096358X0177Y    R180 S1      
327m8968            U26   -AJ30       A01X+046783Y+096358X0177Y    R180 S1      
317m8969            VIA   -    MD0080PA01X+046966Y+097529X0160Y    R180 S0      
317m8969            VIA   -    MD0080PA01X+138662Y+097529X0160Y    R180 S0      
327m8969            U25   -AN46       A01X+138846Y+097634X0177Y    R180 S1      
327m8969            U26   -AN30       A01X+046783Y+097634X0177Y    R180 S1      
317m8970            VIA   -    MD0080PA01X+045856Y+096892X0160Y    R180 S0      
317m8970            VIA   -    MD0080PA01X+139772Y+096891X0160Y    R180 S0      
327m8970            U25   -AL43       A01X+139956Y+096996X0177Y    R180 S1      
327m8970            U26   -AL33       A01X+045672Y+096996X0177Y    R180 S1      
317m8971            VIA   -    MD0080PA01X+045856Y+096254X0160Y    R180 S0      
317m8971            VIA   -    MD0080PA01X+139772Y+096254X0160Y    R180 S0      
327m8971            U25   -AJ43       A01X+139956Y+096358X0177Y    R180 S1      
327m8971            U26   -AJ33       A01X+045672Y+096358X0177Y    R180 S1      
317m8972            VIA   -    MD0080PA01X+045856Y+097529X0160Y    R180 S0      
317m8972            VIA   -    MD0080PA01X+139772Y+097529X0160Y    R180 S0      
327m8972            U25   -AN43       A01X+139956Y+097634X0177Y    R180 S1      
327m8972            U26   -AN33       A01X+045672Y+097634X0177Y    R180 S1      
317m8973            VIA   -    MD0080PA01X+044931Y+096573X0160Y    R180 S0      
317m8973            VIA   -    MD0080PA01X+140697Y+096572X0160Y    R180 S0      
327m8973            U25   -AK40       A01X+140881Y+096677X0177Y    R180 S1      
327m8973            U26   -AK36       A01X+044747Y+096677X0177Y    R180 S1      
317m8974            VIA   -    MD0080PA01X+044931Y+095935X0160Y    R180 S0      
317m8974            VIA   -    MD0080PA01X+140697Y+095935X0160Y    R180 S0      
327m8974            U25   -AH40       A01X+140881Y+096039X0177Y    R180 S1      
327m8974            U26   -AH36       A01X+044747Y+096040X0177Y    R180 S1      
317m8975            VIA   -    MD0080PA01X+044931Y+097210X0160Y    R180 S0      
317m8975            VIA   -    MD0080PA01X+140697Y+097210X0160Y    R180 S0      
327m8975            U25   -AM40       A01X+140881Y+097315X0177Y    R180 S1      
327m8975            U26   -AM36       A01X+044747Y+097315X0177Y    R180 S1      
317m8976            VIA   -    MD0080PA01X+049187Y+096892X0160Y    R180 S0      
317m8976            VIA   -    MD0080PA01X+136441Y+096891X0160Y    R180 S0      
327m8976            U25   -AL52       A01X+136625Y+096996X0177Y    R180 S1      
327m8976            U26   -AL24       A01X+049003Y+096996X0177Y    R180 S1      
317m8977            VIA   -    MD0080PA01X+049187Y+096254X0160Y    R180 S0      
317m8977            VIA   -    MD0080PA01X+136441Y+096254X0160Y    R180 S0      
327m8977            U25   -AJ52       A01X+136625Y+096358X0177Y    R180 S1      
327m8977            U26   -AJ24       A01X+049003Y+096358X0177Y    R180 S1      
317m8978            VIA   -    MD0080PA01X+049187Y+097529X0160Y    R180 S0      
317m8978            VIA   -    MD0080PA01X+136441Y+097529X0160Y    R180 S0      
327m8978            U25   -AN52       A01X+136625Y+097634X0177Y    R180 S1      
327m8978            U26   -AN24       A01X+049003Y+097634X0177Y    R180 S1      
317m8979            VIA   -    MD0080PA01X+048077Y+096892X0160Y    R180 S0      
317m8979            VIA   -    MD0080PA01X+137552Y+096891X0160Y    R180 S0      
327m8979            U25   -AL49       A01X+137735Y+096996X0177Y    R180 S1      
327m8979            U26   -AL27       A01X+047893Y+096996X0177Y    R180 S1      
317m8980            VIA   -    MD0080PA01X+048077Y+096254X0160Y    R180 S0      
317m8980            VIA   -    MD0080PA01X+137552Y+096254X0160Y    R180 S0      
327m8980            U25   -AJ49       A01X+137735Y+096358X0177Y    R180 S1      
327m8980            U26   -AJ27       A01X+047893Y+096358X0177Y    R180 S1      
317m8981            VIA   -    MD0080PA01X+048077Y+097529X0160Y    R180 S0      
317m8981            VIA   -    MD0080PA01X+137552Y+097529X0160Y    R180 S0      
327m8981            U25   -AN49       A01X+137735Y+097634X0177Y    R180 S1      
327m8981            U26   -AN27       A01X+047893Y+097634X0177Y    R180 S1      
317m8982            VIA   -    MD0080PA01X+044931Y+097848X0160Y    R180 S0      
317m8982            VIA   -    MD0080PA01X+140697Y+097848X0160Y    R180 S0      
327m8982            U25   -AP40       A01X+140881Y+097953X0177Y    R180 S1      
327m8982            U26   -AP36       A01X+044747Y+097953X0177Y    R180 S1      
317m8983            VIA   -    MD0080PA01X+047336Y+096892X0160Y    R180 S0      
317m8983            VIA   -    MD0080PA01X+138292Y+096891X0160Y    R180 S0      
327m8983            U25   -AL47       A01X+138476Y+096996X0177Y    R180 S1      
327m8983            U26   -AL29       A01X+047153Y+096996X0177Y    R180 S1      
317m8984            VIA   -    MD0080PA01X+047336Y+096254X0160Y    R180 S0      
317m8984            VIA   -    MD0080PA01X+138292Y+096254X0160Y    R180 S0      
327m8984            U25   -AJ47       A01X+138476Y+096358X0177Y    R180 S1      
327m8984            U26   -AJ29       A01X+047153Y+096358X0177Y    R180 S1      
317m8985            VIA   -    MD0080PA01X+047336Y+097529X0160Y    R180 S0      
317m8985            VIA   -    MD0080PA01X+138292Y+097529X0160Y    R180 S0      
327m8985            U25   -AN47       A01X+138476Y+097634X0177Y    R180 S1      
327m8985            U26   -AN29       A01X+047153Y+097634X0177Y    R180 S1      
317m8986            VIA   -    MD0080PA01X+046226Y+096892X0160Y    R180 S0      
317m8986            VIA   -    MD0080PA01X+139402Y+096891X0160Y    R180 S0      
327m8986            U25   -AL44       A01X+139586Y+096996X0177Y    R180 S1      
327m8986            U26   -AL32       A01X+046042Y+096996X0177Y    R180 S1      
317m8987            VIA   -    MD0080PA01X+046226Y+096254X0160Y    R180 S0      
317m8987            VIA   -    MD0080PA01X+139402Y+096254X0160Y    R180 S0      
327m8987            U25   -AJ44       A01X+139586Y+096358X0177Y    R180 S1      
327m8987            U26   -AJ32       A01X+046042Y+096358X0177Y    R180 S1      
317m8988            VIA   -    MD0080PA01X+046226Y+097529X0160Y    R180 S0      
317m8988            VIA   -    MD0080PA01X+139402Y+097529X0160Y    R180 S0      
327m8988            U25   -AN44       A01X+139586Y+097634X0177Y    R180 S1      
327m8988            U26   -AN32       A01X+046042Y+097634X0177Y    R180 S1      
317m8989            VIA   -    MD0080PA01X+045301Y+096573X0160Y    R180 S0      
317m8989            VIA   -    MD0080PA01X+140327Y+096572X0160Y    R180 S0      
327m8989            U25   -AK41       A01X+140511Y+096677X0177Y    R180 S1      
327m8989            U26   -AK35       A01X+045117Y+096677X0177Y    R180 S1      
317m8990            VIA   -    MD0080PA01X+045301Y+095935X0160Y    R180 S0      
317m8990            VIA   -    MD0080PA01X+140327Y+095935X0160Y    R180 S0      
327m8990            U25   -AH41       A01X+140511Y+096039X0177Y    R180 S1      
327m8990            U26   -AH35       A01X+045117Y+096040X0177Y    R180 S1      
317m8991            VIA   -    MD0080PA01X+045301Y+097210X0160Y    R180 S0      
317m8991            VIA   -    MD0080PA01X+140327Y+097210X0160Y    R180 S0      
327m8991            U25   -AM41       A01X+140511Y+097315X0177Y    R180 S1      
327m8991            U26   -AM35       A01X+045117Y+097315X0177Y    R180 S1      
317m8992            VIA   -    MD0080PA01X+049557Y+096892X0160Y    R180 S0      
317m8992            VIA   -    MD0080PA01X+136071Y+096891X0160Y    R180 S0      
327m8992            U25   -AL53       A01X+136255Y+096996X0177Y    R180 S1      
327m8992            U26   -AL23       A01X+049373Y+096996X0177Y    R180 S1      
317m8993            VIA   -    MD0080PA01X+049557Y+096254X0160Y    R180 S0      
317m8993            VIA   -    MD0080PA01X+136071Y+096254X0160Y    R180 S0      
327m8993            U25   -AJ53       A01X+136255Y+096358X0177Y    R180 S1      
327m8993            U26   -AJ23       A01X+049373Y+096358X0177Y    R180 S1      
317m8994            VIA   -    MD0080PA01X+049557Y+097529X0160Y    R180 S0      
317m8994            VIA   -    MD0080PA01X+136071Y+097529X0160Y    R180 S0      
327m8994            U25   -AN53       A01X+136255Y+097634X0177Y    R180 S1      
327m8994            U26   -AN23       A01X+049373Y+097634X0177Y    R180 S1      
317m8995            VIA   -    MD0080PA01X+048447Y+096892X0160Y    R180 S0      
317m8995            VIA   -    MD0080PA01X+137182Y+096891X0160Y    R180 S0      
327m8995            U25   -AL50       A01X+137365Y+096996X0177Y    R180 S1      
327m8995            U26   -AL26       A01X+048263Y+096996X0177Y    R180 S1      
317m8996            VIA   -    MD0080PA01X+048447Y+096254X0160Y    R180 S0      
317m8996            VIA   -    MD0080PA01X+137182Y+096254X0160Y    R180 S0      
327m8996            U25   -AJ50       A01X+137365Y+096358X0177Y    R180 S1      
327m8996            U26   -AJ26       A01X+048263Y+096358X0177Y    R180 S1      
317m8997            VIA   -    MD0080PA01X+048447Y+097529X0160Y    R180 S0      
317m8997            VIA   -    MD0080PA01X+137182Y+097529X0160Y    R180 S0      
327m8997            U25   -AN50       A01X+137365Y+097634X0177Y    R180 S1      
327m8997            U26   -AN26       A01X+048263Y+097634X0177Y    R180 S1      
317m8998            VIA   -    MD0080PA01X+045301Y+097848X0160Y    R180 S0      
317m8998            VIA   -    MD0080PA01X+140327Y+097848X0160Y    R180 S0      
327m8998            U25   -AP41       A01X+140511Y+097953X0177Y    R180 S1      
327m8998            U26   -AP35       A01X+045117Y+097953X0177Y    R180 S1      
317m8999            VIA   -    MD0080PA01X+046966Y+094978X0160Y    R180 S0      
317m8999            VIA   -    MD0080PA01X+138662Y+094978X0160Y    R180 S0      
327m8999            U25   -AE46       A01X+138846Y+095083X0177Y    R180 S1      
327m8999            U26   -AE30       A01X+046783Y+095083X0177Y    R180 S1      
317m9000            VIA   -    MD0080PA01X+046966Y+094340X0160Y    R180 S0      
317m9000            VIA   -    MD0080PA01X+138662Y+094340X0160Y    R180 S0      
327m9000            U25   -AC46       A01X+138846Y+094445X0177Y    R180 S1      
327m9000            U26   -AC30       A01X+046783Y+094445X0177Y    R180 S1      
317m9001            VIA   -    MD0080PA01X+046966Y+095616X0160Y    R180 S0      
317m9001            VIA   -    MD0080PA01X+138662Y+095616X0160Y    R180 S0      
327m9001            U25   -AG46       A01X+138846Y+095720X0177Y    R180 S1      
327m9001            U26   -AG30       A01X+046783Y+095721X0177Y    R180 S1      
317m9002            VIA   -    MD0080PA01X+045856Y+094978X0160Y    R180 S0      
317m9002            VIA   -    MD0080PA01X+139772Y+094978X0160Y    R180 S0      
327m9002            U25   -AE43       A01X+139956Y+095083X0177Y    R180 S1      
327m9002            U26   -AE33       A01X+045672Y+095083X0177Y    R180 S1      
317m9003            VIA   -    MD0080PA01X+045856Y+094340X0160Y    R180 S0      
317m9003            VIA   -    MD0080PA01X+139772Y+094340X0160Y    R180 S0      
327m9003            U25   -AC43       A01X+139956Y+094445X0177Y    R180 S1      
327m9003            U26   -AC33       A01X+045672Y+094445X0177Y    R180 S1      
317m9004            VIA   -    MD0080PA01X+045856Y+093702X0160Y    R180 S0      
317m9004            VIA   -    MD0080PA01X+139772Y+093702X0160Y    R180 S0      
327m9004            U25   -AA43       A01X+139956Y+093807X0177Y    R180 S1      
327m9004            U26   -AA33       A01X+045672Y+093807X0177Y    R180 S1      
317m9005            VIA   -    MD0080PA01X+045856Y+095616X0160Y    R180 S0      
317m9005            VIA   -    MD0080PA01X+139772Y+095616X0160Y    R180 S0      
327m9005            U25   -AG43       A01X+139956Y+095720X0177Y    R180 S1      
327m9005            U26   -AG33       A01X+045672Y+095721X0177Y    R180 S1      
317m9006            VIA   -    MD0080PA01X+044931Y+094021X0160Y    R180 S0      
317m9006            VIA   -    MD0080PA01X+140697Y+094021X0160Y    R180 S0      
327m9006            U25   -AB40       A01X+140881Y+094126X0177Y    R180 S1      
327m9006            U26   -AB36       A01X+044747Y+094126X0177Y    R180 S1      
317m9007            VIA   -    MD0080PA01X+044931Y+094659X0160Y    R180 S0      
317m9007            VIA   -    MD0080PA01X+140697Y+094659X0160Y    R180 S0      
327m9007            U25   -AD40       A01X+140881Y+094764X0177Y    R180 S1      
327m9007            U26   -AD36       A01X+044747Y+094764X0177Y    R180 S1      
317m9008            VIA   -    MD0080PA01X+049187Y+094978X0160Y    R180 S0      
317m9008            VIA   -    MD0080PA01X+136441Y+094978X0160Y    R180 S0      
327m9008            U25   -AE52       A01X+136625Y+095083X0177Y    R180 S1      
327m9008            U26   -AE24       A01X+049003Y+095083X0177Y    R180 S1      
317m9009            VIA   -    MD0080PA01X+049187Y+094340X0160Y    R180 S0      
317m9009            VIA   -    MD0080PA01X+136441Y+094340X0160Y    R180 S0      
327m9009            U25   -AC52       A01X+136625Y+094445X0177Y    R180 S1      
327m9009            U26   -AC24       A01X+049003Y+094445X0177Y    R180 S1      
317m9010            VIA   -    MD0080PA01X+049187Y+095616X0160Y    R180 S0      
317m9010            VIA   -    MD0080PA01X+136441Y+095616X0160Y    R180 S0      
327m9010            U25   -AG52       A01X+136625Y+095720X0177Y    R180 S1      
327m9010            U26   -AG24       A01X+049003Y+095721X0177Y    R180 S1      
317m9011            VIA   -    MD0080PA01X+048077Y+094978X0160Y    R180 S0      
317m9011            VIA   -    MD0080PA01X+137552Y+094978X0160Y    R180 S0      
327m9011            U25   -AE49       A01X+137735Y+095083X0177Y    R180 S1      
327m9011            U26   -AE27       A01X+047893Y+095083X0177Y    R180 S1      
317m9012            VIA   -    MD0080PA01X+048077Y+094340X0160Y    R180 S0      
317m9012            VIA   -    MD0080PA01X+137552Y+094340X0160Y    R180 S0      
327m9012            U25   -AC49       A01X+137735Y+094445X0177Y    R180 S1      
327m9012            U26   -AC27       A01X+047893Y+094445X0177Y    R180 S1      
317m9013            VIA   -    MD0080PA01X+048077Y+095616X0160Y    R180 S0      
317m9013            VIA   -    MD0080PA01X+137552Y+095616X0160Y    R180 S0      
327m9013            U25   -AG49       A01X+137735Y+095720X0177Y    R180 S1      
327m9013            U26   -AG27       A01X+047893Y+095721X0177Y    R180 S1      
317m9014            VIA   -    MD0080PA01X+044931Y+095297X0160Y    R180 S0      
317m9014            VIA   -    MD0080PA01X+140697Y+095297X0160Y    R180 S0      
327m9014            U25   -AF40       A01X+140881Y+095402X0177Y    R180 S1      
327m9014            U26   -AF36       A01X+044747Y+095402X0177Y    R180 S1      
317m9015            VIA   -    MD0080PA01X+047336Y+094978X0160Y    R180 S0      
317m9015            VIA   -    MD0080PA01X+138292Y+094978X0160Y    R180 S0      
327m9015            U25   -AE47       A01X+138476Y+095083X0177Y    R180 S1      
327m9015            U26   -AE29       A01X+047153Y+095083X0177Y    R180 S1      
317m9016            VIA   -    MD0080PA01X+047336Y+094340X0160Y    R180 S0      
317m9016            VIA   -    MD0080PA01X+138292Y+094340X0160Y    R180 S0      
327m9016            U25   -AC47       A01X+138476Y+094445X0177Y    R180 S1      
327m9016            U26   -AC29       A01X+047153Y+094445X0177Y    R180 S1      
317m9017            VIA   -    MD0080PA01X+047336Y+095616X0160Y    R180 S0      
317m9017            VIA   -    MD0080PA01X+138292Y+095616X0160Y    R180 S0      
327m9017            U25   -AG47       A01X+138476Y+095720X0177Y    R180 S1      
327m9017            U26   -AG29       A01X+047153Y+095721X0177Y    R180 S1      
317m9018            VIA   -    MD0080PA01X+046226Y+094978X0160Y    R180 S0      
317m9018            VIA   -    MD0080PA01X+139402Y+094978X0160Y    R180 S0      
327m9018            U25   -AE44       A01X+139586Y+095083X0177Y    R180 S1      
327m9018            U26   -AE32       A01X+046042Y+095083X0177Y    R180 S1      
317m9019            VIA   -    MD0080PA01X+046226Y+094340X0160Y    R180 S0      
317m9019            VIA   -    MD0080PA01X+139402Y+094340X0160Y    R180 S0      
327m9019            U25   -AC44       A01X+139586Y+094445X0177Y    R180 S1      
327m9019            U26   -AC32       A01X+046042Y+094445X0177Y    R180 S1      
317m9020            VIA   -    MD0080PA01X+046226Y+093702X0160Y    R180 S0      
317m9020            VIA   -    MD0080PA01X+139402Y+093702X0160Y    R180 S0      
327m9020            U25   -AA44       A01X+139586Y+093807X0177Y    R180 S1      
327m9020            U26   -AA32       A01X+046042Y+093807X0177Y    R180 S1      
317m9021            VIA   -    MD0080PA01X+046226Y+095616X0160Y    R180 S0      
317m9021            VIA   -    MD0080PA01X+139402Y+095616X0160Y    R180 S0      
327m9021            U25   -AG44       A01X+139586Y+095720X0177Y    R180 S1      
327m9021            U26   -AG32       A01X+046042Y+095721X0177Y    R180 S1      
317m9022            VIA   -    MD0080PA01X+045301Y+094021X0160Y    R180 S0      
317m9022            VIA   -    MD0080PA01X+140327Y+094021X0160Y    R180 S0      
327m9022            U25   -AB41       A01X+140511Y+094126X0177Y    R180 S1      
327m9022            U26   -AB35       A01X+045117Y+094126X0177Y    R180 S1      
317m9023            VIA   -    MD0080PA01X+045301Y+094659X0160Y    R180 S0      
317m9023            VIA   -    MD0080PA01X+140327Y+094659X0160Y    R180 S0      
327m9023            U25   -AD41       A01X+140511Y+094764X0177Y    R180 S1      
327m9023            U26   -AD35       A01X+045117Y+094764X0177Y    R180 S1      
317m9024            VIA   -    MD0080PA01X+049557Y+094978X0160Y    R180 S0      
317m9024            VIA   -    MD0080PA01X+136071Y+094978X0160Y    R180 S0      
327m9024            U25   -AE53       A01X+136255Y+095083X0177Y    R180 S1      
327m9024            U26   -AE23       A01X+049373Y+095083X0177Y    R180 S1      
317m9025            VIA   -    MD0080PA01X+049557Y+094340X0160Y    R180 S0      
317m9025            VIA   -    MD0080PA01X+136071Y+094340X0160Y    R180 S0      
327m9025            U25   -AC53       A01X+136255Y+094445X0177Y    R180 S1      
327m9025            U26   -AC23       A01X+049373Y+094445X0177Y    R180 S1      
317m9026            VIA   -    MD0080PA01X+049557Y+095616X0160Y    R180 S0      
317m9026            VIA   -    MD0080PA01X+136071Y+095616X0160Y    R180 S0      
327m9026            U25   -AG53       A01X+136255Y+095720X0177Y    R180 S1      
327m9026            U26   -AG23       A01X+049373Y+095721X0177Y    R180 S1      
317m9027            VIA   -    MD0080PA01X+048447Y+094978X0160Y    R180 S0      
317m9027            VIA   -    MD0080PA01X+137182Y+094978X0160Y    R180 S0      
327m9027            U25   -AE50       A01X+137365Y+095083X0177Y    R180 S1      
327m9027            U26   -AE26       A01X+048263Y+095083X0177Y    R180 S1      
317m9028            VIA   -    MD0080PA01X+048447Y+094340X0160Y    R180 S0      
317m9028            VIA   -    MD0080PA01X+137182Y+094340X0160Y    R180 S0      
327m9028            U25   -AC50       A01X+137365Y+094445X0177Y    R180 S1      
327m9028            U26   -AC26       A01X+048263Y+094445X0177Y    R180 S1      
317m9029            VIA   -    MD0080PA01X+048447Y+095616X0160Y    R180 S0      
317m9029            VIA   -    MD0080PA01X+137182Y+095616X0160Y    R180 S0      
327m9029            U25   -AG50       A01X+137365Y+095720X0177Y    R180 S1      
327m9029            U26   -AG26       A01X+048263Y+095721X0177Y    R180 S1      
317m9030            VIA   -    MD0080PA01X+045301Y+095297X0160Y    R180 S0      
317m9030            VIA   -    MD0080PA01X+140327Y+095297X0160Y    R180 S0      
327m9030            U25   -AF41       A01X+140511Y+095402X0177Y    R180 S1      
327m9030            U26   -AF35       A01X+045117Y+095402X0177Y    R180 S1      
327m9031            R8118 -2          A01X+058678Y+045424X0198Y0197     S1      
327m9031            R8119 -2   M      A01X+059378Y+045424X0198Y0197     S1      
327m9031            R6096 -2          A01X+065642Y+042986X0198Y0197R180 S1      
317m9031            VIA   -    MD0100PA00X+064241Y+042761X0200Y         S0      
317m9031            VIA   -    M      A01X+062280Y+046135X0200Y         S2      
017m9031            VIA   -    M      A18X+062280Y+046135X0260Y         S2      
017m9031                  -    MD0100PA00X+062280Y+046135                       
327m9031            U206  -1   M      A01X+061720Y+046135X0250Y0480R270 S1      
327m9031            R2233 -2          A01X+063008Y+046144X0198Y0197R180 S1      
327FM_UART_LS_EN    R1563 -2          A01X+080533Y+043963X0198Y0197R180 S1      
327FM_UART_LS_EN    U18   -U7         A01X+074772Y+043879X0160Y    R090 S1      
317FM_UART_LS_EN    VIA   -    MD0100PA00X+074926Y+043726X0180Y    R090 S0      
317FM_UART_LS_EN    VIA   -    M      A01X+080246Y+044322X0200Y         S2      
017FM_UART_LS_EN    VIA   -    M      A18X+080246Y+044322X0260Y         S2      
017FM_UART_LS_EN          -    MD0100PA00X+080246Y+044322                       
327FM_UART_EN       R3063 -2          A01X+141062Y+161334X0198Y0197R090 S1      
327FM_UART_EN       VIA   -    M      A01X+141062Y+161700X0300Y    R180 S1      
327FM_UART_EN       U204  -1          A01X+141362Y+162563X0170Y0240     S1      
327m9032            J41   -A52        A01X+055334Y+005354X0150Y0570R180 S1      
327m9032            R3776 -2          A18X+055362Y+003734X0198Y0197R270 S2      
317m9032            VIA   -    M      A01X+055365Y+004884X0200Y         S2      
017m9032            VIA   -    M      A18X+055365Y+004884X0260Y         S2      
017m9032                  -    MD0100PA00X+055365Y+004884                       
317m9033            VIA   -    M      A01X+058312Y+047674X0200Y         S2      
017m9033            VIA   -    M      A18X+058312Y+047674X0260Y         S2      
017m9033                  -    MD0100PA00X+058312Y+047674                       
327m9033            U18   -F13        A01X+071308Y+045769X0160Y    R090 S1      
317m9033            VIA   -    MD0100PA00X+071154Y+045922X0180Y    R090 S0      
317m9033            VIA   -    MD0100PA00X+055362Y+003105X0200Y         S0      
327m9033            R3776 -1          A18X+055362Y+003419X0198Y0197R270 S2      
327m9034            J41   -A55        A01X+054625Y+005354X0150Y0570R180 S1      
327m9034            R3777 -2          A18X+053912Y+003714X0198Y0197R270 S2      
317m9034            VIA   -    M      A01X+054472Y+004289X0200Y         S2      
017m9034            VIA   -    M      A18X+054472Y+004289X0260Y         S2      
017m9034                  -    MD0100PA00X+054472Y+004289                       
317m9035            VIA   -    MD0100PA00X+053912Y+003134X0200Y         S0      
327m9035            R3777 -1          A18X+053912Y+003399X0198Y0197R270 S2      
327m9035            U18   -G15        A01X+071623Y+046399X0160Y    R090 S1      
317m9035            VIA   -    M      A01X+066600Y+047384X0200Y    R270 S2      
017m9035            VIA   -    M      A18X+066600Y+047384X0260Y    R270 S2      
017m9035                  -    MD0100PA00X+066600Y+047384                       
317m9035            VIA   -    MD0100PA00X+071469Y+046552X0180Y    R090 S0      
327m9036            R992  -1          A18X+067558Y+045386X0198Y0197     S2      
327m9036            VIA   -    M      A18X+068604Y+045030X0260Y    R090 S2      
327m9036            U18   -E11        A01X+070993Y+045139X0160Y    R090 S1      
317m9036            VIA   -    MD0100PA00X+070840Y+044985X0180Y    R090 S0      
317m9037            VIA   -    MD0100PA00X+095095Y+028466X0200Y         S0      
327m9037            U218  -2          A01X+099268Y+042463X0220Y0320R270 S1      
317m9037            VIA   -    MD0100PA00X+098819Y+042463X0200Y         S0      
317m9037            VIA   -    MD0100PA00X+065864Y+057389X0200Y         S0      
317m9037            VIA   -    MD0100PA00X+096628Y+055674X0200Y         S0      
327m9037            R993  -1   M      A18X+065951Y+045388X0198Y0197     S2      
327m9037            R992  -2          A18X+067242Y+045386X0198Y0197     S2      
317m9037            VIA   -    MD0100PA00X+063545Y+044980X0200Y         S0      
317m9037            VIA   -    M      A01X+146668Y+007859X0200Y    R270 S2      
017m9037            VIA   -    M      A18X+146668Y+007859X0260Y    R270 S2      
017m9037                  -    MD0100PA00X+146668Y+007859                       
327m9037            U104  -2          A01X+144537Y+005667X0220Y0320R270 S1      
317m9038            VIA   -    MD0100PA00X+115220Y+166963X0200Y         S0      
327m9038            R3515 -2          A01X+016274Y+170742X0198Y0197R270 S1      
317m9038            VIA   -    MD0100PA00X+016274Y+170488X0200Y         S0      
317m9038            VIA   -    MD0100PA00X+015408Y+145601X0200Y         S0      
317m9038            J105  -N2   D0142PA00X+157776Y+167201X0302Y    R180 S3      
317m9038            VIA   -    MD0100PA00X+113148Y+148543X0200Y         S0      
317m9038            VIA   -    M      A01X+068435Y+144891X0200Y         S2      
017m9038            VIA   -    M      A18X+068435Y+144891X0260Y         S2      
017m9038                  -    MD0100PA00X+068435Y+144891                       
317m9039            VIA   -    M      A01X+016274Y+171317X0200Y         S2      
017m9039            VIA   -    M      A18X+016274Y+171317X0260Y         S2      
017m9039                  -    MD0100PA00X+016274Y+171317                       
327m9039            R2932 -1          A01X+015474Y+171058X0198Y0197R270 S1      
327m9039            R2914 -2   M      A01X+015874Y+171058X0198Y0197R090 S1      
327m9039            U256  -4          A01X+016274Y+171594X0160Y0200R270 S1      
327m9039            R3515 -1   M      A01X+016274Y+171058X0198Y0197R270 S1      
327m9040            R2261 -1          A01X+077150Y+039329X0198Y0197R090 S1      
317m9040            VIA   -    MD0100PA00X+077151Y+039086X0200Y    R090 S0      
317m9040            VIA   -    MD0100PA00X+077196Y+033972X0200Y         S0      
317m9040            VIA   -    MD0100PA00X+043328Y+047197X0200Y         S0      
317m9040            VIA   -    MD0100PA00X+064092Y+036034X0200Y         S0      
327m9040            U256  -3          A01X+015526Y+171594X0160Y0200R270 S1      
327m9040            R2918 -1   M      A01X+014990Y+171594X0198Y0197R270 S1      
327m9040            R2910 -2          A01X+014990Y+171979X0198Y0197R270 S1      
317m9040            VIA   -    M      A01X+015260Y+171594X0200Y         S2      
017m9040            VIA   -    M      A18X+015260Y+171594X0260Y         S2      
017m9040                  -    MD0100PA00X+015260Y+171594                       
327FM_SWB_PWRGD_N   R2841 -2          A18X+139690Y+165443X0198Y0197R090 S2      
327FM_SWB_PWRGD_N   VIA   -    M      A18X+139010Y+164507X0260Y    R270 S2      
327FM_SWB_PWRGD_N   Q71   -5          A18X+139494Y+164424X0170Y0200R270 S2      
327FM_SWB_PWRGD_N   Q71   -6   M      A18X+139494Y+164680X0170Y0200R270 S2      
327m9041            VIA   -    M      A18X+141562Y+163101X0260Y         S2      
327m9041            Q71   -3          A18X+140242Y+164168X0170Y0200R270 S2      
327m9041            R2934 -2   M      A18X+141117Y+164140X0198Y0197R180 S2      
327m9041            C1774 -1   M      A18X+141509Y+164143X0198Y0197R180 S2      
317m9041            VIA   -    MD0100PA00X+081800Y+049622X0200Y         S0      
327m9041            R2663 -2          A01X+080958Y+049134X0198Y0197     S1      
317m9041            VIA   -    MD0100PA00X+078567Y+034228X0200Y         S0      
317m9041            VIA   -    MD0100PA00X+140667Y+161633X0200Y         S0      
317FM_SWB_PWRGD     VIA   -    MD0100PA00X+145880Y+168708X0200Y         S0      
317FM_SWB_PWRGD     VIA   -    M      A01X+141876Y+165500X0200Y    R090 S2      
017FM_SWB_PWRGD     VIA   -    M      A18X+141876Y+165500X0260Y    R090 S2      
017FM_SWB_PWRGD           -    MD0100PA00X+141876Y+165500                       
317FM_SWB_PWRGD     J106  -A3   D0142PA00X+151870Y+173421X0302Y    R180 S3      
327FM_SWB_PWRGD     Q71   -2          A18X+140242Y+164424X0170Y0200R270 S2      
327FM_SWB_PWRGD     R2837 -2   M      A18X+140996Y+164972X0198Y0197R180 S2      
327FM_SWB_PWRGD     R2838 -1   M      A18X+141394Y+164972X0198Y0197R180 S2      
317m9042            J105  -N4   D0142PA00X+159350Y+167201X0302Y    R180 S3      
327m9042            Q70   -2          A01X+169802Y+171432X0170Y0200R090 S1      
327m9042            R2832 -2   M      A01X+168951Y+171561X0198Y0197R270 S1      
327m9042            R2833 -1   M      A01X+168551Y+171561X0198Y0197R090 S1      
317m9042            VIA   -    M      A01X+168003Y+171561X0200Y         S2      
017m9042            VIA   -    M      A18X+168003Y+171561X0260Y         S2      
017m9042                  -    MD0100PA00X+168003Y+171561                       
327m9043            Q70   -3          A01X+169802Y+171176X0170Y0200R090 S1      
327m9043            C1754 -1   M      A01X+168951Y+171176X0198Y0197R270 S1      
317m9043            VIA   -    M      A01X+168003Y+171061X0200Y         S2      
017m9043            VIA   -    M      A18X+168003Y+171061X0260Y         S2      
017m9043                  -    MD0100PA00X+168003Y+171061                       
327m9043            R2933 -2   M      A01X+168551Y+171176X0198Y0197R090 S1      
317m9043            VIA   -    MD0100PA00X+081739Y+049159X0200Y    R180 S0      
327m9043            R2844 -2          A01X+080951Y+048734X0198Y0197     S1      
327m9044            VIA   -    M      A01X+171036Y+171688X0300Y    R270 S1      
327m9044            R2836 -2          A01X+171036Y+171208X0198Y0197R090 S1      
327m9044            Q70   -5          A01X+170550Y+171432X0170Y0200R090 S1      
327m9044            Q70   -6   M      A01X+170550Y+171688X0170Y0200R090 S1      
327m9045            VIA   -    M      A18X+075956Y+049155X0260Y         S2      
327m9045            U18   -U19        A01X+074772Y+047659X0160Y    R090 S1      
317m9045            VIA   -    MD0100PA00X+074926Y+047812X0180Y    R090 S0      
327m9045            R395  -1          A18X+076065Y+049777X0198Y0197R270 S2      
327m9046            SW1   -11         A01X+169910Y+016676X0300Y0500R270 S1      
327m9046            R1261 -2          A18X+169050Y+016676X0198Y0197R180 S2      
317m9046            VIA   -    M      A01X+169510Y+016676X0200Y    R090 S2      
017m9046            VIA   -    M      A18X+169510Y+016676X0260Y    R090 S2      
017m9046                  -    MD0100PA00X+169510Y+016676                       
317m9046            VIA   -    MD0100PA00X+105187Y+030548X0200Y         S0      
317m9046            VIA   -    MD0100PA00X+104084Y+051089X0200Y         S0      
327m9046            R395  -2          A18X+076065Y+050092X0198Y0197R270 S2      
317m9046            VIA   -    MD0100PA00X+077634Y+054573X0200Y         S0      
327m9047            J41   -OB14       A01X+072150Y+006516X0150Y0570R180 S1      
317m9047            VIA   -    M      A01X+071432Y+005629X0200Y         S2      
017m9047            VIA   -    M      A18X+071432Y+005629X0260Y         S2      
017m9047                  -    MD0100PA00X+071432Y+005629                       
327m9047            R3778 -1          A18X+070930Y+005629X0198Y0197R090 S2      
317m9048            VIA   -    M      A01X+070567Y+004801X0200Y         S2      
017m9048            VIA   -    M      A18X+070567Y+004801X0260Y         S2      
017m9048                  -    MD0100PA00X+070567Y+004801                       
327m9048            R3778 -2          A18X+070930Y+005314X0198Y0197R090 S2      
327m9048            U18   -B20        A01X+070048Y+047974X0160Y    R090 S1      
317m9048            VIA   -    MD0100PA00X+069895Y+048127X0180Y    R090 S0      
327m9049            VIA   -    M      A01X+072850Y+050001X0300Y         S1      
327m9049            R933  -1          A01X+072850Y+050779X0198Y0197R090 S1      
327m9049            U18   -M22        A01X+073198Y+048604X0160Y    R090 S1      
317FM_SMERR_LED_N   VIA   -    MD0100PA00X+090334Y+050510X0200Y         S0      
317FM_SMERR_LED_N   VIA   -    MD0100PA00X+091075Y+028614X0200Y         S0      
317FM_SMERR_LED_N   VIA   -    MD0100PA00X+072850Y+051336X0200Y    R180 S0      
327FM_SMERR_LED_N   R933  -2          A01X+072850Y+051094X0198Y0197R090 S1      
317FM_SMERR_LED_N   VIA   -    MD0100PA00X+078745Y+049534X0200Y         S0      
317FM_SMERR_LED_N   VIA   -    MD0100PA00X+081319Y+049836X0200Y         S0      
327FM_SMERR_LED_N   U86   -2          A01X+136437Y+011620X0220Y0530R180 S1      
317FM_SMERR_LED_N   VIA   -    M      A01X+136437Y+012038X0200Y    R180 S2      
017FM_SMERR_LED_N   VIA   -    M      A18X+136437Y+012038X0260Y    R180 S2      
017FM_SMERR_LED_N         -    MD0100PA00X+136437Y+012038                       
327m9050            Q11   -2          A01X+135431Y+008282X0170Y0200     S1      
327m9050            VIA   -    M      A01X+135331Y+008768X0300Y         S1      
327m9050            R936  -2          A01X+135620Y+009248X0198Y0197R270 S1      
327m9050            R945  -2   M      A01X+135220Y+009248X0198Y0197R270 S1      
327m9051            R936  -1          A01X+135620Y+009562X0198Y0197R270 S1      
327m9051            VIA   -    M      A01X+135620Y+010042X0300Y    R180 S1      
327m9051            U86   -4          A01X+136063Y+010656X0220Y0530R180 S1      
327m9052            VIA   -    M      A01X+073950Y+038350X0300Y    R090 S1      
327m9052            U18   -P2         A01X+073828Y+042304X0160Y    R090 S1      
327m9052            R1303 -1          A01X+074350Y+037994X0198Y0197R270 S1      
327m9052            R1036 -1   M      A01X+073950Y+037994X0198Y0197R270 S1      
327m9053            Q74   -2          A18X+042000Y+164674X0170Y0200     S2      
327m9053            R3032 -1   M      A18X+041708Y+165350X0198Y0197     S2      
327m9053            R3514 -2   M      A18X+041708Y+165750X0198Y0197R180 S2      
327m9053            VIA   -    M      A18X+042150Y+165750X0260Y         S2      
317m9053            J110  -N6   D0142PA00X+053445Y+167201X0302Y    R180 S3      
317m9054            VIA   -    MD0100PA00X+079740Y+048746X0200Y         S0      
327m9054            R11667-2          A01X+077823Y+048734X0198Y0197     S1      
317m9054            VIA   -    MD0100PA00X+079436Y+056000X0200Y         S0      
317m9054            VIA   -    M      A01X+043200Y+165000X0200Y         S2      
017m9054            VIA   -    M      A18X+043200Y+165000X0260Y         S2      
017m9054                  -    MD0100PA00X+043200Y+165000                       
327m9054            Q74   -3          A18X+042256Y+164674X0170Y0200     S2      
327m9054            R3035 -2   M      A18X+043200Y+164658X0198Y0197R270 S2      
327m9054            C1804 -1   M      A18X+042800Y+164658X0198Y0197R090 S2      
317m9054            VIA   -    MD0100PA00X+039645Y+157774X0200Y         S0      
317m9054            VIA   -    MD0100PA00X+009089Y+165475X0200Y         S0      
327m9055            R3034 -2          A18X+040850Y+164642X0198Y0197R090 S2      
327m9055            VIA   -    M      A18X+040899Y+164229X0260Y         S2      
327m9055            Q74   -6   M      A18X+041744Y+163926X0170Y0200     S2      
327m9055            Q74   -5          A18X+042000Y+163926X0170Y0200     S2      
317m9056            VIA   -    M      A01X+045950Y+165900X0200Y         S2      
017m9056            VIA   -    M      A18X+045950Y+165900X0260Y         S2      
017m9056                  -    MD0100PA00X+045950Y+165900                       
317m9056            J110  -N4   D0142PA00X+051870Y+167201X0302Y    R180 S3      
327m9056            R3510 -2   M      A01X+044758Y+164441X0198Y0197R270 S1      
327m9056            R3028 -1   M      A01X+045308Y+164386X0198Y0197R090 S1      
327m9056            Q75   -2          A01X+045724Y+163500X0170Y0200R270 S1      
317m9057            VIA   -    MD0100PA00X+081298Y+047134X0200Y    R180 S0      
327m9057            R3066 -2          A01X+080951Y+047134X0198Y0197     S1      
317m9057            VIA   -    MD0100PA00X+081575Y+064422X0200Y         S0      
317m9057            VIA   -    M      A01X+086539Y+080124X0200Y         S2      
017m9057            VIA   -    M      A18X+086539Y+080124X0260Y         S2      
017m9057                  -    MD0100PA00X+086539Y+080124                       
317m9057            VIA   -    MD0100PA00X+070111Y+164034X0200Y         S0      
327m9057            C1802 -1   M      A01X+046100Y+164392X0198Y0197R090 S1      
327m9057            R3030 -2   M      A01X+045700Y+164392X0198Y0197R270 S1      
327m9057            Q75   -3          A01X+045724Y+163756X0170Y0200R270 S1      
317m9057            VIA   -    MD0100PA00X+046275Y+164129X0200Y         S0      
327m9058            VIA   -    M      A01X+044359Y+164085X0300Y         S1      
327m9058            R3029 -2          A01X+044359Y+164445X0198Y0197R270 S1      
327m9058            Q75   -5   M      A01X+044976Y+163500X0170Y0200R270 S1      
327m9058            Q75   -6          A01X+044976Y+163244X0170Y0200R270 S1      
327m9059            R1856 -2          A01X+074881Y+014205X0198Y0197     S1      
327m9059            Q39   -G          A01X+075929Y+014344X0320Y0360     S1      
327m9059            VIA   -    M      A01X+075360Y+014344X0300Y         S1      
327m9060            J41   -A57        A01X+054152Y+005354X0150Y0570R180 S1      
317m9060            VIA   -    M      A01X+074305Y+013918X0200Y         S2      
017m9060            VIA   -    M      A18X+074305Y+013918X0260Y         S2      
017m9060                  -    MD0100PA00X+074305Y+013918                       
317m9060            VIA   -    MD0100PA00X+058368Y+007068X0200Y         S0      
317m9060            VIA   -    MD0100PA00X+067974Y+021776X0200Y         S0      
327m9060            U18   -M2         A01X+073198Y+042304X0160Y    R090 S1      
317m9060            VIA   -    MD0100PA00X+073351Y+042151X0180Y    R090 S0      
327m9060            R1856 -1          A01X+074566Y+014205X0198Y0197     S1      
327m9060            R1854 -2   M      A01X+074567Y+013786X0198Y0197R180 S1      
327m9061            VIA   -           A01X+078324Y+046152X0300Y         S1      
327m9061            U18   -AB13       A01X+076347Y+045769X0160Y    R090 S1      
327m9061            R957  -1   M      A01X+077508Y+045934X0198Y0197     S1      
327m9062            J41   -A51        A01X+055570Y+005354X0150Y0570R180 S1      
317m9062            VIA   -    M      A01X+061868Y+051130X0200Y         S2      
017m9062            VIA   -    M      A18X+061868Y+051130X0260Y         S2      
017m9062                  -    MD0100PA00X+061868Y+051130                       
317m9062            VIA   -    MD0100PA00X+055498Y+004531X0200Y         S0      
317m9062            VIA   -    MD0100PA00X+055159Y+044366X0200Y         S0      
327m9062            R957  -2          A01X+077823Y+045934X0198Y0197     S1      
317m9062            VIA   -    MD0100PA00X+078098Y+045952X0200Y    R180 S0      
317m9062            VIA   -    MD0100PA00X+077496Y+051420X0200Y         S0      
327m9063            VIA   -    M      A01X+071650Y+050301X0300Y         S1      
327m9063            R57   -2          A01X+071650Y+050779X0198Y0197R270 S1      
327m9063            U18   -H21        A01X+071938Y+048288X0160Y    R090 S1      
327m9064            U18   -H22        A01X+071938Y+048604X0160Y    R090 S1      
327m9064            VIA   -    M      A01X+072050Y+050001X0300Y         S1      
327m9064            R241  -2          A01X+072050Y+050779X0198Y0197R270 S1      
327m9065            R1616 -1          A18X+076850Y+054029X0198Y0197R270 S2      
327m9065            U18   -W21        A01X+075402Y+048288X0160Y    R090 S1      
317m9065            VIA   -    MD0100PA00X+075556Y+048442X0180Y    R090 S0      
327m9065            VIA   -    M      A18X+075840Y+050677X0260Y    R090 S2      
327FM_ROM_LS_EN     VIA   -    M      A01X+076150Y+050301X0300Y         S1      
327FM_ROM_LS_EN     R1564 -1          A01X+076050Y+050779X0198Y0197R090 S1      
327FM_ROM_LS_EN     U18   -Y22        A01X+075717Y+048604X0160Y    R090 S1      
317m9066            VIA   -    MD0100PA00X+077004Y+044683X0200Y         S2      
327m9066            R283  -2          A01X+077508Y+044734X0198Y0197R180 S1      
327m9066            U18   -AB9        A01X+076347Y+044509X0160Y    R090 S1      
327m9067            VIA   -    M      A18X+077128Y+041306X0260Y    R270 S2      
327m9067            U18   -U6         A01X+074772Y+043564X0160Y    R090 S1      
317m9067            VIA   -    MD0100PA00X+074926Y+043411X0180Y    R090 S0      
327m9067            R230  -2          A18X+077608Y+041134X0198Y0197     S2      
327m9068            R286  -2          A18X+077508Y+042734X0198Y0197     S2      
327m9068            VIA   -    M      A18X+076177Y+043955X0260Y    R090 S2      
327m9068            U18   -T8         A01X+074458Y+044194X0160Y    R090 S1      
317m9068            VIA   -    MD0100PA00X+074611Y+044040X0180Y    R090 S0      
327m9069            VIA   -    M      A18X+077025Y+040746X0260Y    R270 S2      
327m9069            U18   -R7         A01X+074143Y+043879X0160Y    R090 S1      
317m9069            VIA   -    MD0100PA00X+074296Y+043726X0180Y    R090 S0      
327m9069            R233  -2          A18X+077608Y+040734X0198Y0197     S2      
317m9070            VIA   -    MD0100PA00X+078688Y+042734X0200Y    R180 S2      
327m9070            U18   -Y5         A01X+075717Y+043249X0160Y    R090 S1      
317m9070            VIA   -    MD0100PA00X+075871Y+043096X0180Y    R090 S0      
327m9070            R209  -2          A01X+078953Y+042734X0198Y0197R180 S1      
317m9071            VIA   -    MD0100PA00X+077053Y+042346X0200Y         S2      
327m9071            C5002 -1          A01X+077509Y+041946X0198Y0197     S1      
327m9071            U18   -AB6        A01X+076347Y+043564X0160Y    R090 S1      
327m9071            R225  -2   M      A01X+077508Y+042334X0198Y0197R180 S1      
327m9072            VIA   -    M      A01X+078374Y+044110X0300Y         S1      
327m9072            C5001 -1          A01X+078958Y+043934X0198Y0197     S1      
327m9072            R177  -2   M      A01X+077508Y+043934X0198Y0197R180 S1      
327m9072            U18   -AB8        A01X+076347Y+044194X0160Y    R090 S1      
317m9073            VIA   -    MD0100PA00X+077261Y+043469X0200Y         S2      
327m9073            R280  -2          A01X+077508Y+043134X0198Y0197R180 S1      
327m9073            U18   -AB7        A01X+076347Y+043879X0160Y    R090 S1      
327m9074            R228  -2          A01X+078953Y+041934X0198Y0197R180 S1      
317m9074            VIA   -    MD0100PA00X+078592Y+041919X0200Y    R180 S0      
327m9074            U18   -Y4         A01X+075717Y+042934X0160Y    R090 S1      
317m9074            VIA   -    MD0100PA00X+075871Y+042781X0180Y    R090 S2      
327m9075            R203  -2          A18X+071134Y+052226X0198Y0197R090 S2      
327m9075            U18   -J18        A01X+072253Y+047344X0160Y    R090 S1      
327m9075            VIA   -    M      A18X+071481Y+049392X0260Y    R090 S2      
317m9075            VIA   -    MD0100PA00X+072099Y+047497X0180Y    R090 S0      
327m9076            R242  -2          A18X+070865Y+049777X0198Y0197R090 S2      
327m9076            U18   -H19        A01X+071938Y+047659X0160Y    R090 S1      
317m9076            VIA   -    MD0100PA00X+071784Y+047812X0180Y    R090 S0      
327m9076            VIA   -    M      A18X+070993Y+049079X0260Y    R090 S2      
317m9077            VIA   -    MD0100PA00X+077092Y+044251X0200Y         S2      
327m9077            U18   -AA9        A01X+076032Y+044509X0160Y    R090 S1      
327m9077            R282  -2          A01X+077508Y+044334X0198Y0197R180 S1      
327m9078            VIA   -    M      A18X+077163Y+041858X0260Y         S2      
327m9078            R229  -2          A18X+077608Y+041534X0198Y0197     S2      
327m9078            U18   -V6         A01X+075087Y+043564X0160Y    R090 S1      
317m9078            VIA   -    MD0100PA00X+075241Y+043411X0180Y    R090 S0      
327m9079            R285  -1          A18X+077508Y+042334X0198Y0197R180 S2      
327m9079            VIA   -    M      A18X+076445Y+043373X0260Y    R090 S2      
327m9079            U18   -T7         A01X+074458Y+043879X0160Y    R090 S1      
317m9079            VIA   -    MD0100PA00X+074611Y+043726X0180Y    R090 S0      
317m9080            VIA   -    MD0100PA00X+071469Y+042781X0180Y    R090 S0      
327m9080            U18   -G4         A01X+071623Y+042934X0160Y    R090 S1      
327m9080            R141  -2          A18X+070350Y+039644X0198Y0197R270 S2      
317m9080            VIA   -    M      A01X+070350Y+040129X0200Y         S2      
017m9080            VIA   -    M      A18X+070350Y+040129X0260Y         S2      
017m9080                  -    MD0100PA00X+070350Y+040129                       
317m9081            VIA   -    M      A01X+084600Y+042336X0200Y         S2      
017m9081            VIA   -    M      A18X+084600Y+042336X0260Y         S2      
017m9081                  -    MD0100PA00X+084600Y+042336                       
327m9081            R8235 -1          A18X+009592Y+143550X0198Y0197R180 S2      
317m9081            VIA   -    MD0100PA00X+008510Y+143305X0200Y         S0      
327m9081            R285  -2          A18X+077823Y+042334X0198Y0197R180 S2      
317m9081            VIA   -    MD0100PA00X+083775Y+033534X0200Y         S0      
317m9081            VIA   -    MD0100PA00X+044230Y+047444X0200Y         S0      
317m9081            VIA   -    MD0100PA00X+063900Y+036486X0200Y         S0      
327m9082            VIA   -    M      A18X+074076Y+041475X0260Y         S2      
327m9082            R232  -2          A18X+074350Y+039644X0198Y0197R270 S2      
327m9082            U18   -P7         A01X+073828Y+043879X0160Y    R090 S1      
317m9082            VIA   -    MD0100PA00X+073981Y+043726X0180Y    R090 S0      
327m9083            VIA   -    M      A18X+070949Y+039948X0260Y    R090 S2      
327m9083            R137  -2          A18X+070750Y+039644X0198Y0197R270 S2      
327m9083            U18   -G3         A01X+071623Y+042619X0160Y    R090 S1      
317m9083            VIA   -    MD0100PA00X+071469Y+042466X0180Y    R090 S0      
317m9084            VIA   -    MD0100PA00X+119100Y+142590X0200Y         S0      
317m9084            VIA   -    M      A01X+129600Y+142770X0200Y         S2      
017m9084            VIA   -    M      A18X+129600Y+142770X0260Y         S2      
017m9084                  -    MD0100PA00X+129600Y+142770                       
317m9084            VIA   -    MD0100PA00X+076830Y+037436X0200Y         S0      
317m9084            VIA   -    MD0100PA00X+151594Y+048441X0200Y         S0      
327m9084            R232  -1          A18X+074350Y+039329X0198Y0197R270 S2      
327m9084            R8058 -1          A18X+119692Y+142400X0198Y0197R180 S2      
317m9085            VIA   -    M      A01X+078377Y+042245X0200Y    R180 S2      
017m9085            VIA   -    M      A18X+078377Y+042245X0260Y    R180 S2      
017m9085                  -    MD0100PA00X+078377Y+042245                       
327m9085            R208  -2          A01X+078953Y+042334X0198Y0197R180 S1      
327m9085            U18   -W5         A01X+075402Y+043249X0160Y    R090 S1      
317m9085            VIA   -    MD0100PA00X+075556Y+043096X0180Y    R090 S0      
327m9086            VIA   -    M      A01X+071950Y+040606X0300Y         S1      
327m9086            R284  -1          A01X+071950Y+039644X0198Y0197R270 S1      
327m9086            U18   -G2         A01X+071623Y+042304X0160Y    R090 S1      
327m9087            VIA   -    M      A01X+071550Y+040138X0300Y         S1      
327m9087            U18   -F1         A01X+071308Y+041989X0160Y    R090 S1      
327m9087            R231  -2          A01X+071550Y+039644X0198Y0197R090 S1      
327m9088            R224  -2          A18X+077968Y+043850X0198Y0197     S2      
327m9088            VIA   -    M      A18X+077566Y+043908X0260Y    R090 S2      
327m9088            U18   -V9         A01X+075087Y+044509X0160Y    R090 S1      
317m9088            VIA   -    MD0100PA00X+075241Y+044356X0180Y    R090 S0      
317m9089            VIA   -    MD0100PA00X+076830Y+043822X0200Y         S2      
327m9089            U18   -AA8        A01X+076032Y+044194X0160Y    R090 S1      
327m9089            R176  -2          A01X+077508Y+043534X0198Y0197R180 S1      
327m9090            R278  -1          A18X+071150Y+039644X0198Y0197R090 S2      
327m9090            VIA   -    M      A18X+071270Y+041220X0260Y    R090 S2      
327m9090            U18   -H4         A01X+071938Y+042934X0160Y    R090 S1      
317m9090            VIA   -    MD0100PA00X+071784Y+042781X0180Y    R090 S0      
317m9091            VIA   -    M      A01X+076965Y+043051X0200Y         S2      
017m9091            VIA   -    M      A18X+076965Y+043051X0260Y         S2      
017m9091                  -    MD0100PA00X+076965Y+043051                       
327m9091            R279  -2          A01X+077508Y+042734X0198Y0197R180 S1      
327m9091            U18   -AA7        A01X+076032Y+043879X0160Y    R090 S1      
327m9092            VIA   -    M      A18X+071499Y+040646X0260Y    R090 S2      
327m9092            R226  -1          A18X+071550Y+039644X0198Y0197R090 S2      
327m9092            U18   -H3         A01X+071938Y+042619X0160Y    R090 S1      
317m9092            VIA   -    MD0100PA00X+071784Y+042466X0180Y    R090 S0      
317m9093            VIA   -    M      A01X+078270Y+041528X0200Y    R180 S2      
017m9093            VIA   -    M      A18X+078270Y+041528X0260Y    R180 S2      
017m9093                  -    MD0100PA00X+078270Y+041528                       
327m9093            U18   -W4         A01X+075402Y+042934X0160Y    R090 S1      
317m9093            VIA   -    MD0100PA00X+075556Y+042781X0180Y    R090 S0      
327m9093            R227  -1          A01X+078953Y+041534X0198Y0197     S1      
317m9094            VIA   -    M      A01X+076350Y+038686X0300Y    R090 S1      
017m9094            VIA   -    M      A18X+076350Y+038686X0200Y    R090 S1      
017m9094                  -    MD0100PA00X+076350Y+038686                       
327m9094            R271  -1          A01X+076350Y+037994X0198Y0197R270 S1      
327m9094            U18   -V5         A01X+075087Y+043249X0160Y    R090 S1      
317m9094            VIA   -    MD0100PA00X+075241Y+043096X0180Y    R090 S0      
327m9095            SW1   -18         A01X+169910Y+013176X0300Y0500R270 S1      
317m9095            VIA   -    M      A01X+169510Y+013176X0200Y    R090 S2      
017m9095            VIA   -    M      A18X+169510Y+013176X0260Y    R090 S2      
017m9095                  -    MD0100PA00X+169510Y+013176                       
327m9095            R744  -2          A18X+168085Y+013176X0198Y0197R180 S2      
327m9095            R1357 -2   M      A18X+169050Y+013176X0198Y0197R180 S2      
327m9095            R271  -2          A01X+076350Y+037679X0198Y0197R270 S1      
317m9095            VIA   -    MD0100PA00X+076630Y+037286X0200Y         S0      
317m9095            VIA   -    MD0100PA00X+077212Y+033354X0200Y         S0      
327m9096            VIA   -    M      A01X+076160Y+040606X0300Y         S1      
327m9096            R182  -1          A01X+076750Y+039644X0198Y0197R270 S1      
327m9096            U18   -V1         A01X+075087Y+041989X0160Y    R090 S1      
327m9097            SW1   -17         A01X+169910Y+013676X0300Y0500R270 S1      
317m9097            VIA   -    M      A01X+169510Y+013676X0200Y    R090 S2      
017m9097            VIA   -    M      A18X+169510Y+013676X0260Y    R090 S2      
017m9097                  -    MD0100PA00X+169510Y+013676                       
327m9097            R734  -2          A18X+168085Y+013676X0198Y0197R180 S2      
327m9097            R1356 -2   M      A18X+169050Y+013676X0198Y0197R180 S2      
317m9097            VIA   -    MD0100PA00X+076813Y+033536X0200Y         S0      
317m9097            VIA   -    MD0100PA00X+076750Y+039086X0200Y    R090 S0      
327m9097            R182  -2          A01X+076750Y+039329X0198Y0197R270 S1      
327m9098            R1282 -2          A18X+077403Y+044656X0198Y0197     S2      
327m9098            U18   -W10        A01X+075402Y+044824X0160Y    R090 S1      
317m9098            VIA   -    MD0100PA00X+075556Y+044670X0180Y    R090 S0      
327m9098            VIA   -    M      A18X+076132Y+044934X0260Y    R090 S2      
327m9099            VIA   -    M      A18X+072514Y+040646X0260Y    R090 S2      
327m9099            U18   -M7         A01X+073198Y+043879X0160Y    R090 S1      
317m9099            VIA   -    MD0100PA00X+073351Y+043726X0180Y    R090 S0      
327m9099            R959  -2          A18X+072350Y+039644X0198Y0197R270 S2      
327m9100            VIA   -    M      A18X+073029Y+041207X0260Y         S2      
327m9100            R958  -2          A18X+073150Y+039644X0198Y0197R270 S2      
327m9100            U18   -M6         A01X+073198Y+043564X0160Y    R090 S1      
317m9100            VIA   -    MD0100PA00X+073351Y+043411X0180Y    R090 S0      
317m9101            VIA   -    MD0100PA00X+085665Y+061679X0200Y         S0      
317m9101            VIA   -    MD0100PA00X+092564Y+061662X0200Y         S0      
327m9101            U14   -3          A01X+093146Y+061669X0140Y0520R090 S1      
327m9101            R1650 -2          A01X+086406Y+051911X0198Y0197R090 S1      
327m9101            Q64   -D   M      A01X+086385Y+053458X0400Y0560R270 S1      
327m9101            U154  -3          A01X+093146Y+063119X0140Y0520R090 S1      
317m9101            VIA   -    M      A01X+093578Y+063119X0200Y    R180 S2      
017m9101            VIA   -    M      A18X+093578Y+063119X0260Y    R180 S2      
017m9101                  -    MD0100PA00X+093578Y+063119                       
317m9102            VIA   -    M      A01X+075680Y+051705X0200Y    R180 S2      
017m9102            VIA   -    M      A18X+075680Y+051705X0260Y    R180 S2      
017m9102                  -    MD0100PA00X+075680Y+051705                       
327m9102            R173  -1          A01X+075650Y+052429X0198Y0197R090 S1      
327m9102            U18   -R17        A01X+074143Y+047029X0160Y    R090 S1      
317m9102            VIA   -    MD0100PA00X+074296Y+047182X0180Y    R090 S0      
317m9103            VIA   -    M      A01X+092645Y+057781X0200Y         S2      
017m9103            VIA   -    M      A18X+092645Y+057781X0260Y         S2      
017m9103                  -    MD0100PA00X+092645Y+057781                       
317m9103            VIA   -    MD0100PA00X+093577Y+058769X0200Y         S0      
327m9103            R1647 -2   M      A01X+092645Y+057070X0198Y0197R180 S1      
327m9103            Q63   -D          A01X+092863Y+055829X0400Y0560R270 S1      
327m9103            U13   -3          A01X+093146Y+060219X0140Y0520R090 S1      
327m9103            U153  -3   M      A01X+093146Y+058769X0140Y0520R090 S1      
327m9104            R158  -1          A18X+075665Y+049777X0198Y0197R270 S2      
327m9104            U18   -U18        A01X+074772Y+047344X0160Y    R090 S1      
327m9104            VIA   -    M      A18X+075532Y+048716X0260Y    R090 S2      
317m9104            VIA   -    MD0100PA00X+074926Y+047497X0180Y    R090 S0      
317m9105            VIA   -    MD0080PA00X+142663Y+115561X0160Y         S0      
327m9105            R1205 -1          A01X+145333Y+127192X0198Y0197R090 S1      
327m9105            U25   -DF36       A01X+142480Y+115457X0177Y    R180 S1      
327m9105            VIA   -    M      A01X+145531Y+126729X0300Y    R180 S1      
317m9105            VIA   -    MD0100PA00X+141898Y+117514X0200Y    R180 S0      
327m9106            SW1   -19         A01X+169910Y+012676X0300Y0500R270 S1      
327m9106            R1205 -2          A01X+145333Y+127507X0198Y0197R090 S1      
327m9106            R6106 -2          A18X+169050Y+012276X0198Y0197R180 S2      
327m9106            R1358 -2   M      A18X+169050Y+012676X0198Y0197R180 S2      
317m9106            VIA   -    MD0100PA00X+169510Y+012676X0200Y    R090 S0      
317m9106            VIA   -    M      A01X+159762Y+136538X0200Y         S2      
017m9106            VIA   -    M      A18X+159762Y+136538X0260Y         S2      
017m9106                  -    MD0100PA00X+159762Y+136538                       
327FM_P1_PCC1_R_N   R1279 -2          A01X+071952Y+052426X0198Y0197R270 S1      
317FM_P1_PCC1_R_N   VIA   -    M      A01X+072040Y+051744X0300Y    R180 S1      
017FM_P1_PCC1_R_N   VIA   -    M      A18X+072040Y+051744X0200Y    R180 S1      
017FM_P1_PCC1_R_N         -    MD0100PA00X+072040Y+051744                       
327FM_P1_PCC1_R_N   U18   -J20        A01X+072253Y+047974X0160Y    R090 S1      
317FM_P1_PCC1_R_N   VIA   -    MD0100PA00X+072099Y+048127X0180Y    R090 S0      
317FM_P1_PCC1_N     VIA   -    MD0080PA00X+031544Y+115880X0160Y         S0      
327FM_P1_PCC1_N     R1279 -1          A01X+071952Y+052741X0198Y0197R270 S1      
327FM_P1_PCC1_N     U26   -DG72       A01X+031728Y+115776X0177Y    R180 S1      
317FM_P1_PCC1_N     VIA   -    MD0100PA00X+005775Y+080802X0200Y         S0      
317FM_P1_PCC1_N     VIA   -    M      A01X+066569Y+055029X0200Y         S2      
017FM_P1_PCC1_N     VIA   -    M      A18X+066569Y+055029X0260Y         S2      
017FM_P1_PCC1_N           -    MD0100PA00X+066569Y+055029                       
317FM_P1_PCC1_N     VIA   -    MD0100PA00X+011304Y+068628X0200Y         S0      
317FM_P1_PCC1_N     VIA   -    MD0100PA00X+036585Y+051647X0200Y         S0      
317FM_P1_PCC1_N     VIA   -    MD0100PA00X+071984Y+053735X0200Y         S0      
327FM_P1_PCC1_N     R1286 -1          A01X+072050Y+054029X0198Y0197R090 S1      
327FM_P1_PCC0_R_N   R1278 -2          A18X+072065Y+049777X0198Y0197R090 S2      
327FM_P1_PCC0_R_N   U18   -J19        A01X+072253Y+047659X0160Y    R090 S1      
317FM_P1_PCC0_R_N   VIA   -    MD0100PA00X+072099Y+047812X0180Y    R090 S0      
327FM_P1_PCC0_R_N   VIA   -    M      A18X+072065Y+049035X0260Y    R090 S2      
317FM_P1_PCC0_N     VIA   -    MD0080PA00X+049927Y+087962X0160Y    R180 S0      
327FM_P1_PCC0_N     R1285 -1          A18X+071484Y+052535X0198Y0197R270 S2      
327FM_P1_PCC0_N     U26   -C22        A01X+049743Y+088067X0177Y    R180 S1      
317FM_P1_PCC0_N     VIA   -    MD0100PA00X+071650Y+051736X0200Y    R180 S0      
317FM_P1_PCC0_N     VIA   -    MD0100PA00X+069481Y+068019X0200Y         S0      
327FM_P1_PCC0_N     R1278 -1          A18X+072065Y+050092X0198Y0197R090 S2      
317FM_P1_PCC0_N     VIA   -    MD0100PA00X+070020Y+073321X0200Y         S0      
327FM_P1_PCC0_N     VIA   -    M      A18X+058061Y+077645X0260Y    R180 S2      
327FM_P0_PCC1_R_N   U18   -K18        A01X+072568Y+047344X0160Y    R090 S1      
317FM_P0_PCC1_R_N   VIA   -    MD0100PA00X+072414Y+047497X0180Y    R090 S0      
327FM_P0_PCC1_R_N   R1281 -2          A18X+072465Y+049777X0198Y0197R090 S2      
327FM_P0_PCC1_R_N   VIA   -    M      A18X+072570Y+049299X0260Y    R090 S2      
317FM_P0_PCC1_N     VIA   -    MD0080PA00X+129158Y+115880X0160Y         S0      
327FM_P0_PCC1_N     U25   -DG72       A01X+129342Y+115776X0177Y    R180 S1      
317FM_P0_PCC1_N     VIA   -    MD0100PA00X+118271Y+073382X0200Y         S0      
327FM_P0_PCC1_N     VIA   -    M      A18X+123018Y+080116X0260Y    R180 S2      
327FM_P0_PCC1_N     R1281 -1          A18X+072465Y+050092X0198Y0197R090 S2      
317FM_P0_PCC1_N     VIA   -    MD0100PA00X+072450Y+052186X0200Y    R180 S0      
317FM_P0_PCC1_N     VIA   -    MD0100PA00X+078365Y+063167X0200Y         S0      
317FM_P0_PCC1_N     VIA   -    MD0100PA00X+111844Y+062531X0200Y         S0      
327FM_P0_PCC1_N     R1288 -1          A18X+072191Y+052518X0198Y0197R270 S2      
317FM_P0_PCC0_R_N   VIA   -    MD0100PA00X+072434Y+053753X0200Y         S0      
327FM_P0_PCC0_R_N   U18   -K17        A01X+072568Y+047029X0160Y    R090 S1      
317FM_P0_PCC0_R_N   VIA   -    MD0100PA00X+072414Y+047182X0180Y    R090 S2      
327FM_P0_PCC0_R_N   R1280 -2          A01X+072450Y+054029X0198Y0197R270 S1      
317FM_P0_PCC0_N     VIA   -    MD0080PA00X+147541Y+087962X0160Y    R180 S0      
327FM_P0_PCC0_N     U25   -C22        A01X+147358Y+088067X0177Y    R180 S1      
317FM_P0_PCC0_N     VIA   -    MD0100PA00X+147373Y+081355X0200Y    R180 S0      
317FM_P0_PCC0_N     VIA   -    M      A01X+072725Y+061069X0200Y         S2      
017FM_P0_PCC0_N     VIA   -    M      A18X+072725Y+061069X0260Y         S2      
017FM_P0_PCC0_N           -    MD0100PA00X+072725Y+061069                       
317FM_P0_PCC0_N     VIA   -    MD0100PA00X+083506Y+066094X0200Y         S0      
317FM_P0_PCC0_N     VIA   -    MD0100PA00X+072468Y+054586X0200Y    R180 S0      
327FM_P0_PCC0_N     R1280 -1          A01X+072450Y+054344X0198Y0197R270 S1      
327FM_P0_PCC0_N     R1287 -1          A01X+072050Y+055029X0198Y0197R090 S1      
327m9107            R8413 -2          A18X+031172Y+004594X0198Y0197R270 S2      
327m9107            J35   -OB1        A01X+030733Y+004437X0150Y0570R180 S1      
317m9107            VIA   -    MD0100PA00X+031040Y+005036X0200Y         S0      
317m9107            VIA   -    MD0100PA00X+023253Y+011483X0200Y         S0      
327m9107            U286  -2          A01X+019342Y+011302X0170Y0240     S1      
317m9107            VIA   -    MD0100PA00X+069895Y+048757X0180Y    R090 S0      
327m9107            U18   -B22        A01X+070048Y+048604X0160Y    R090 S1      
317m9107            VIA   -    MD0100PA00X+061590Y+049347X0200Y         S0      
317m9107            VIA   -    M      A01X+056376Y+048635X0200Y         S2      
017m9107            VIA   -    M      A18X+056376Y+048635X0260Y         S2      
017m9107                  -    MD0100PA00X+056376Y+048635                       
317m9108            VIA   -    MD0100PA00X+092472Y+037221X0200Y         S0      
317m9108            VIA   -    MD0100PA00X+072756Y+036886X0200Y    R270 S0      
327m9108            R6054 -1          A01X+072756Y+037679X0198Y0197R090 S1      
317m9108            VIA   -    M      A01X+179793Y+038529X0200Y         S2      
017m9108            VIA   -    M      A18X+179793Y+038529X0260Y         S2      
017m9108                  -    MD0100PA00X+179793Y+038529                       
327m9108            U66   -2          A01X+180563Y+038785X0170Y0240R270 S1      
317m9108            VIA   -    MD0100PA00X+178370Y+005001X0200Y         S0      
327m9108            J38   -OB1        A01X+178174Y+004437X0150Y0570R180 S1      
327m9108            R3132 -2          A18X+178767Y+005001X0198Y0197R090 S2      
327m9109            U18   -U16        A01X+074772Y+046714X0160Y    R090 S1      
317m9109            VIA   -    MD0100PA00X+074926Y+046867X0180Y    R090 S0      
317m9109            VIA   -    MD0100PA00X+068133Y+021233X0200Y         S0      
317m9109            VIA   -    M      A01X+020409Y+013891X0300Y         S1      
017m9109            VIA   -    M      A18X+020409Y+013891X0200Y         S1      
017m9109                  -    MD0100PA00X+020409Y+013891                       
327m9109            R3206 -1          A01X+019600Y+014096X0198Y0197R180 S1      
327m9110            R1282 -1          A18X+077718Y+044656X0198Y0197     S2      
327m9110            R2474 -1          A01X+182309Y+037955X0198Y0197     S1      
317m9110            VIA   -    M      A01X+172534Y+035933X0200Y         S2      
017m9110            VIA   -    M      A18X+172534Y+035933X0260Y         S2      
017m9110                  -    MD0100PA00X+172534Y+035933                       
317m9110            VIA   -    MD0100PA00X+102267Y+035785X0200Y         S0      
317m9110            VIA   -    MD0100PA00X+099886Y+043714X0200Y         S0      
317m9110            VIA   -    MD0100PA00X+084282Y+044874X0200Y         S0      
327m9111            R1396 -1          A01X+071012Y+015776X0198Y0197     S1      
327m9111            VIA   -    M      A01X+071045Y+015251X0300Y         S1      
327m9111            J59   -69         A01X+069728Y+015472X0110Y0630R270 S1      
327m9112            J41   -B9         A01X+068530Y+006516X0150Y0570R180 S1      
317m9112            VIA   -    MD0100PA00X+068578Y+007002X0200Y         S0      
327m9112            VIA   -    M      A18X+068803Y+007638X0260Y         S2      
327m9112            R6028 -1          A18X+068352Y+007563X0198Y0197     S2      
327FM_JTAG_BMC_OE   R8021 -1          A01X+078992Y+050700X0198Y0197     S1      
317FM_JTAG_BMC_OE   VIA   -    M      A01X+078610Y+050754X0200Y         S2      
017FM_JTAG_BMC_OE   VIA   -    M      A18X+078610Y+050754X0260Y         S2      
017FM_JTAG_BMC_OE         -    MD0100PA00X+078610Y+050754                       
317FM_JTAG_BMC_OE   VIA   -    MD0100PA00X+074296Y+048757X0180Y    R090 S0      
327FM_JTAG_BMC_OE   U18   -R22        A01X+074143Y+048604X0160Y    R090 S1      
327FW_RECOVERY      J41   -A43        A01X+057460Y+005354X0150Y0570R180 S1      
327FW_RECOVERY      R4087 -2          A18X+057620Y+005265X0198Y0197R090 S2      
317FW_RECOVERY      VIA   -    M      A01X+057533Y+004767X0200Y         S2      
017FW_RECOVERY      VIA   -    M      A18X+057533Y+004767X0260Y         S2      
017FW_RECOVERY            -    MD0100PA00X+057533Y+004767                       
327m9113            VIA   -    M      A18X+072010Y+040646X0260Y    R090 S2      
327m9113            U18   -J3         A01X+072253Y+042619X0160Y    R090 S1      
317m9113            VIA   -    MD0100PA00X+072099Y+042466X0180Y    R090 S0      
327m9113            R81   -1          A18X+071950Y+039644X0198Y0197R090 S2      
317m9114            VIA   -    MD0100PA00X+135522Y+120056X0200Y         S0      
327m9114            U25   -DJ35       A01X+142665Y+116413X0177Y    R180 S1      
327m9114            R207  -1          A18X+135260Y+120799X0198Y0197R180 S2      
327m9114            VIA   -    M      A18X+121011Y+124936X0260Y    R180 S2      
327m9114            R81   -2          A18X+071950Y+039329X0198Y0197R090 S2      
317m9114            VIA   -    MD0100PA00X+071950Y+039086X0200Y    R090 S0      
317m9114            VIA   -    MD0100PA00X+094782Y+038657X0200Y         S0      
317m9114            VIA   -    MD0100PA00X+104338Y+045274X0200Y         S0      
317m9114            VIA   -    MD0100PA00X+104239Y+073343X0200Y         S0      
317m9115            VIA   -    MD0100PA00X+063743Y+042894X0200Y         S0      
327m9115            R172  -2          A18X+067278Y+042935X0198Y0197     S2      
317m9115            VIA   -    MD0100PA00X+065592Y+049796X0200Y         S0      
327m9115            U108  -9          A01X+071718Y+065119X0120Y0210R180 S1      
317m9115            VIA   -    M      A01X+071537Y+065473X0200Y         S2      
017m9115            VIA   -    M      A18X+071537Y+065473X0260Y         S2      
017m9115                  -    MD0100PA00X+071537Y+065473                       
327m9116            VIA   -    M      A18X+069007Y+043097X0260Y         S2      
327m9116            U18   -D5         A01X+070678Y+043249X0160Y    R090 S1      
317m9116            VIA   -    MD0100PA00X+070524Y+043096X0180Y    R090 S0      
327m9116            R172  -1          A18X+067592Y+042935X0198Y0197     S2      
327m9117            R171  -1          A18X+067562Y+043773X0198Y0197     S2      
327m9117            VIA   -    M      A18X+069041Y+043744X0260Y    R090 S2      
327m9117            U18   -E6         A01X+070993Y+043564X0160Y    R090 S1      
317m9117            VIA   -    MD0100PA00X+070840Y+043411X0180Y    R090 S0      
327m9118            R25   -1   M      A18X+064672Y+043101X0198Y0197R090 S2      
317m9118            VIA   -    MD0100PA00X+063524Y+043352X0200Y         S0      
327m9118            R171  -2          A18X+067248Y+043773X0198Y0197     S2      
317m9118            VIA   -    MD0100PA00X+065876Y+049796X0200Y         S0      
327m9118            U108  -6          A01X+072308Y+065119X0120Y0210R180 S1      
317m9118            VIA   -    M      A01X+072581Y+065471X0200Y         S2      
017m9118            VIA   -    M      A18X+072581Y+065471X0260Y         S2      
017m9118                  -    MD0100PA00X+072581Y+065471                       
327m9119            R170  -2          A01X+067242Y+042186X0198Y0197R180 S1      
317m9119            VIA   -    MD0100PA00X+062656Y+034393X0200Y         S0      
327m9119            U107  -9          A01X+015018Y+067414X0120Y0210R270 S1      
317m9119            VIA   -    M      A01X+014047Y+067044X0200Y         S2      
017m9119            VIA   -    M      A18X+014047Y+067044X0260Y         S2      
017m9119                  -    MD0100PA00X+014047Y+067044                       
317m9119            VIA   -    MD0100PA00X+038352Y+044339X0200Y         S0      
327m9120            R170  -1          A01X+067558Y+042186X0198Y0197R180 S1      
327m9120            U18   -A2         A01X+069733Y+042304X0160Y    R090 S1      
327m9120            VIA   -    M      A01X+068020Y+042528X0300Y    R090 S1      
327m9121            VIA   -    M      A01X+068020Y+041711X0300Y    R090 S1      
327m9121            U18   -B2         A01X+070048Y+042304X0160Y    R090 S1      
327m9121            R169  -1          A01X+067558Y+041336X0198Y0197R180 S1      
327m9122            R12   -1          A01X+067247Y+040932X0198Y0197     S1      
327m9122            R169  -2   M      A01X+067242Y+041336X0198Y0197R180 S1      
317m9122            VIA   -    MD0100PA00X+063169Y+034130X0200Y         S0      
327m9122            U107  -6          A01X+015018Y+068004X0120Y0210R270 S1      
317m9122            VIA   -    M      A01X+014060Y+068303X0200Y         S2      
017m9122            VIA   -    M      A18X+014060Y+068303X0260Y         S2      
017m9122                  -    MD0100PA00X+014060Y+068303                       
317m9122            VIA   -    MD0100PA00X+038094Y+044339X0200Y         S0      
317m9123            VIA   -    M      A01X+171846Y+065798X0200Y    R180 S2      
017m9123            VIA   -    M      A18X+171846Y+065798X0260Y    R180 S2      
017m9123                  -    MD0100PA00X+171846Y+065798                       
327m9123            U106  -9          A01X+172381Y+066128X0120Y0210R270 S1      
317m9123            VIA   -    MD0100PA00X+109173Y+050936X0200Y         S0      
317m9123            VIA   -    MD0100PA00X+086033Y+047516X0200Y         S0      
327m9123            R166  -2          A18X+067242Y+044186X0198Y0197     S2      
317m9123            VIA   -    MD0100PA00X+066600Y+043784X0200Y    R270 S0      
327m9124            U18   -F7         A01X+071308Y+043879X0160Y    R090 S1      
317m9124            VIA   -    MD0100PA00X+071154Y+043726X0180Y    R090 S0      
327m9124            VIA   -    M      A18X+068596Y+044153X0260Y    R090 S2      
327m9124            R166  -1          A18X+067558Y+044186X0198Y0197     S2      
327m9125            VIA   -    M      A18X+068017Y+041786X0260Y    R090 S2      
327m9125            R165  -1          A18X+067557Y+041786X0198Y0197     S2      
327m9125            U18   -C4         A01X+070363Y+042934X0160Y    R090 S1      
317m9125            VIA   -    MD0100PA00X+070210Y+042781X0180Y    R090 S0      
327m9126            R11   -1          A18X+065904Y+041794X0198Y0197R090 S2      
317m9126            VIA   -    MD0100PA00X+087022Y+043042X0200Y         S0      
317m9126            VIA   -    M      A01X+171603Y+066818X0200Y         S2      
017m9126            VIA   -    M      A18X+171603Y+066818X0260Y         S2      
017m9126                  -    MD0100PA00X+171603Y+066818                       
327m9126            U106  -6          A01X+172381Y+066719X0120Y0210R270 S1      
317m9126            VIA   -    MD0100PA00X+108573Y+050936X0200Y         S0      
317m9126            VIA   -    MD0100PA00X+089900Y+048104X0200Y         S0      
317m9126            VIA   -    MD0100PA00X+066202Y+041790X0200Y         S0      
327m9126            R165  -2          A18X+067242Y+041786X0198Y0197     S2      
327m9127            U105  -9          A01X+118567Y+057937X0120Y0210R270 S1      
317m9127            VIA   -    M      A01X+118295Y+057703X0200Y         S2      
017m9127            VIA   -    M      A18X+118295Y+057703X0260Y         S2      
017m9127                  -    MD0100PA00X+118295Y+057703                       
317m9127            VIA   -    MD0100PA00X+066577Y+057176X0200Y         S0      
327m9127            R164  -2          A01X+067242Y+041786X0198Y0197R180 S1      
317m9127            VIA   -    MD0100PA00X+067002Y+041869X0200Y    R270 S0      
327m9128            VIA   -    M      A01X+068350Y+042108X0300Y    R090 S1      
327m9128            R164  -1          A01X+067558Y+041786X0198Y0197R180 S1      
327m9128            U18   -C3         A01X+070363Y+042619X0160Y    R090 S1      
327m9129            VIA   -    M      A01X+069460Y+040606X0300Y         S1      
327m9129            R163  -1          A01X+069150Y+039644X0198Y0197R270 S1      
327m9129            U18   -B1         A01X+070048Y+041989X0160Y    R090 S1      
327m9130            U105  -6          A01X+118567Y+058528X0120Y0210R270 S1      
317m9130            VIA   -    M      A01X+118259Y+058776X0200Y         S2      
017m9130            VIA   -    M      A18X+118259Y+058776X0260Y         S2      
017m9130                  -    MD0100PA00X+118259Y+058776                       
317m9130            VIA   -    MD0100PA00X+066445Y+057490X0200Y         S0      
317m9130            VIA   -    MD0100PA00X+060603Y+041897X0200Y         S0      
317m9130            VIA   -    MD0100PA00X+068750Y+039068X0200Y         S0      
327m9130            R163  -2          A01X+069150Y+039329X0198Y0197R270 S1      
327m9130            R10   -1   M      A01X+068750Y+039329X0198Y0197R090 S1      
327m9131            R856  -1          A01X+074450Y+052429X0198Y0197R090 S1      
327m9131            U18   -U22        A01X+074772Y+048604X0160Y    R090 S1      
327m9131            VIA   -    M      A01X+074663Y+051608X0160Y0041R090 S1      
327m9132            R708  -1          A01X+074850Y+052429X0198Y0197R090 S1      
327m9132            U18   -P16        A01X+073828Y+046714X0160Y    R090 S1      
317m9132            VIA   -    MD0100PA00X+073981Y+046867X0180Y    R090 S0      
317m9132            VIA   -    M      A01X+075250Y+051336X0200Y    R180 S2      
017m9132            VIA   -    M      A18X+075250Y+051336X0260Y    R180 S2      
017m9132                  -    MD0100PA00X+075250Y+051336                       
317m9133            VIA   -    MD0100PA00X+018976Y+173156X0200Y         S0      
317m9133            J111  -N4   D0142PA00X+032146Y+167201X0302Y    R180 S3      
317m9133            VIA   -    M      A01X+037053Y+165860X0200Y         S2      
017m9133            VIA   -    M      A18X+037053Y+165860X0260Y         S2      
017m9133                  -    MD0100PA00X+037053Y+165860                       
327m9133            R2925 -2          A01X+018976Y+172895X0198Y0197R090 S1      
317m9133            VIA   -    MD0100PA00X+039153Y+158237X0200Y         S0      
317m9134            VIA   -    M      A01X+018976Y+172304X0200Y         S2      
017m9134            VIA   -    M      A18X+018976Y+172304X0260Y         S2      
017m9134                  -    MD0100PA00X+018976Y+172304                       
327m9134            U196  -6          A01X+018924Y+172056X0160Y0200R270 S1      
327m9134            R2925 -1   M      A01X+018976Y+172580X0198Y0197R090 S1      
327m9134            R2912 -2   M      A01X+018576Y+172580X0198Y0197R270 S1      
327m9134            R3508 -1          A01X+018176Y+172580X0198Y0197R090 S1      
317m9135            VIA   -    MD0100PA00X+081785Y+055087X0200Y         S0      
317m9135            VIA   -    MD0100PA00X+082911Y+043928X0200Y         S0      
327m9135            R2262 -1          A01X+082412Y+043928X0198Y0197R180 S1      
327m9135            R2937 -1          A01X+017508Y+172500X0198Y0197R180 S1      
327m9135            R2936 -2   M      A01X+017508Y+172100X0198Y0197     S1      
327m9135            U196  -1          A01X+018176Y+172056X0160Y0200R270 S1      
317m9135            VIA   -    M      A01X+017838Y+172056X0200Y         S2      
017m9135            VIA   -    M      A18X+017838Y+172056X0260Y         S2      
017m9135                  -    MD0100PA00X+017838Y+172056                       
317FM_GPU_PWRGD_N   VIA   -    M      A01X+018253Y+167685X0200Y         S2      
017FM_GPU_PWRGD_N   VIA   -    M      A18X+018253Y+167685X0260Y         S2      
017FM_GPU_PWRGD_N         -    MD0100PA00X+018253Y+167685                       
327FM_GPU_PWRGD_N   Q72   -5          A18X+018767Y+167431X0170Y0200R270 S2      
327FM_GPU_PWRGD_N   R2842 -2          A18X+018281Y+167207X0198Y0197R270 S2      
327FM_GPU_PWRGD_N   Q72   -6   M      A18X+018767Y+167687X0170Y0200R270 S2      
317m9136            VIA   -    M      A01X+020208Y+171784X0200Y         S2      
017m9136            VIA   -    M      A18X+020208Y+171784X0260Y         S2      
017m9136                  -    MD0100PA00X+020208Y+171784                       
327m9136            R2935 -2          A18X+020766Y+167175X0198Y0197R270 S2      
327m9136            C1756 -1   M      A18X+020366Y+167175X0198Y0197R090 S2      
327m9136            Q72   -3   M      A18X+019515Y+167175X0170Y0200R270 S2      
317m9136            VIA   -    MD0100PA00X+082724Y+055077X0200Y         S0      
317m9136            VIA   -    MD0100PA00X+082875Y+047134X0200Y         S0      
327m9136            R2664 -2          A01X+082393Y+047134X0198Y0197     S1      
317FM_GPU_PWRGD     VIA   -    M      A01X+019975Y+167560X0200Y         S2      
017FM_GPU_PWRGD     VIA   -    M      A18X+019975Y+167560X0260Y         S2      
017FM_GPU_PWRGD           -    MD0100PA00X+019975Y+167560                       
327FM_GPU_PWRGD     R3512 -2          A18X+020766Y+167560X0198Y0197R090 S2      
327FM_GPU_PWRGD     Q72   -2          A18X+019515Y+167431X0170Y0200R270 S2      
327FM_GPU_PWRGD     R3513 -1   M      A18X+020366Y+167560X0198Y0197R270 S2      
317FM_GPU_PWRGD     J111  -N6   D0142PA00X+033720Y+167201X0302Y    R180 S3      
317FM_GPU_PWRGD     VIA   -    MD0100PA00X+038933Y+159882X0200Y         S0      
327m9137            VIA   -    M      A01X+076569Y+049998X0300Y         S1      
317m9137            VIA   -    MD0100PA00X+076280Y+049365X0200Y         S0      
327m9137            R1202 -1          A01X+076450Y+050779X0198Y0197R090 S1      
317m9137            VIA   -    MD0100PA00X+075556Y+048127X0180Y    R090 S0      
327m9137            U18   -W20        A01X+075402Y+047974X0160Y    R090 S1      
327m9138            SW1   -12         A01X+169910Y+016176X0300Y0500R270 S1      
327m9138            R6044 -1          A18X+169050Y+016176X0198Y0197     S2      
317m9138            VIA   -    M      A01X+169510Y+016176X0200Y    R090 S2      
017m9138            VIA   -    M      A18X+169510Y+016176X0260Y    R090 S2      
017m9138                  -    MD0100PA00X+169510Y+016176                       
317m9138            VIA   -    MD0100PA00X+103441Y+056742X0200Y         S0      
327m9138            R1202 -2          A01X+076450Y+051094X0198Y0197R090 S1      
317m9138            VIA   -    MD0100PA00X+076581Y+056341X0200Y         S0      
317m9138            VIA   -    MD0100PA00X+106292Y+029505X0200Y         S0      
317m9139            VIA   -    M      A01X+070000Y+038679X0300Y    R090 S1      
017m9139            VIA   -    M      A18X+070000Y+038679X0200Y    R090 S1      
017m9139                  -    MD0100PA00X+070000Y+038679                       
327m9139            R235  -2          A01X+070430Y+037994X0198Y0197R090 S1      
327m9139            U18   -G6         A01X+071623Y+043564X0160Y    R090 S1      
317m9139            VIA   -    MD0100PA00X+071469Y+043411X0180Y    R090 S0      
327m9140            VIA   -    M      A18X+068517Y+042660X0260Y    R090 S2      
327m9140            R234  -2          A18X+067565Y+042200X0198Y0197R180 S2      
327m9140            U18   -F6         A01X+071308Y+043564X0160Y    R090 S1      
317m9140            VIA   -    MD0100PA00X+071154Y+043411X0180Y    R090 S0      
327m9141            U18   -D4         A01X+070678Y+042934X0160Y    R090 S1      
317m9141            VIA   -    MD0100PA00X+070524Y+042781X0180Y    R090 S0      
327m9141            VIA   -    M      A18X+068319Y+041386X0260Y    R090 S2      
327m9141            R205  -2          A18X+067559Y+041386X0198Y0197R180 S2      
327m9142            VIA   -    M      A18X+070065Y+041196X0260Y    R090 S2      
327m9142            R204  -2          A18X+069150Y+039644X0198Y0197R270 S2      
327m9142            U18   -D3         A01X+070678Y+042619X0160Y    R090 S1      
317m9142            VIA   -    MD0100PA00X+070524Y+042466X0180Y    R090 S0      
327m9143            VIA   -    M      A01X+071250Y+050001X0300Y         S1      
327m9143            R272  -2          A01X+071250Y+050779X0198Y0197R270 S1      
327m9143            U18   -G21        A01X+071623Y+048288X0160Y    R090 S1      
327FM_CPU1_SP5R4    VIA   -    M      A18X+074640Y+041732X0260Y         S2      
327FM_CPU1_SP5R4    R269  -2          A18X+075150Y+039644X0198Y0197R270 S2      
327FM_CPU1_SP5R4    U18   -T4         A01X+074458Y+042934X0160Y    R090 S1      
317FM_CPU1_SP5R4    VIA   -    MD0100PA00X+074611Y+042781X0180Y    R090 S0      
327FM_CPU1_SP5R3    R268  -2          A18X+075550Y+039644X0198Y0197R270 S2      
327FM_CPU1_SP5R3    VIA   -    M      A18X+075400Y+040336X0260Y    R090 S2      
327FM_CPU1_SP5R3    U18   -T3         A01X+074458Y+042619X0160Y    R090 S1      
317FM_CPU1_SP5R3    VIA   -    MD0100PA00X+074611Y+042466X0180Y    R090 S0      
327FM_CPU1_SP5R2    R261  -2          A18X+074346Y+038380X0198Y0197R270 S2      
317FM_CPU1_SP5R2    VIA   -    M      A01X+074350Y+038696X0300Y    R090 S1      
017FM_CPU1_SP5R2    VIA   -    M      A18X+074350Y+038696X0200Y    R090 S1      
017FM_CPU1_SP5R2          -    MD0100PA00X+074350Y+038696                       
327FM_CPU1_SP5R2    U18   -R4         A01X+074143Y+042934X0160Y    R090 S1      
317FM_CPU1_SP5R2    VIA   -    MD0100PA00X+074296Y+042781X0180Y    R090 S0      
327FM_CPU1_SP5R1    VIA   -    M      A18X+074593Y+041196X0260Y    R090 S2      
327FM_CPU1_SP5R1    R260  -2          A18X+075150Y+038394X0198Y0197R270 S2      
327FM_CPU1_SP5R1    U18   -R3         A01X+074143Y+042619X0160Y    R090 S1      
317FM_CPU1_SP5R1    VIA   -    MD0100PA00X+074296Y+042466X0180Y    R090 S0      
327m9144            VIA   -    M      A18X+073090Y+047895X0260Y    R090 S2      
327m9144            R193  -1          A18X+073761Y+051208X0198Y0197R270 S2      
327m9144            U18   -N16        A01X+073513Y+046714X0160Y    R090 S1      
317m9144            VIA   -    MD0100PA00X+073666Y+046867X0180Y    R090 S0      
327m9145            VIA   -    M      A01X+070028Y+049996X0300Y         S1      
327m9145            U18   -D22        A01X+070678Y+048604X0160Y    R090 S1      
327m9145            R191  -1          A01X+070050Y+050779X0198Y0197R090 S1      
327m9146            VIA   -    M      A01X+069736Y+050413X0300Y         S1      
327m9146            R192  -1          A01X+069650Y+050779X0198Y0197R090 S1      
327m9146            U18   -D21        A01X+070678Y+048288X0160Y    R090 S1      
317FM_CPU1_SA1      VIA   -    M      A01X+076750Y+040147X0200Y    R090 S2      
017FM_CPU1_SA1      VIA   -    M      A18X+076750Y+040147X0260Y    R090 S2      
017FM_CPU1_SA1            -    MD0100PA00X+076750Y+040147                       
327FM_CPU1_SA1      R267  -2          A18X+076750Y+039644X0198Y0197R270 S2      
327FM_CPU1_SA1      U18   -G7         A01X+071623Y+043879X0160Y    R090 S1      
317FM_CPU1_SA1      VIA   -    MD0100PA00X+071469Y+043726X0180Y    R090 S0      
317FM_CPU1_SA0      VIA   -    M      A01X+075726Y+040876X0200Y         S2      
017FM_CPU1_SA0      VIA   -    M      A18X+075726Y+040876X0260Y         S2      
017FM_CPU1_SA0            -    MD0100PA00X+075726Y+040876                       
327FM_CPU1_SA0      R266  -1          A18X+076350Y+038394X0198Y0197R090 S2      
327FM_CPU1_SA0      U18   -J7         A01X+072253Y+043879X0160Y    R090 S1      
317FM_CPU1_SA0      VIA   -    MD0100PA00X+072099Y+043726X0180Y    R090 S0      
327m9147            VIA   -    M      A01X+070957Y+050432X0300Y         S1      
327m9147            U18   -F22        A01X+071308Y+048604X0160Y    R090 S1      
327m9147            R273  -2          A01X+070850Y+050779X0198Y0197R270 S1      
327m9148            R252  -1          A01X+076500Y+054029X0198Y0197R090 S1      
327m9148            VIA   -    M      A01X+076657Y+053217X0300Y         S1      
327m9148            U18   -Y21        A01X+075717Y+048288X0160Y    R090 S1      
317m9149            VIA   -    MD0100PA00X+085221Y+050721X0200Y         S0      
327m9149            U18   -AA22       A01X+076032Y+048604X0160Y    R090 S1      
317m9149            VIA   -    M      A01X+077104Y+051129X0200Y         S2      
017m9149            VIA   -    M      A18X+077104Y+051129X0260Y         S2      
017m9149                  -    MD0100PA00X+077104Y+051129                       
317m9149            VIA   -    MD0100PA00X+085789Y+045985X0200Y         S0      
327m9149            R195  -1          A01X+082084Y+045534X0198Y0197     S1      
317m9149            VIA   -    MD0100PA00X+081611Y+045534X0200Y         S0      
327m9150            VIA   -    M      A01X+072350Y+040106X0300Y         S1      
327m9150            R270  -1          A01X+072350Y+039644X0198Y0197R270 S1      
327m9150            U18   -G1         A01X+071623Y+041989X0160Y    R090 S1      
327m9151            R196  -2          A01X+072303Y+052424X0198Y0197R270 S1      
327m9151            U18   -H18        A01X+071938Y+047344X0160Y    R090 S1      
317m9151            VIA   -    MD0100PA00X+071784Y+047497X0180Y    R090 S0      
317m9151            VIA   -    M      A01X+072450Y+051736X0200Y    R180 S2      
017m9151            VIA   -    M      A18X+072450Y+051736X0260Y    R180 S2      
017m9151                  -    MD0100PA00X+072450Y+051736                       
327m9152            VIA   -    M      A01X+075750Y+049998X0300Y         S1      
327m9152            R277  -1          A01X+075650Y+050779X0198Y0197R090 S1      
327m9152            U18   -W22        A01X+075402Y+048604X0160Y    R090 S1      
327m9153            VIA   -    M      A01X+070822Y+040123X0300Y         S1      
327m9153            R190  -2          A01X+070750Y+039644X0198Y0197R090 S1      
327m9153            U18   -E2         A01X+070993Y+042304X0160Y    R090 S1      
327m9154            R189  -2          A01X+071150Y+039644X0198Y0197R090 S1      
327m9154            VIA   -    M      A01X+071150Y+040567X0300Y         S1      
327m9154            U18   -E1         A01X+070993Y+041989X0160Y    R090 S1      
327m9155            R187  -2          A01X+070830Y+037994X0198Y0197R090 S1      
317m9155            VIA   -    M      A01X+070750Y+038236X0200Y    R090 S2      
017m9155            VIA   -    M      A18X+070750Y+038236X0260Y    R090 S2      
017m9155                  -    MD0100PA00X+070750Y+038236                       
327m9155            U18   -H7         A01X+071938Y+043879X0160Y    R090 S1      
317m9155            VIA   -    MD0100PA00X+071784Y+043726X0180Y    R090 S0      
327m9156            R265  -1          A18X+077508Y+049934X0198Y0197R180 S2      
327m9156            VIA   -    M      A18X+076932Y+049480X0260Y    R090 S2      
327m9156            U18   -W19        A01X+075402Y+047659X0160Y    R090 S1      
317m9156            VIA   -    MD0100PA00X+075556Y+047812X0180Y    R090 S0      
327m9157            VIA   -    M      A01X+075370Y+040118X0300Y         S1      
327m9157            U18   -T2         A01X+074458Y+042304X0160Y    R090 S1      
327m9157            R264  -2          A01X+075550Y+039644X0198Y0197R090 S1      
327m9158            VIA   -    M      A01X+075080Y+040599X0300Y         S1      
327m9158            R263  -2          A01X+075150Y+039644X0198Y0197R090 S1      
327m9158            U18   -T1         A01X+074458Y+041989X0160Y    R090 S1      
317m9159            VIA   -    MD0100PA00X+073955Y+038827X0200Y    R090 S2      
327m9159            R262  -2          A18X+073946Y+038380X0198Y0197R270 S2      
327m9159            U18   -P4         A01X+073828Y+042934X0160Y    R090 S1      
317m9159            VIA   -    MD0100PA00X+073981Y+042781X0180Y    R090 S0      
327m9160            R239  -2          A01X+070030Y+037994X0198Y0197R090 S1      
327m9160            U18   -E3         A01X+070993Y+042619X0160Y    R090 S1      
317m9160            VIA   -    M      A01X+070030Y+038250X0200Y    R090 S2      
017m9160            VIA   -    M      A18X+070030Y+038250X0260Y    R090 S2      
017m9160                  -    MD0100PA00X+070030Y+038250                       
317m9160            VIA   -    MD0100PA00X+070840Y+042466X0180Y    R090 S0      
327m9161            R238  -2          A01X+069080Y+037994X0198Y0197R090 S1      
327m9161            U18   -E4         A01X+070993Y+042934X0160Y    R090 S1      
317m9161            VIA   -    MD0100PA00X+070840Y+042781X0180Y    R090 S2      
317m9161            VIA   -    MD0100PA00X+069550Y+038236X0200Y    R090 S0      
327m9162            VIA   -    M      A01X+069504Y+040108X0300Y         S1      
327m9162            R237  -2          A01X+069550Y+039644X0198Y0197R090 S1      
327m9162            U18   -C1         A01X+070363Y+041989X0160Y    R090 S1      
327m9163            VIA   -    M      A01X+069994Y+040250X0300Y         S1      
327m9163            R236  -2          A01X+069950Y+039644X0198Y0197R090 S1      
327m9163            U18   -D2         A01X+070678Y+042304X0160Y    R090 S1      
327m9164            U18   -F19        A01X+071308Y+047659X0160Y    R090 S1      
317m9164            VIA   -    MD0100PA00X+071154Y+047812X0180Y    R090 S0      
317m9164            VIA   -    M      A01X+070377Y+051346X0200Y    R180 S2      
017m9164            VIA   -    M      A18X+070377Y+051346X0260Y    R180 S2      
017m9164                  -    MD0100PA00X+070377Y+051346                       
327m9164            R216  -2          A01X+070450Y+052429X0198Y0197R270 S1      
327FM_CPU0_SP5R4    VIA   -    M      A01X+076250Y+040110X0300Y         S1      
327FM_CPU0_SP5R4    R223  -1          A01X+076350Y+039644X0198Y0197R270 S1      
327FM_CPU0_SP5R4    U18   -U2         A01X+074772Y+042304X0160Y    R090 S1      
327FM_CPU0_SP5R3    VIA   -    M      A01X+075630Y+040584X0300Y         S1      
327FM_CPU0_SP5R3    R222  -2          A01X+075950Y+039644X0198Y0197R090 S1      
327FM_CPU0_SP5R3    U18   -U1         A01X+074772Y+041989X0160Y    R090 S1      
327FM_CPU0_SP5R2    VIA   -    M      A18X+073250Y+040618X0260Y    R090 S2      
327FM_CPU0_SP5R2    U18   -N6         A01X+073513Y+043564X0160Y    R090 S1      
317FM_CPU0_SP5R2    VIA   -    MD0100PA00X+073666Y+043411X0180Y    R090 S0      
327FM_CPU0_SP5R2    R181  -2          A18X+073550Y+039644X0198Y0197R270 S2      
327FM_CPU0_SP5R1    R180  -2          A18X+073546Y+038380X0198Y0197R270 S2      
327FM_CPU0_SP5R1    VIA   -    M      A18X+073600Y+040233X0260Y    R090 S2      
327FM_CPU0_SP5R1    U18   -N5         A01X+073513Y+043249X0160Y    R090 S1      
317FM_CPU0_SP5R1    VIA   -    MD0100PA00X+073666Y+043096X0180Y    R090 S0      
327m9165            VIA   -    M      A01X+073250Y+050301X0300Y         S1      
327m9165            R250  -1          A01X+073250Y+050779X0198Y0197R090 S1      
327m9165            U18   -M21        A01X+073198Y+048288X0160Y    R090 S1      
327m9166            VIA   -    M      A01X+068850Y+053551X0300Y         S1      
327m9166            R248  -1          A01X+068850Y+054029X0198Y0197R090 S1      
327m9166            U18   -C21        A01X+070363Y+048288X0160Y    R090 S1      
327m9167            VIA   -    M      A01X+069455Y+049991X0300Y         S1      
327m9167            R249  -1          A01X+069250Y+050779X0198Y0197R090 S1      
327m9167            U18   -C22        A01X+070363Y+048604X0160Y    R090 S1      
317FM_CPU0_SA1      VIA   -    M      A01X+074763Y+040616X0200Y         S2      
017FM_CPU0_SA1      VIA   -    M      A18X+074763Y+040616X0260Y         S2      
017FM_CPU0_SA1            -    MD0100PA00X+074763Y+040616                       
327FM_CPU0_SA1      R221  -1          A18X+074750Y+039644X0198Y0197R090 S2      
327FM_CPU0_SA1      U18   -J2         A01X+072253Y+042304X0160Y    R090 S1      
317FM_CPU0_SA1      VIA   -    MD0100PA00X+072099Y+042151X0180Y    R090 S0      
317FM_CPU0_SA0      VIA   -    M      A01X+075950Y+040210X0200Y         S2      
017FM_CPU0_SA0      VIA   -    M      A18X+075950Y+040210X0260Y         S2      
017FM_CPU0_SA0            -    MD0100PA00X+075950Y+040210                       
327FM_CPU0_SA0      U18   -H5         A01X+071938Y+043249X0160Y    R090 S1      
317FM_CPU0_SA0      VIA   -    MD0100PA00X+071784Y+043096X0180Y    R090 S0      
327FM_CPU0_SA0      R220  -1          A18X+075950Y+039644X0198Y0197R090 S2      
327m9168            R217  -2          A01X+071248Y+052298X0198Y0197R270 S1      
327m9168            U18   -G22        A01X+071623Y+048604X0160Y    R090 S1      
327m9168            VIA   -    M      A01X+071467Y+051521X0160Y0041R090 S1      
317m9169            VIA   -    M      A01X+078688Y+044334X0200Y    R180 S2      
017m9169            VIA   -    M      A18X+078688Y+044334X0260Y    R180 S2      
017m9169                  -    MD0100PA00X+078688Y+044334                       
327m9169            R218  -2          A01X+078953Y+044334X0198Y0197R180 S1      
327m9169            U18   -W9         A01X+075402Y+044509X0160Y    R090 S1      
317m9169            VIA   -    MD0100PA00X+075556Y+044356X0180Y    R090 S0      
327m9170            VIA   -    M      A01X+072450Y+050301X0300Y         S1      
327m9170            R215  -2          A01X+072450Y+050779X0198Y0197R270 S1      
327m9170            U18   -J22        A01X+072253Y+048604X0160Y    R090 S1      
317m9171            VIA   -    M      A01X+071964Y+038686X0300Y    R090 S1      
017m9171            VIA   -    M      A18X+071964Y+038686X0200Y    R090 S1      
017m9171                  -    MD0100PA00X+071964Y+038686                       
327m9171            R179  -1          A01X+071630Y+037994X0198Y0197R270 S1      
327m9171            U18   -J6         A01X+072253Y+043564X0160Y    R090 S1      
317m9171            VIA   -    MD0100PA00X+072099Y+043411X0180Y    R090 S0      
327m9172            U18   -G20        A01X+071623Y+047974X0160Y    R090 S1      
317m9172            VIA   -    MD0100PA00X+071469Y+048127X0180Y    R090 S0      
327m9172            R253  -2          A18X+071265Y+049777X0198Y0197R090 S2      
327m9172            VIA   -    M      A18X+071563Y+048705X0260Y    R090 S2      
327m9173            R219  -2          A01X+073031Y+052421X0198Y0197R270 S1      
317m9173            VIA   -    MD0100PA00X+072099Y+046867X0180Y    R090 S2      
327m9173            U18   -J16        A01X+072253Y+046714X0160Y    R090 S1      
317m9173            VIA   -    MD0100PA00X+072850Y+052186X0200Y    R180 S0      
327m9174            VIA   -    M      A01X+074450Y+050001X0300Y         S1      
327m9174            U18   -P21        A01X+073828Y+048288X0160Y    R090 S1      
327m9174            R258  -1          A01X+074450Y+050779X0198Y0197R090 S1      
327m9175            R246  -2          A01X+071230Y+037994X0198Y0197R090 S1      
317m9175            VIA   -    MD0100PA00X+071150Y+038236X0200Y    R090 S0      
327m9175            U18   -H6         A01X+071938Y+043564X0160Y    R090 S1      
317m9175            VIA   -    MD0100PA00X+071784Y+043411X0180Y    R090 S2      
327m9176            R245  -2          A18X+072542Y+038086X0198Y0197     S2      
327m9176            U18   -G5         A01X+071623Y+043249X0160Y    R090 S1      
327m9176            VIA   -    M      A18X+072261Y+040196X0260Y    R090 S2      
317m9176            VIA   -    MD0100PA00X+071469Y+043096X0180Y    R090 S0      
317m9177            VIA   -    MD0100PA00X+069010Y+040178X0200Y         S2      
327m9177            R244  -2          A18X+068756Y+039644X0198Y0197R270 S2      
327m9177            U18   -F5         A01X+071308Y+043249X0160Y    R090 S1      
317m9177            VIA   -    MD0100PA00X+071154Y+043096X0180Y    R090 S0      
327m9178            U18   -D1         A01X+070678Y+041989X0160Y    R090 S1      
327m9178            VIA   -    M      A01X+070400Y+040600X0300Y         S1      
327m9178            R243  -2          A01X+070350Y+039644X0198Y0197R090 S1      
327m9179            VIA   -    M      A18X+076511Y+049174X0260Y    R090 S2      
327m9179            U18   -U17        A01X+074772Y+047029X0160Y    R090 S1      
317m9179            VIA   -    MD0100PA00X+074926Y+047182X0180Y    R090 S0      
327m9179            R186  -1          A18X+076415Y+049777X0198Y0197R270 S2      
327m9180            R185  -2          A18X+074750Y+038394X0198Y0197R270 S2      
327m9180            VIA   -    M      A18X+074400Y+040109X0260Y    R090 S2      
327m9180            U18   -P3         A01X+073828Y+042619X0160Y    R090 S1      
317m9180            VIA   -    MD0100PA00X+073981Y+042466X0180Y    R090 S0      
327m9181            VIA   -    M      A01X+074400Y+040597X0300Y         S1      
327m9181            R184  -2          A01X+074750Y+039644X0198Y0197R090 S1      
327m9181            U18   -R2         A01X+074143Y+042304X0160Y    R090 S1      
327m9182            VIA   -    M      A01X+074500Y+040000X0300Y         S1      
327m9182            U18   -R1         A01X+074143Y+041989X0160Y    R090 S1      
327m9182            R183  -2          A01X+074350Y+039644X0198Y0197R090 S1      
327m9183            U18   -J17        A01X+072253Y+047029X0160Y    R090 S1      
317m9183            VIA   -    MD0100PA00X+072099Y+047182X0180Y    R090 S0      
327m9183            R371  -2          A01X+070850Y+054029X0198Y0197R270 S1      
317m9183            VIA   -    M      A01X+070821Y+053782X0200Y         S2      
017m9183            VIA   -    M      A18X+070821Y+053782X0260Y         S2      
017m9183                  -    MD0100PA00X+070821Y+053782                       
327FM_CLR_CMOS      VIA   -    M      A18X+073810Y+040878X0260Y    R090 S2      
327FM_CLR_CMOS      R275  -2          A18X+073965Y+039642X0198Y0197R270 S2      
327FM_CLR_CMOS      U18   -N3         A01X+073513Y+042619X0160Y    R090 S1      
317FM_CLR_CMOS      VIA   -    MD0100PA00X+073666Y+042466X0180Y    R090 S0      
327m9184            VIA   -    M      A01X+073390Y+040594X0300Y         S1      
327m9184            R6053 -2          A01X+073550Y+039644X0198Y0197R090 S1      
327m9184            U18   -N2         A01X+073513Y+042304X0160Y    R090 S1      
317m9185            VIA   -    MD0100PA00X+074825Y+167477X0200Y    R270 S0      
317m9185            VIA   -    MD0100PA00X+113904Y+161138X0200Y         S0      
327m9185            R3063 -1          A01X+141062Y+161019X0198Y0197R090 S1      
317m9185            VIA   -    M      A01X+140929Y+160580X0200Y         S2      
017m9185            VIA   -    M      A18X+140929Y+160580X0260Y         S2      
017m9185                  -    MD0100PA00X+140929Y+160580                       
317m9185            VIA   -    MD0100PA00X+112488Y+149004X0200Y         S0      
317m9185            VIA   -    MD0100PA00X+075042Y+146889X0200Y         S0      
327m9185            R2796 -1          A18X+072867Y+165300X0198Y0197     S2      
327m9185            U190  -D          A01X+076130Y+167990X0320Y0360R180 S1      
327m9185            R2794 -2   M      A01X+075219Y+167492X0198Y0197R270 S1      
317m9185            VIA   -    MD0100PA00X+074500Y+151647X0200Y         S0      
327m9186            J41   -A47        A01X+056515Y+005354X0150Y0570R180 S1      
327m9186            R1815 -2          A18X+056420Y+005261X0198Y0197R090 S2      
317m9186            VIA   -    M      A01X+056518Y+004798X0200Y         S2      
017m9186            VIA   -    M      A18X+056518Y+004798X0260Y         S2      
017m9186                  -    MD0100PA00X+056518Y+004798                       
327m9187            R1204 -1          A01X+144933Y+127192X0198Y0197R090 S1      
327m9187            U25   -DJ33       A01X+143405Y+116413X0177Y    R180 S1      
327m9187            VIA   -    M      A01X+144996Y+126792X0300Y    R180 S1      
327m9188            SW1   -14         A01X+169910Y+015176X0300Y0500R270 S1      
327m9188            R1204 -2          A01X+144933Y+127507X0198Y0197R090 S1      
327m9188            R1265 -1          A18X+169050Y+015376X0198Y0197     S2      
317m9188            VIA   -    MD0100PA00X+169510Y+015176X0200Y    R090 S0      
317m9188            VIA   -    MD0100PA00X+158052Y+049765X0200Y         S0      
317m9188            VIA   -    MD0100PA00X+095738Y+051523X0200Y         S0      
317m9188            VIA   -    MD0100PA00X+077500Y+051131X0200Y         S0      
317m9188            VIA   -    MD0100PA00X+075241Y+048757X0180Y    R090 S0      
327m9188            U18   -V22        A01X+075087Y+048604X0160Y    R090 S1      
317m9188            VIA   -    MD0100PA00X+097883Y+030341X0200Y         S0      
317m9188            VIA   -    M      A01X+156427Y+133844X0200Y         S2      
017m9188            VIA   -    M      A18X+156427Y+133844X0260Y         S2      
017m9188                  -    MD0100PA00X+156427Y+133844                       
327m9189            U25   -DJ29       A01X+144885Y+116413X0177Y    R180 S1      
327m9189            VIA   -    M      A01X+150548Y+126584X0300Y    R180 S1      
327m9189            R939  -1          A01X+150548Y+127081X0198Y0197R090 S1      
317m9190            VIA   -    M      A01X+156846Y+131153X0200Y         S2      
017m9190            VIA   -    M      A18X+156846Y+131153X0260Y         S2      
017m9190                  -    MD0100PA00X+156846Y+131153                       
317m9190            VIA   -    MD0100PA00X+156690Y+134773X0200Y         S0      
327m9190            U101  -2          A18X+159725Y+135551X0220Y0530R090 S2      
327m9190            R942  -2   M      A18X+156550Y+134476X0198Y0197R270 S2      
327m9190            R934  -1          A18X+156915Y+134477X0198Y0197R090 S2      
327m9190            R939  -2          A01X+150548Y+127396X0198Y0197R090 S1      
317m9191            VIA   -    M      A01X+075296Y+053768X0200Y         S2      
017m9191            VIA   -    M      A18X+075296Y+053768X0260Y         S2      
017m9191                  -    MD0100PA00X+075296Y+053768                       
327m9191            R937  -1          A01X+075250Y+054029X0198Y0197R090 S1      
327m9191            U18   -U21        A01X+074772Y+048288X0160Y    R090 S1      
317m9191            VIA   -    MD0100PA00X+074926Y+048442X0180Y    R090 S0      
317m9192            VIA   -    MD0100PA00X+154722Y+148081X0200Y         S0      
327m9192            C5000 -1   M      A18X+157291Y+135925X0198Y0197R090 S2      
327m9192            R6100 -2          A18X+156891Y+135925X0198Y0197R270 S2      
317m9192            VIA   -    MD0100PA00X+157291Y+136676X0200Y         S0      
317m9192            VIA   -    M      A01X+075250Y+054586X0200Y    R180 S2      
017m9192            VIA   -    M      A18X+075250Y+054586X0260Y    R180 S2      
017m9192                  -    MD0100PA00X+075250Y+054586                       
317m9192            VIA   -    MD0100PA00X+102920Y+035161X0200Y         S0      
317m9192            VIA   -    MD0100PA00X+102455Y+051125X0200Y         S0      
327m9192            R937  -2          A01X+075250Y+054344X0198Y0197R090 S1      
327m9193            R3205 -1          A01X+019764Y+013061X0198Y0197R090 S1      
327m9193            VIA   -    M      A01X+019598Y+012556X0300Y         S1      
327m9193            U286  -4          A01X+019598Y+012050X0170Y0240     S1      
327m9194            U66   -4          A01X+181311Y+038529X0170Y0240R270 S1      
327m9194            VIA   -    M      A01X+181827Y+038529X0300Y         S1      
327m9194            R2473 -1          A01X+182309Y+038395X0198Y0197     S1      
327m9195            U321  -4          A01X+035732Y+012252X0180Y0520R270 S1      
317m9195            VIA   -    MD0100PA00X+075482Y+016340X0200Y         S0      
317m9195            VIA   -    MD0100PA00X+036174Y+012071X0200Y         S0      
317m9195            VIA   -    MD0100PA00X+019000Y+014300X0200Y         S0      
327m9195            R3205 -2          A01X+019764Y+013376X0198Y0197R090 S1      
327m9195            R3207 -1   M      A01X+019284Y+014496X0198Y0197     S1      
327m9195            VIA   -    M      A01X+019284Y+013626X0300Y         S1      
327m9195            R3206 -2   M      A01X+019284Y+014096X0198Y0197R180 S1      
317m9195            VIA   -    MD0100PA00X+082762Y+030296X0200Y         S0      
327m9195            U222  -4          A18X+083550Y+030419X0140Y0590R090 S2      
327m9195            U222  -1          A18X+083550Y+031186X0140Y0590R090 S2      
317m9195            VIA   -    MD0100PA00X+083042Y+031186X0200Y         S0      
327m9195            U222  -13         A18X+081250Y+030931X0140Y0590R090 S2      
327m9195            U222  -10         A18X+081250Y+030163X0140Y0590R090 S2      
317m9195            VIA   -    MD0100PA00X+080389Y+030197X0200Y         S0      
317m9195            VIA   -    MD0100PA00X+079994Y+028682X0200Y         S0      
327m9195            U223  -10         A18X+076990Y+027659X0140Y0590R090 S2      
327m9195            U223  -1   M      A18X+079290Y+028682X0140Y0590R090 S2      
327m9195            U223  -13  M      A18X+076990Y+028426X0140Y0590R090 S2      
317m9195            VIA   -    MD0100PA00X+079820Y+027915X0200Y         S0      
327m9195            U223  -4          A18X+079290Y+027915X0140Y0590R090 S2      
327FB_BMC_ISOLATE   U320  -4          A01X+149280Y+013456X0180Y0520R090 S1      
327FB_BMC_ISOLATE   R1289 -1          A01X+182623Y+038805X0198Y0197R180 S1      
327FB_BMC_ISOLATE   R2474 -2   M      A01X+182624Y+037955X0198Y0197     S1      
327FB_BMC_ISOLATE   R2473 -2   M      A01X+182624Y+038395X0198Y0197     S1      
317FB_BMC_ISOLATE   VIA   -    M      A01X+182867Y+037955X0200Y         S2      
017FB_BMC_ISOLATE   VIA   -    M      A18X+182867Y+037955X0260Y         S2      
017FB_BMC_ISOLATE         -    MD0100PA00X+182867Y+037955                       
317FB_BMC_ISOLATE   VIA   -    MD0100PA00X+148865Y+013456X0200Y         S0      
317FB_BMC_ISOLATE   VIA   -    MD0100PA00X+078264Y+031089X0200Y         S0      
327FB_BMC_ISOLATE   U67   -1          A18X+078798Y+031158X0140Y0590R090 S2      
327FB_BMC_ISOLATE   U67   -4          A18X+078798Y+030391X0140Y0590R090 S2      
327FB_BMC_ISOLATE   U67   -10         A18X+076498Y+030135X0140Y0590R090 S2      
327FB_BMC_ISOLATE   U67   -13         A18X+076498Y+030903X0140Y0590R090 S2      
317FB_BMC_ISOLATE   VIA   -    MD0100PA00X+076986Y+030246X0200Y         S0      
327FB_BMC_ISOLATE   U7    -10         A18X+081858Y+027118X0140Y0590R090 S2      
327FB_BMC_ISOLATE   U7    -13  M      A18X+081858Y+027886X0140Y0590R090 S2      
317FB_BMC_ISOLATE   VIA   -    MD0100PA00X+081287Y+027886X0200Y         S0      
327FB_BMC_ISOLATE   U7    -1   M      A18X+084158Y+028142X0140Y0590R090 S2      
327FB_BMC_ISOLATE   U7    -4          A18X+084158Y+027374X0140Y0590R090 S2      
317FB_BMC_ISOLATE   VIA   -    MD0100PA00X+084619Y+028142X0200Y         S0      
317ESPI_CPU0_R_D3   VIA   -    MD0080PA00X+146549Y+115880X0160Y         S0      
327ESPI_CPU0_R_D3   U25   -DG25       A01X+146365Y+115776X0177Y    R180 S1      
327ESPI_CPU0_R_D3   VIA   -    M      A18X+146526Y+119319X0260Y    R180 S2      
327ESPI_CPU0_R_D3   R471  -2          A18X+154810Y+128299X0198Y0197     S2      
317ESPI_CPU0_R_D2   VIA   -    MD0080PA00X+146734Y+115561X0160Y         S0      
327ESPI_CPU0_R_D2   U25   -DF25       A01X+146550Y+115457X0177Y    R180 S1      
327ESPI_CPU0_R_D2   VIA   -    M      A18X+146836Y+119846X0260Y    R180 S2      
327ESPI_CPU0_R_D2   R470  -2          A18X+154810Y+127899X0198Y0197     S2      
317ESPI_CPU0_R_D1   VIA   -    MD0080PA00X+146919Y+115242X0160Y         S0      
327ESPI_CPU0_R_D1   U25   -DE24       A01X+146735Y+115138X0177Y    R180 S1      
327ESPI_CPU0_R_D1   VIA   -    M      A18X+148047Y+120005X0260Y    R180 S2      
327ESPI_CPU0_R_D1   R469  -2          A18X+153280Y+126449X0198Y0197     S2      
317ESPI_CPU0_R_D0   VIA   -    MD0080PA00X+147104Y+116199X0160Y         S0      
327ESPI_CPU0_R_D0   U25   -DH24       A01X+146920Y+116094X0177Y    R180 S1      
327ESPI_CPU0_R_D0   VIA   -    M      A18X+147560Y+119276X0260Y    R180 S2      
327ESPI_CPU0_R_D0   R468  -2          A18X+154804Y+127438X0198Y0197     S2      
327m9196            R462  -2          A18X+156488Y+127879X0180Y0200R180 S2      
327m9196            U25   -DJ23       A01X+147106Y+116413X0177Y    R180 S1      
317m9196            VIA   -    M      A01X+156045Y+127900X0200Y    R180 S2      
017m9196            VIA   -    M      A18X+156045Y+127900X0260Y    R180 S2      
017m9196                  -    MD0100PA00X+156045Y+127900                       
317m9197            VIA   -    MD0080PA00X+147104Y+115561X0160Y         S0      
327m9197            R472  -2          A18X+158628Y+127517X0180Y0200R180 S2      
327m9197            U25   -DF24       A01X+146920Y+115457X0177Y    R180 S1      
327m9197            VIA   -    M      A18X+152754Y+124484X0260Y    R180 S2      
317m9198            VIA   -    M      A01X+073650Y+053786X0200Y         S2      
017m9198            VIA   -    M      A18X+073650Y+053786X0260Y         S2      
017m9198                  -    MD0100PA00X+073650Y+053786                       
327m9198            U18   -P17        A01X+073828Y+047029X0160Y    R090 S1      
317m9198            VIA   -    MD0100PA00X+073981Y+047182X0180Y    R090 S0      
327m9198            R1552 -1          A01X+073650Y+054029X0198Y0197R090 S1      
317m9199            VIA   -    M      A01X+074050Y+054586X0200Y         S2      
017m9199            VIA   -    M      A18X+074050Y+054586X0260Y         S2      
017m9199                  -    MD0100PA00X+074050Y+054586                       
327m9199            R1551 -1          A01X+074050Y+054344X0198Y0197R270 S1      
317m9199            VIA   -    MD0100PA00X+073981Y+047497X0180Y    R090 S0      
327m9199            U18   -P18        A01X+073828Y+047344X0160Y    R090 S1      
327m9200            R1550 -1          A18X+074444Y+049777X0198Y0197R270 S2      
327m9200            U18   -P19        A01X+073828Y+047659X0160Y    R090 S1      
317m9200            VIA   -    MD0100PA00X+073981Y+047812X0180Y    R090 S0      
327m9200            VIA   -    M      A18X+074360Y+049313X0260Y    R090 S2      
317m9201            VIA   -    M      A01X+076450Y+051334X0200Y         S2      
017m9201            VIA   -    M      A18X+076450Y+051334X0260Y         S2      
017m9201                  -    MD0100PA00X+076450Y+051334                       
327m9201            R1549 -1          A18X+076768Y+049934X0198Y0197R180 S2      
327m9201            U18   -T21        A01X+074458Y+048288X0160Y    R090 S1      
317m9201            VIA   -    MD0100PA00X+074611Y+048442X0180Y    R090 S0      
327ESPI_CPU0_D3     J41   -B8         A01X+068766Y+006516X0150Y0570R180 S1      
327ESPI_CPU0_D3     R1552 -2          A01X+073650Y+054344X0198Y0197R090 S1      
317ESPI_CPU0_D3     VIA   -    MD0100PA00X+073667Y+054586X0200Y    R180 S0      
317ESPI_CPU0_D3     VIA   -    MD0100PA00X+068766Y+007320X0200Y         S0      
317ESPI_CPU0_D3     VIA   -    MD0100PA00X+155918Y+128716X0200Y         S0      
327ESPI_CPU0_D3     R1506 -2          A18X+156060Y+128411X0198Y0197     S2      
327ESPI_CPU0_D3     R471  -1          A18X+155125Y+128299X0198Y0197     S2      
327ESPI_CPU0_D3     VIA   -    M      A18X+155585Y+128299X0260Y    R180 S2      
327ESPI_CPU0_D2     J41   -B7         A01X+069003Y+006516X0150Y0570R180 S1      
317ESPI_CPU0_D2     VIA   -    MD0100PA00X+155438Y+127876X0200Y    R180 S0      
317ESPI_CPU0_D2     VIA   -    M      A01X+069003Y+007014X0200Y         S2      
017ESPI_CPU0_D2     VIA   -    M      A18X+069003Y+007014X0260Y         S2      
017ESPI_CPU0_D2           -    MD0100PA00X+069003Y+007014                       
327ESPI_CPU0_D2     R1551 -2          A01X+074050Y+054029X0198Y0197R270 S1      
317ESPI_CPU0_D2     VIA   -    MD0100PA00X+074050Y+053786X0200Y         S0      
327ESPI_CPU0_D2     R470  -1          A18X+155125Y+127899X0198Y0197     S2      
327ESPI_CPU0_D2     R1505 -2          A01X+155438Y+127636X0198Y0197R090 S1      
327ESPI_CPU0_D1     J41   -B6         A01X+069239Y+006516X0150Y0570R180 S1      
327ESPI_CPU0_D1     R1550 -2          A18X+074444Y+050092X0198Y0197R270 S2      
327ESPI_CPU0_D1     VIA   -    M      A18X+154350Y+126931X0260Y    R180 S2      
317ESPI_CPU0_D1     VIA   -    MD0100PA00X+156193Y+126990X0200Y    R180 S0      
317ESPI_CPU0_D1     VIA   -    MD0100PA00X+074564Y+054588X0200Y    R180 S0      
317ESPI_CPU0_D1     VIA   -    MD0100PA00X+069239Y+007269X0200Y         S0      
327ESPI_CPU0_D1     R469  -1          A18X+153595Y+126449X0198Y0197     S2      
327ESPI_CPU0_D1     R1504 -2          A01X+156506Y+127344X0198Y0197     S1      
327ESPI_CPU0_D0     J41   -B5         A01X+069475Y+006516X0150Y0570R180 S1      
327ESPI_CPU0_D0     VIA   -    M      A18X+155580Y+127635X0260Y    R180 S2      
317ESPI_CPU0_D0     VIA   -    MD0100PA00X+155751Y+128029X0200Y    R180 S0      
317ESPI_CPU0_D0     VIA   -    MD0100PA00X+077720Y+053025X0200Y    R180 S0      
327ESPI_CPU0_D0     R1549 -2          A18X+077083Y+049934X0198Y0197R180 S2      
317ESPI_CPU0_D0     VIA   -    MD0100PA00X+069475Y+007021X0200Y         S0      
327ESPI_CPU0_D0     R468  -1          A18X+155119Y+127438X0198Y0197     S2      
327ESPI_CPU0_D0     R1503 -2          A01X+155808Y+127636X0198Y0197R090 S1      
327m9202            VIA   -    M      A01X+074214Y+050494X0300Y         S1      
327m9202            R1553 -1          A01X+074090Y+052431X0198Y0197R090 S1      
327m9202            VIA   -    M      A01X+074100Y+051886X0300Y    R090 S1      
327m9202            U18   -P22        A01X+073828Y+048604X0160Y    R090 S1      
327m9203            J41   -B2         A01X+070184Y+006516X0150Y0570R180 S1      
327m9203            R462  -1          A18X+156803Y+127879X0180Y0200R180 S2      
327m9203            R1592 -1   M      A18X+156803Y+127879X0180Y0200     S2      
327m9203            R1553 -2          A01X+074090Y+052746X0198Y0197R090 S1      
327m9203            VIA   -    M      A18X+158407Y+127971X0260Y    R180 S2      
317m9203            VIA   -    MD0100PA00X+159718Y+128229X0200Y    R180 S0      
317m9203            VIA   -    MD0100PA00X+070108Y+007245X0200Y         S0      
317m9203            VIA   -    MD0100PA00X+074185Y+055354X0200Y    R180 S0      
327m9203            R455  -2   M      A18X+159960Y+127899X0198Y0197     S2      
317m9204            VIA   -    M      A01X+072858Y+053748X0200Y         S2      
017m9204            VIA   -    M      A18X+072858Y+053748X0260Y         S2      
017m9204                  -    MD0100PA00X+072858Y+053748                       
317m9204            VIA   -    MD0100PA00X+073981Y+048127X0180Y    R090 S0      
327m9204            U18   -P20        A01X+073828Y+047974X0160Y    R090 S1      
327m9204            R1557 -1          A01X+072850Y+054029X0198Y0197R090 S1      
327m9205            J41   -B3         A01X+069948Y+006516X0150Y0570R180 S1      
327m9205            R1197 -2          A18X+074213Y+057317X0198Y0197R180 S2      
327m9205            R8034 -2          A18X+073260Y+058204X0198Y0197R180 S2      
317m9205            VIA   -    MD0100PA00X+074120Y+057747X0200Y         S0      
327m9205            R8035 -2   M      A18X+074598Y+057317X0198Y0197     S2      
317m9205            VIA   -    M      A01X+069948Y+006998X0200Y         S2      
017m9205            VIA   -    M      A18X+069948Y+006998X0260Y         S2      
017m9205                  -    MD0100PA00X+069948Y+006998                       
327E1S_0_PWRDIS     R10296-1          A18X+093150Y+020161X0198Y0197     S2      
327E1S_0_PWRDIS     R3771 -2   M      A18X+093150Y+019761X0198Y0197R180 S2      
327E1S_0_PWRDIS     J90   -B12        A01X+093150Y+019356X0150Y0500R090 S1      
317E1S_0_PWRDIS     VIA   -    M      A01X+092339Y+019356X0200Y         S2      
017E1S_0_PWRDIS     VIA   -    M      A18X+092339Y+019356X0260Y         S2      
017E1S_0_PWRDIS           -    MD0100PA00X+092339Y+019356                       
327E1S_0_PRSNT_N    R6116 -2          A01X+062943Y+043788X0198Y0197R180 S1      
317E1S_0_PRSNT_N    VIA   -    MD0100PA00X+063228Y+044190X0200Y         S0      
317E1S_0_PRSNT_N    VIA   -    MD0100PA00X+076595Y+019067X0200Y         S0      
327E1S_0_PRSNT_N    R6052 -2          A01X+075900Y+036379X0198Y0197R270 S1      
317E1S_0_PRSNT_N    VIA   -    MD0100PA00X+076498Y+036805X0200Y         S0      
327E1S_0_PRSNT_N    R1304 -1          A18X+076350Y+039644X0198Y0197R090 S2      
317E1S_0_PRSNT_N    VIA   -    M      A01X+085621Y+019154X0200Y         S2      
017E1S_0_PRSNT_N    VIA   -    M      A18X+085621Y+019154X0260Y         S2      
017E1S_0_PRSNT_N          -    MD0100PA00X+085621Y+019154                       
327E1S_0_PRSNT_N    J90   -A12        A01X+091339Y+019356X0150Y0500R090 S1      
327m9206            R6094 -2          A01X+064292Y+043786X0198Y0197R180 S1      
317m9206            VIA   -    MD0100PA00X+063921Y+043819X0200Y         S0      
317m9206            VIA   -    MD0100PA00X+090902Y+029473X0200Y         S0      
317m9206            VIA   -    M      A01X+088935Y+019549X0200Y         S2      
017m9206            VIA   -    M      A18X+088935Y+019549X0260Y         S2      
017m9206                  -    MD0100PA00X+088935Y+019549                       
327m9206            J90   -A11        A01X+091339Y+019120X0150Y0500R090 S1      
327m9206            R2426 -1   M      A01X+088430Y+019206X0198Y0197R180 S1      
327m9206            R10287-2          A01X+088430Y+018745X0198Y0197     S1      
327m9207            U26   -A65        A01X+034200Y+087429X0177Y    R180 S1      
317m9207            VIA   -    MD0100PA00X+035328Y+085962X0200Y         S0      
327m9207            VIA   -    M      A18X+035907Y+083889X0260Y    R180 S2      
327m9207            R928  -1          A18X+035281Y+081815X0198Y0197R090 S2      
327m9208            U26   -A66        A01X+033830Y+087429X0177Y    R180 S1      
327m9208            VIA   -    M      A18X+036007Y+083139X0260Y    R180 S2      
327m9208            R862  -1          A18X+035631Y+081815X0198Y0197R090 S2      
317m9208            VIA   -    MD0100PA00X+035654Y+084971X0200Y         S0      
327m9209            U26   -C65        A01X+034200Y+088067X0177Y    R180 S1      
327m9209            VIA   -    M      A18X+035937Y+082469X0260Y    R180 S2      
327m9209            R618  -1          A18X+035981Y+081815X0198Y0197R090 S2      
317m9209            VIA   -    MD0100PA00X+035690Y+085979X0200Y         S0      
327m9210            U26   -C66        A01X+033830Y+088067X0177Y    R180 S1      
327m9210            VIA   -    M      A18X+036467Y+082485X0260Y    R180 S2      
327m9210            R486  -1          A18X+036331Y+081805X0198Y0197R090 S2      
317m9210            VIA   -    MD0100PA00X+035740Y+085598X0200Y         S0      
327m9211            R932  -2          A01X+001869Y+017522X0198Y0197R090 S1      
327m9211            J7    -7          A01X+002303Y+019722X0300Y0950R270 S1      
327m9211            VIA   -    M      A01X+001869Y+018032X0300Y         S1      
327m9212            R931  -2          A01X+001178Y+017505X0198Y0197R090 S1      
327m9212            J7    -5          A01X+002303Y+020222X0300Y0950R270 S1      
327m9212            VIA   -    M      A01X+000888Y+018093X0300Y         S1      
327m9213            R930  -2          A01X+001054Y+023022X0198Y0197R270 S1      
327m9213            J7    -3          A01X+002303Y+020722X0300Y0950R270 S1      
327m9213            VIA   -    M      A01X+000801Y+021922X0300Y         S1      
327m9214            R929  -2          A01X+001736Y+023017X0198Y0197R270 S1      
327m9214            J7    -1          A01X+002303Y+021222X0300Y0950R270 S1      
327m9214            VIA   -    M      A01X+001452Y+022369X0300Y         S1      
317CPU1_XTRIG_L7    VIA   -    MD0100PA00X+129552Y+038956X0200Y         S0      
317CPU1_XTRIG_L7    VIA   -    MD0100PA00X+070350Y+037436X0200Y         S0      
327CPU1_XTRIG_L7    R235  -1          A01X+070430Y+037679X0198Y0197R090 S1      
317CPU1_XTRIG_L7    J212  -8    D0440PA00X+136126Y+016421X0640Y    R270 S3      
327CPU1_XTRIG_L7    R928  -2          A18X+035281Y+081500X0198Y0197R090 S2      
327CPU1_XTRIG_L7    R540  -1          A18X+035281Y+080925X0198Y0197R090 S2      
317CPU1_XTRIG_L7    VIA   -    MD0100PA00X+035281Y+081219X0200Y    R180 S0      
317CPU1_XTRIG_L7    VIA   -    M      A01X+001869Y+016721X0200Y    R090 S2      
017CPU1_XTRIG_L7    VIA   -    M      A18X+001869Y+016721X0260Y    R090 S2      
017CPU1_XTRIG_L7          -    MD0100PA00X+001869Y+016721                       
327CPU1_XTRIG_L7    R932  -1          A01X+001869Y+017207X0198Y0197R090 S1      
317CPU1_XTRIG_L6    J212  -6    D0440PA00X+137126Y+016421X0640Y    R270 S3      
317CPU1_XTRIG_L6    VIA   -    MD0100PA00X+130223Y+038936X0200Y         S0      
317CPU1_XTRIG_L6    VIA   -    MD0100PA00X+065935Y+039394X0200Y         S0      
327CPU1_XTRIG_L6    R862  -2          A18X+035631Y+081500X0198Y0197R090 S2      
327CPU1_XTRIG_L6    R539  -1          A18X+035631Y+080925X0198Y0197R090 S2      
317CPU1_XTRIG_L6    VIA   -    MD0100PA00X+035631Y+081219X0200Y    R180 S0      
327CPU1_XTRIG_L6    R931  -1          A01X+001178Y+017190X0198Y0197R090 S1      
317CPU1_XTRIG_L6    VIA   -    M      A01X+001178Y+016704X0200Y    R090 S2      
017CPU1_XTRIG_L6    VIA   -    M      A18X+001178Y+016704X0260Y    R090 S2      
017CPU1_XTRIG_L6          -    MD0100PA00X+001178Y+016704                       
327CPU1_XTRIG_L6    R234  -1          A18X+067250Y+042200X0198Y0197R180 S2      
317CPU1_XTRIG_L5    J212  -4    D0440PA00X+138126Y+016421X0640Y    R270 S3      
327CPU1_XTRIG_L5    R618  -2          A18X+035981Y+081500X0198Y0197R090 S2      
327CPU1_XTRIG_L5    R538  -1          A18X+035981Y+080925X0198Y0197R090 S2      
317CPU1_XTRIG_L5    VIA   -    MD0100PA00X+035981Y+081219X0200Y    R180 S0      
327CPU1_XTRIG_L5    R930  -1          A01X+001054Y+023337X0198Y0197R270 S1      
317CPU1_XTRIG_L5    VIA   -    M      A01X+001968Y+023715X0200Y    R270 S2      
017CPU1_XTRIG_L5    VIA   -    M      A18X+001968Y+023715X0260Y    R270 S2      
017CPU1_XTRIG_L5          -    MD0100PA00X+001968Y+023715                       
327CPU1_XTRIG_L5    R205  -1          A18X+067244Y+041386X0198Y0197R180 S2      
317CPU1_XTRIG_L5    VIA   -    MD0100PA00X+066130Y+040986X0200Y    R270 S0      
317CPU1_XTRIG_L5    VIA   -    MD0100PA00X+130543Y+038936X0200Y         S0      
317CPU1_XTRIG_L4    J212  -2    D0440PA00X+139126Y+016421X0640Y    R270 S3      
327CPU1_XTRIG_L4    R486  -2          A18X+036331Y+081490X0198Y0197R090 S2      
327CPU1_XTRIG_L4    R537  -1          A18X+036331Y+080925X0198Y0197R090 S2      
317CPU1_XTRIG_L4    VIA   -    MD0100PA00X+036331Y+081209X0200Y    R180 S0      
327CPU1_XTRIG_L4    R929  -1          A01X+001736Y+023332X0198Y0197R270 S1      
317CPU1_XTRIG_L4    VIA   -    M      A01X+002241Y+023002X0200Y    R270 S2      
017CPU1_XTRIG_L4    VIA   -    M      A18X+002241Y+023002X0260Y    R270 S2      
017CPU1_XTRIG_L4          -    MD0100PA00X+002241Y+023002                       
317CPU1_XTRIG_L4    VIA   -    MD0100PA00X+069150Y+038246X0200Y         S0      
327CPU1_XTRIG_L4    R204  -1          A18X+069150Y+039329X0198Y0197R270 S2      
317CPU1_XTRIG_L4    VIA   -    MD0100PA00X+129903Y+038936X0200Y         S0      
317m9215            VIA   -    MD0080PA00X+049675Y+105038X0160Y         S0      
327m9215            U26   -BN23       A01X+049491Y+104933X0177Y    R180 S1      
317m9215            VIA   -    M      A01X+058427Y+126399X0200Y    R180 S2      
017m9215            VIA   -    M      A18X+058427Y+126399X0260Y    R180 S2      
017m9215                  -    MD0100PA00X+058427Y+126399                       
327m9215            R373  -2          A01X+058760Y+126667X0198Y0197R180 S1      
327m9215            R374  -2   M      A01X+058760Y+126267X0198Y0197R180 S1      
327m9216            R1533 -2          A18X+071944Y+038076X0198Y0197R090 S2      
317m9216            VIA   -    M      A01X+072353Y+036886X0200Y         S2      
017m9216            VIA   -    M      A18X+072353Y+036886X0260Y         S2      
017m9216                  -    MD0100PA00X+072353Y+036886                       
327m9216            U18   -J5         A01X+072253Y+043249X0160Y    R090 S1      
317m9216            VIA   -    MD0100PA00X+072099Y+043096X0180Y    R090 S0      
327m9216            R488  -2          A01X+072030Y+037994X0198Y0197R090 S1      
327m9217            U26   -DJ9        A01X+054672Y+116414X0177Y    R180 S1      
317m9217            VIA   -    MD0100PA00X+088373Y+065169X0200Y         S0      
317m9217            VIA   -    MD0100PA00X+071950Y+037436X0200Y    R270 S0      
327m9217            R488  -1          A01X+072030Y+037679X0198Y0197R090 S1      
317m9217            VIA   -    MD0100PA00X+084036Y+038281X0200Y         S0      
317m9217            VIA   -    M      A01X+088441Y+079433X0200Y         S2      
017m9217            VIA   -    M      A18X+088441Y+079433X0260Y         S2      
017m9217                  -    MD0100PA00X+088441Y+079433                       
317m9217            VIA   -    MD0100PA00X+056428Y+123119X0200Y    R180 S0      
327m9217            R536  -1          A18X+056899Y+123408X0198Y0197R180 S2      
327m9218            U26   -DE36       A01X+044680Y+115138X0177Y    R180 S1      
327m9218            VIA   -    M      A01X+055509Y+126559X0300Y    R180 S1      
327m9218            R570  -2          A01X+056451Y+126494X0198Y0197R270 S1      
327m9219            R194  -2          A18X+074296Y+053645X0198Y0197R090 S2      
317m9219            VIA   -    M      A01X+073918Y+052139X0200Y    R180 S2      
017m9219            VIA   -    M      A18X+073918Y+052139X0260Y    R180 S2      
017m9219                  -    MD0100PA00X+073918Y+052139                       
327m9219            U18   -L16        A01X+072883Y+046714X0160Y    R090 S1      
317m9219            VIA   -    MD0100PA00X+072729Y+046867X0180Y    R090 S0      
327m9220            R551  -1   M      A01X+056845Y+126809X0198Y0197R270 S1      
327m9220            R570  -1          A01X+056451Y+126809X0198Y0197R270 S1      
327m9220            VIA   -    M      A18X+075178Y+056447X0260Y         S2      
317m9220            VIA   -    MD0100PA00X+082279Y+078584X0200Y         S0      
317m9220            VIA   -    MD0100PA00X+075188Y+066672X0200Y         S0      
317m9220            VIA   -    MD0100PA00X+067527Y+143452X0200Y         S0      
327m9220            R194  -1          A18X+074296Y+053960X0198Y0197R090 S2      
317CPU1_SP5R4       VIA   -    MD0080PA00X+054671Y+116199X0160Y         S0      
327CPU1_SP5R4       U26   -DH10       A01X+054487Y+116095X0177Y    R180 S1      
317CPU1_SP5R4       VIA   -    M      A01X+005510Y+129268X0200Y         S2      
017CPU1_SP5R4       VIA   -    M      A18X+005510Y+129268X0260Y         S2      
017CPU1_SP5R4             -    MD0100PA00X+005510Y+129268                       
317CPU1_SP5R4       VIA   -    MD0100PA00X+062080Y+047470X0200Y         S0      
317CPU1_SP5R4       VIA   -    MD0100PA00X+063976Y+053344X0200Y         S0      
327CPU1_SP5R4       R269  -1          A18X+075150Y+039329X0198Y0197R270 S2      
317CPU1_SP5R4       VIA   -    MD0100PA00X+075150Y+039086X0200Y    R090 S0      
317CPU1_SP5R4       VIA   -    MD0100PA00X+067906Y+045514X0200Y         S0      
317CPU1_SP5R4       VIA   -    MD0100PA00X+042762Y+128042X0200Y         S0      
327CPU1_SP5R4       R513  -2          A18X+061320Y+126299X0198Y0197     S2      
317CPU1_SP5R4       VIA   -    MD0100PA00X+061055Y+126299X0200Y    R180 S0      
327CPU1_SP5R3       U26   -DH73       A01X+031172Y+116095X0177Y    R180 S1      
327CPU1_SP5R3       VIA   -    M      A18X+023077Y+125900X0260Y         S2      
317CPU1_SP5R3       VIA   -    MD0100PA00X+034788Y+120643X0200Y    R180 S0      
327CPU1_SP5R3       R515  -2          A18X+036185Y+120239X0198Y0197R180 S2      
317CPU1_SP5R3       VIA   -    MD0100PA00X+006055Y+127604X0200Y         S0      
317CPU1_SP5R3       VIA   -    MD0100PA00X+074770Y+033277X0200Y         S0      
317CPU1_SP5R3       VIA   -    MD0100PA00X+037963Y+049394X0200Y         S0      
317CPU1_SP5R3       VIA   -    MD0100PA00X+060681Y+042953X0200Y         S0      
317CPU1_SP5R3       VIA   -    MD0100PA00X+062639Y+033054X0200Y         S0      
317CPU1_SP5R3       VIA   -    MD0100PA00X+075635Y+036085X0200Y    R270 S0      
327CPU1_SP5R3       R268  -1          A18X+075550Y+039329X0198Y0197R270 S2      
327CPU1_SP5R2       U26   -C68        A01X+033090Y+088067X0177Y    R180 S1      
317CPU1_SP5R2       VIA   -    MD0100PA00X+028526Y+079931X0200Y    R180 S0      
317CPU1_SP5R2       VIA   -    M      A01X+043708Y+050186X0200Y    R180 S2      
017CPU1_SP5R2       VIA   -    M      A18X+043708Y+050186X0260Y    R180 S2      
017CPU1_SP5R2             -    MD0100PA00X+043708Y+050186                       
327CPU1_SP5R2       R261  -1          A18X+074346Y+038065X0198Y0197R270 S2      
317CPU1_SP5R2       VIA   -    MD0100PA00X+074350Y+036886X0200Y    R270 S0      
327CPU1_SP5R2       R517  -2          A18X+027785Y+080189X0198Y0197R180 S2      
317CPU1_SP5R1       VIA   -    MD0080PA00X+051037Y+087962X0160Y    R180 S0      
327CPU1_SP5R1       U26   -C19        A01X+050854Y+088067X0177Y    R180 S1      
317CPU1_SP5R1       VIA   -    MD0100PA00X+063341Y+049796X0200Y         S0      
317CPU1_SP5R1       VIA   -    MD0100PA00X+068135Y+068130X0200Y         S0      
327CPU1_SP5R1       R260  -1          A18X+075150Y+038079X0198Y0197R270 S2      
317CPU1_SP5R1       VIA   -    MD0100PA00X+075150Y+036886X0200Y    R270 S0      
317CPU1_SP5R1       VIA   -    MD0100PA00X+066358Y+073151X0200Y         S0      
327CPU1_SP5R1       VIA   -    M      A18X+062023Y+075162X0260Y    R180 S2      
327CPU1_SP5R1       R522  -2   M      A18X+057217Y+080031X0198Y0197R090 S2      
317CPU1_SMERR_N     VIA   -    MD0100PA00X+056467Y+123891X0200Y    R180 S0      
327CPU1_SMERR_N     U26   -DJ11       A01X+053932Y+116414X0177Y    R180 S1      
317CPU1_SMERR_N     VIA   -    MD0100PA00X+042402Y+127214X0200Y         S0      
327CPU1_SMERR_N     R193  -2          A18X+073761Y+051523X0198Y0197R270 S2      
317CPU1_SMERR_N     VIA   -    MD0100PA00X+072870Y+055094X0200Y         S0      
317CPU1_SMERR_N     VIA   -    M      A01X+064959Y+054008X0200Y         S2      
017CPU1_SMERR_N     VIA   -    M      A18X+064959Y+054008X0260Y         S2      
017CPU1_SMERR_N           -    MD0100PA00X+064959Y+054008                       
327CPU1_SMERR_N     R550  -1          A18X+056901Y+123816X0198Y0197R180 S2      
317CPU1_SLP_S5_N    VIA   -    MD0080PA00X+056707Y+115880X0160Y         S0      
317CPU1_SLP_S5_N    VIA   -    MD0100PA00X+060894Y+126599X0200Y    R180 S0      
327CPU1_SLP_S5_N    U26   -DG4        A01X+056523Y+115776X0177Y    R180 S1      
327CPU1_SLP_S5_N    R548  -1          A18X+061320Y+126699X0198Y0197R180 S2      
317CPU1_SLP_S5_N    VIA   -    MD0100PA00X+042762Y+127542X0200Y         S0      
317CPU1_SLP_S5_N    VIA   -    M      A01X+005510Y+129868X0200Y         S2      
017CPU1_SLP_S5_N    VIA   -    M      A18X+005510Y+129868X0260Y         S2      
017CPU1_SLP_S5_N          -    MD0100PA00X+005510Y+129868                       
327CPU1_SLP_S5_N    R191  -2          A01X+070050Y+051094X0198Y0197R090 S1      
317CPU1_SLP_S5_N    VIA   -    MD0100PA00X+069943Y+051334X0200Y    R180 S0      
317CPU1_SLP_S5_N    VIA   -    MD0100PA00X+027855Y+052304X0200Y         S0      
317CPU1_SLP_S3_N    VIA   -    MD0100PA00X+005510Y+128968X0200Y         S0      
317CPU1_SLP_S3_N    VIA   -    M      A01X+061559Y+128204X0200Y    R180 S2      
017CPU1_SLP_S3_N    VIA   -    M      A18X+061559Y+128204X0260Y    R180 S2      
017CPU1_SLP_S3_N          -    MD0100PA00X+061559Y+128204                       
327CPU1_SLP_S3_N    U26   -DJ5        A01X+056153Y+116414X0177Y    R180 S1      
317CPU1_SLP_S3_N    VIA   -    MD0100PA00X+064231Y+053577X0200Y         S0      
327CPU1_SLP_S3_N    R192  -2          A01X+069650Y+051094X0198Y0197R090 S1      
317CPU1_SLP_S3_N    VIA   -    MD0100PA00X+069411Y+053788X0200Y         S0      
317CPU1_SLP_S3_N    VIA   -    MD0100PA00X+042762Y+128292X0200Y         S0      
327CPU1_SLP_S3_N    R549  -1          A18X+061321Y+127867X0198Y0197R180 S2      
317CPU1_SA1         VIA   -    MD0080PA00X+037465Y+116518X0160Y         S0      
327CPU1_SA1         U26   -DJ56       A01X+037649Y+116414X0177Y    R180 S1      
317CPU1_SA1         VIA   -    M      A01X+064262Y+038930X0200Y         S2      
017CPU1_SA1         VIA   -    M      A18X+064262Y+038930X0260Y         S2      
017CPU1_SA1               -    MD0100PA00X+064262Y+038930                       
317CPU1_SA1         VIA   -    MD0100PA00X+077151Y+038686X0200Y         S0      
327CPU1_SA1         R267  -1          A18X+076750Y+039329X0198Y0197R270 S2      
327CPU1_SA1         R521  -1   M      A18X+035864Y+118786X0198Y0197R180 S2      
317CPU1_SA0         VIA   -    MD0080PA00X+037835Y+116518X0160Y         S0      
327CPU1_SA0         U26   -DJ55       A01X+038019Y+116414X0177Y    R180 S1      
317CPU1_SA0         VIA   -    M      A01X+063731Y+039368X0200Y         S2      
017CPU1_SA0         VIA   -    M      A18X+063731Y+039368X0260Y         S2      
017CPU1_SA0               -    MD0100PA00X+063731Y+039368                       
327CPU1_SA0         R266  -2          A18X+076350Y+038079X0198Y0197R090 S2      
317CPU1_SA0         VIA   -    MD0100PA00X+076433Y+037440X0200Y    R270 S0      
327CPU1_SA0         R518  -2   M      A18X+035776Y+119813X0198Y0197     S2      
327CPU1_SA0         R519  -1   M      A18X+035864Y+119392X0198Y0197R180 S2      
327CPU1_PWR_GD_IN   R252  -2          A01X+076500Y+054344X0198Y0197R090 S1      
327CPU1_PWR_GD_IN   R434  -2          A18X+160275Y+128299X0198Y0197R180 S2      
317CPU1_PWR_GD_IN   VIA   -    MD0100PA00X+160580Y+128617X0200Y    R180 S0      
327CPU1_PWR_GD_IN   U26   -DJ8        A01X+055042Y+116414X0177Y    R180 S1      
327CPU1_PWR_GD_IN   VIA   -    M      A18X+076278Y+057080X0260Y         S2      
317CPU1_PWR_GD_IN   VIA   -    MD0100PA00X+082277Y+078836X0200Y         S0      
317CPU1_PWR_GD_IN   VIA   -    MD0100PA00X+076266Y+066784X0200Y         S0      
317CPU1_PWR_GD_IN   VIA   -    MD0100PA00X+076834Y+056368X0200Y         S0      
317CPU1_PWR_GD_IN   VIA   -    MD0100PA00X+067367Y+143192X0200Y         S0      
317CPU1_PWRGD_OUT   VIA   -    MD0080PA00X+045049Y+116199X0160Y         S0      
327CPU1_PWRGD_OUT   U26   -DH36       A01X+044865Y+116095X0177Y    R180 S1      
317CPU1_PWRGD_OUT   VIA   -    M      A01X+056441Y+043164X0200Y         S2      
017CPU1_PWRGD_OUT   VIA   -    M      A18X+056441Y+043164X0260Y         S2      
017CPU1_PWRGD_OUT         -    MD0100PA00X+056441Y+043164                       
317CPU1_PWRGD_OUT   VIA   -    MD0100PA00X+078005Y+032827X0200Y         S0      
317CPU1_PWRGD_OUT   VIA   -    MD0100PA00X+054298Y+033453X0200Y         S0      
327CPU1_PWRGD_OUT   R195  -2          A01X+082399Y+045534X0198Y0197     S1      
317CPU1_PWRGD_OUT   VIA   -    MD0100PA00X+082875Y+045534X0200Y         S0      
327CPU1_PWRGD_OUT   R456  -1   M      A18X+037347Y+120754X0198Y0197     S2      
327CPU1_PWRGD_OUT   R491  -2   M      A18X+037347Y+121154X0198Y0197R180 S2      
327CPU1_PROCHOT_N   U26   -A69        A01X+032720Y+087429X0177Y    R180 S1      
327CPU1_PROCHOT_N   VIA   -    M      A01X+026327Y+077199X0300Y    R180 S1      
317CPU1_PROCHOT_N   VIA   -    MD0100PA00X+023298Y+074398X0200Y         S0      
317CPU1_PROCHOT_N   VIA   -    MD0100PA00X+045742Y+049798X0200Y    R180 S0      
317CPU1_PROCHOT_N   VIA   -    MD0100PA00X+072350Y+039086X0200Y    R090 S0      
327CPU1_PROCHOT_N   R270  -2          A01X+072350Y+039329X0198Y0197R270 S1      
327CPU1_PROCHOT_N   R520  -1          A18X+023320Y+074900X0198Y0197R270 S2      
327CPU1_NV_SAVE_N   R196  -1          A01X+072303Y+052739X0198Y0197R270 S1      
327CPU1_NV_SAVE_N   U26   -B64        A01X+034385Y+087748X0177Y    R180 S1      
317CPU1_NV_SAVE_N   VIA   -    MD0100PA00X+026899Y+078325X0200Y    R180 S0      
317CPU1_NV_SAVE_N   VIA   -    M      A01X+046864Y+051410X0200Y         S2      
017CPU1_NV_SAVE_N   VIA   -    M      A18X+046864Y+051410X0260Y         S2      
017CPU1_NV_SAVE_N         -    MD0100PA00X+046864Y+051410                       
317CPU1_NV_SAVE_N   VIA   -    MD0100PA00X+072050Y+053347X0200Y         S0      
327CPU1_NV_SAVE_N   R553  -1          A18X+026615Y+078479X0198Y0197     S2      
317m9221            VIA   -    MD0080PA00X+046714Y+116518X0160Y         S0      
327m9221            U26   -DJ31       A01X+046531Y+116414X0177Y    R180 S1      
327m9221            R277  -2          A01X+075650Y+051094X0198Y0197R090 S1      
317m9221            VIA   -    MD0100PA00X+075650Y+051334X0200Y         S0      
317m9221            VIA   -    MD0100PA00X+063076Y+050587X0200Y         S0      
317m9221            VIA   -    M      A01X+052910Y+045205X0200Y         S2      
017m9221            VIA   -    M      A18X+052910Y+045205X0260Y         S2      
017m9221                  -    MD0100PA00X+052910Y+045205                       
327m9221            R562  -2          A18X+061321Y+127480X0198Y0197     S2      
327m9222            VIA   -    M      A18X+073620Y+049300X0260Y    R090 S2      
327m9222            U18   -R16        A01X+074143Y+046714X0160Y    R090 S1      
327m9222            R161  -1          A18X+073644Y+049777X0198Y0197R270 S2      
317m9222            VIA   -    MD0100PA00X+074296Y+046867X0180Y    R090 S0      
317m9223            VIA   -    M      A01X+108287Y+040307X0200Y         S2      
017m9223            VIA   -    M      A18X+108287Y+040307X0260Y         S2      
017m9223                  -    MD0100PA00X+108287Y+040307                       
327m9223            U151  -9          A01X+109711Y+039338X0140Y0630R090 S1      
317m9223            VIA   -    MD0100PA00X+105096Y+059109X0200Y         S0      
317m9223            VIA   -    MD0100PA00X+074050Y+051336X0200Y    R180 S0      
327m9223            R161  -2          A18X+073644Y+050092X0198Y0197R270 S2      
317m9223            VIA   -    MD0100PA00X+074162Y+058071X0200Y         S0      
317m9224            VIA   -    MD0100PA00X+092099Y+061413X0200Y         S0      
327m9224            U154  -7          A01X+091689Y+062863X0140Y0520R090 S1      
327m9224            U14   -7   M      A01X+091689Y+061413X0140Y0520R090 S1      
317m9224            VIA   -    M      A01X+084794Y+053832X0200Y         S2      
017m9224            VIA   -    M      A18X+084794Y+053832X0260Y         S2      
017m9224                  -    MD0100PA00X+084794Y+053832                       
327m9224            R1649 -2          A01X+084187Y+053826X0198Y0197R090 S1      
327m9224            Q64   -G          A01X+085518Y+053832X0400Y0560R270 S1      
327m9224            R173  -2          A01X+075650Y+052744X0198Y0197R090 S1      
317m9224            VIA   -    MD0100PA00X+075619Y+052989X0200Y         S0      
317m9225            VIA   -    MD0080PA00X+052821Y+116199X0160Y         S0      
317m9225            VIA   -    MD0100PA00X+061190Y+053518X0200Y         S0      
317m9225            VIA   -    M      A01X+057212Y+043704X0200Y         S2      
017m9225            VIA   -    M      A18X+057212Y+043704X0260Y         S2      
017m9225                  -    MD0100PA00X+057212Y+043704                       
327m9225            U26   -DH15       A01X+052637Y+116095X0177Y    R180 S1      
327m9225            R547  -1          A18X+056903Y+124210X0198Y0197R180 S2      
317m9225            VIA   -    MD0100PA00X+056135Y+122855X0200Y    R180 S0      
317m9225            VIA   -    MD0100PA00X+042402Y+126714X0200Y         S0      
327m9225            R190  -1          A01X+070750Y+039329X0198Y0197R090 S1      
317m9225            VIA   -    MD0100PA00X+070750Y+039086X0200Y    R090 S0      
327m9226            R6503 -1          A18X+026615Y+077541X0198Y0197     S2      
327m9226            U26   -B63        A01X+034755Y+087748X0177Y    R180 S1      
317m9226            VIA   -    M      A01X+027116Y+078059X0200Y    R180 S2      
017m9226            VIA   -    M      A18X+027116Y+078059X0260Y    R180 S2      
017m9226                  -    MD0100PA00X+027116Y+078059                       
317m9226            VIA   -    MD0100PA00X+045208Y+051187X0200Y    R090 S0      
327m9226            R265  -2          A18X+077823Y+049934X0198Y0197R180 S2      
317m9226            VIA   -    MD0100PA00X+078335Y+049922X0200Y    R180 S0      
327m9226            R558  -1   M      A18X+026615Y+078059X0198Y0197     S2      
317CPU1_CORETYPE2   VIA   -    MD0080PA00X+032721Y+088281X0160Y    R180 S0      
327CPU1_CORETYPE2   U26   -D68        A01X+032905Y+088386X0177Y    R180 S1      
317CPU1_CORETYPE2   VIA   -    M      A01X+046044Y+049984X0200Y    R180 S2      
017CPU1_CORETYPE2   VIA   -    M      A18X+046044Y+049984X0260Y    R180 S2      
017CPU1_CORETYPE2         -    MD0100PA00X+046044Y+049984                       
317CPU1_CORETYPE2   VIA   -    MD0100PA00X+075550Y+039086X0200Y    R090 S0      
327CPU1_CORETYPE2   R264  -1          A01X+075550Y+039329X0198Y0197R090 S1      
327CPU1_CORETYPE2   R512  -2          A18X+026897Y+080276X0198Y0197R270 S2      
327CPU1_CORETYPE1   U26   -B69        A01X+032535Y+087748X0177Y    R180 S1      
317CPU1_CORETYPE1   VIA   -    M      A01X+025707Y+077277X0200Y    R180 S2      
017CPU1_CORETYPE1   VIA   -    M      A18X+025707Y+077277X0260Y    R180 S2      
017CPU1_CORETYPE1         -    MD0100PA00X+025707Y+077277                       
317CPU1_CORETYPE1   VIA   -    MD0100PA00X+075165Y+038686X0200Y    R090 S0      
327CPU1_CORETYPE1   R263  -1          A01X+075150Y+039329X0198Y0197R090 S1      
327CPU1_CORETYPE1   R514  -2          A18X+025205Y+077239X0198Y0197R180 S2      
327CPU1_CORETYPE0   U26   -C70        A01X+032350Y+088067X0177Y    R180 S1      
317CPU1_CORETYPE0   VIA   -    MD0100PA00X+025467Y+077639X0200Y    R180 S0      
317CPU1_CORETYPE0   VIA   -    M      A01X+073950Y+036886X0200Y    R270 S2      
017CPU1_CORETYPE0   VIA   -    M      A18X+073950Y+036886X0260Y    R270 S2      
017CPU1_CORETYPE0         -    MD0100PA00X+073950Y+036886                       
327CPU1_CORETYPE0   R262  -1          A18X+073946Y+038065X0198Y0197R270 S2      
327CPU1_CORETYPE0   R516  -2          A18X+025205Y+077639X0198Y0197R180 S2      
327CPU1_BP3         U26   -A62        A01X+035310Y+087429X0177Y    R180 S1      
317CPU1_BP3         VIA   -    MD0100PA00X+036482Y+086185X0200Y         S0      
317CPU1_BP3         VIA   -    M      A01X+009378Y+019724X0200Y         S2      
017CPU1_BP3         VIA   -    M      A18X+009378Y+019724X0260Y         S2      
017CPU1_BP3               -    MD0100PA00X+009378Y+019724                       
327CPU1_BP3         J49   -7          A01X+010598Y+019724X0300Y0950R270 S1      
327CPU1_BP3         R534  -1          A18X+036681Y+080925X0198Y0197R090 S2      
327CPU1_BP2         U26   -A63        A01X+034940Y+087429X0177Y    R180 S1      
317CPU1_BP2         VIA   -    MD0100PA00X+036490Y+085256X0200Y         S0      
317CPU1_BP2         VIA   -    M      A01X+009378Y+020224X0200Y         S2      
017CPU1_BP2         VIA   -    M      A18X+009378Y+020224X0260Y         S2      
017CPU1_BP2               -    MD0100PA00X+009378Y+020224                       
327CPU1_BP2         J49   -5          A01X+010598Y+020224X0300Y0950R270 S1      
327CPU1_BP2         R533  -1          A18X+037031Y+080925X0198Y0197R090 S2      
327CPU1_BP1         U26   -C62        A01X+035310Y+088067X0177Y    R180 S1      
317CPU1_BP1         VIA   -    MD0100PA00X+036963Y+086072X0200Y         S0      
317CPU1_BP1         VIA   -    M      A01X+009378Y+020724X0200Y         S2      
017CPU1_BP1         VIA   -    M      A18X+009378Y+020724X0260Y         S2      
017CPU1_BP1               -    MD0100PA00X+009378Y+020724                       
327CPU1_BP1         J49   -3          A01X+010598Y+020724X0300Y0950R270 S1      
327CPU1_BP1         R532  -1          A18X+037381Y+080925X0198Y0197R090 S2      
327CPU1_BP0         U26   -C63        A01X+034940Y+088067X0177Y    R180 S1      
317CPU1_BP0         VIA   -    MD0100PA00X+036686Y+085727X0200Y         S0      
317CPU1_BP0         VIA   -    M      A01X+009378Y+021224X0200Y         S2      
017CPU1_BP0         VIA   -    M      A18X+009378Y+021224X0260Y         S2      
017CPU1_BP0               -    MD0100PA00X+009378Y+021224                       
327CPU1_BP0         J49   -1          A01X+010598Y+021224X0300Y0950R270 S1      
327CPU1_BP0         R531  -1          A18X+037731Y+080925X0198Y0197R090 S2      
327m9227            U25   -A65        A01X+131814Y+087429X0177Y    R180 S1      
327m9227            VIA   -    M      A01X+129668Y+077089X0300Y    R180 S1      
327m9227            R357  -1          A01X+129668Y+076556X0198Y0197R270 S1      
327m9228            U25   -A66        A01X+131444Y+087429X0177Y    R180 S1      
327m9228            VIA   -    M      A01X+129068Y+077139X0300Y    R180 S1      
327m9228            R356  -1          A01X+129268Y+076556X0198Y0197R270 S1      
317m9229            VIA   -    MD0080PA00X+131630Y+087962X0160Y    R180 S0      
327m9229            U25   -C65        A01X+131814Y+088067X0177Y    R180 S1      
327m9229            VIA   -    M      A18X+129945Y+080109X0260Y    R180 S2      
327m9229            R157  -1          A18X+128983Y+080130X0198Y0197     S2      
317m9230            VIA   -    MD0080PA00X+131260Y+087962X0160Y    R180 S0      
327m9230            U25   -C66        A01X+131444Y+088067X0177Y    R180 S1      
327m9230            VIA   -    M      A18X+129445Y+080109X0260Y    R180 S2      
327m9230            R156  -1          A18X+128268Y+080440X0198Y0197R090 S2      
327m9231            J5    -7          A01X+135768Y+025159X0300Y0950R090 S1      
327m9231            VIA   -    M      A01X+137266Y+025159X0300Y    R180 S1      
327m9231            R485  -2          A01X+137814Y+025159X0198Y0197R180 S1      
327m9232            J5    -5          A01X+135768Y+024659X0300Y0950R090 S1      
327m9232            R484  -2          A01X+137814Y+024659X0198Y0197R180 S1      
327m9232            VIA   -    M      A01X+137266Y+024659X0300Y    R180 S1      
327m9233            J5    -3          A01X+135768Y+024159X0300Y0950R090 S1      
327m9233            R483  -2          A01X+137814Y+024159X0198Y0197R180 S1      
327m9233            VIA   -    M      A01X+137266Y+024159X0300Y    R180 S1      
327m9234            J5    -1          A01X+135768Y+023659X0300Y0950R090 S1      
327m9234            R481  -2          A01X+137814Y+023659X0198Y0197R180 S1      
327m9234            VIA   -    M      A01X+137266Y+023659X0300Y    R180 S1      
317CPU0_XTRIG_L7    VIA   -    MD0100PA00X+143140Y+053340X0200Y         S0      
317CPU0_XTRIG_L7    VIA   -    MD0100PA00X+139530Y+025614X0200Y    R180 S0      
327CPU0_XTRIG_L7    R485  -1          A01X+138129Y+025159X0198Y0197R180 S1      
327CPU0_XTRIG_L7    R477  -1          A01X+159088Y+023925X0198Y0197R180 S1      
317CPU0_XTRIG_L7    VIA   -    MD0100PA00X+159330Y+023925X0200Y    R090 S0      
317CPU0_XTRIG_L7    J212  -7    D0440PA00X+136126Y+017421X0640Y    R270 S3      
327CPU0_XTRIG_L7    R416  -1          A01X+130068Y+076206X0198Y0197R270 S1      
327CPU0_XTRIG_L7    R357  -2   M      A01X+129668Y+076241X0198Y0197R270 S1      
327CPU0_XTRIG_L7    R239  -1          A01X+070030Y+037679X0198Y0197R090 S1      
317CPU0_XTRIG_L7    VIA   -    MD0100PA00X+069950Y+037436X0200Y         S0      
317CPU0_XTRIG_L7    VIA   -    MD0100PA00X+066619Y+059866X0200Y         S0      
317CPU0_XTRIG_L7    VIA   -    MD0100PA00X+130510Y+066210X0200Y         S0      
317CPU0_XTRIG_L7    VIA   -    M      A01X+112032Y+063583X0200Y    R270 S2      
017CPU0_XTRIG_L7    VIA   -    M      A18X+112032Y+063583X0260Y    R270 S2      
017CPU0_XTRIG_L7          -    MD0100PA00X+112032Y+063583                       
317CPU0_XTRIG_L6    VIA   -    MD0100PA00X+143540Y+053620X0200Y         S0      
327CPU0_XTRIG_L6    R484  -1          A01X+138129Y+024659X0198Y0197R180 S1      
317CPU0_XTRIG_L6    VIA   -    MD0100PA00X+139530Y+025114X0200Y    R180 S0      
327CPU0_XTRIG_L6    R476  -1          A01X+159088Y+023425X0198Y0197R180 S1      
317CPU0_XTRIG_L6    VIA   -    MD0100PA00X+159330Y+023425X0200Y    R090 S0      
317CPU0_XTRIG_L6    J212  -5    D0440PA00X+137126Y+017421X0640Y    R270 S3      
327CPU0_XTRIG_L6    R415  -1          A01X+128868Y+076206X0198Y0197R270 S1      
327CPU0_XTRIG_L6    R356  -2   M      A01X+129268Y+076241X0198Y0197R270 S1      
327CPU0_XTRIG_L6    R238  -1          A01X+069080Y+037679X0198Y0197R090 S1      
317CPU0_XTRIG_L6    VIA   -    MD0100PA00X+069550Y+037436X0200Y         S0      
317CPU0_XTRIG_L6    VIA   -    MD0100PA00X+066299Y+059866X0200Y         S0      
317CPU0_XTRIG_L6    VIA   -    M      A01X+130250Y+066450X0200Y         S2      
017CPU0_XTRIG_L6    VIA   -    M      A18X+130250Y+066450X0260Y         S2      
017CPU0_XTRIG_L6          -    MD0100PA00X+130250Y+066450                       
317CPU0_XTRIG_L5    J212  -3    D0440PA00X+138126Y+017421X0640Y    R270 S3      
317CPU0_XTRIG_L5    VIA   -    MD0100PA00X+123522Y+077721X0200Y    R180 S0      
317CPU0_XTRIG_L5    VIA   -    MD0100PA00X+157333Y+054335X0200Y         S0      
327CPU0_XTRIG_L5    R237  -1          A01X+069550Y+039329X0198Y0197R090 S1      
317CPU0_XTRIG_L5    VIA   -    MD0100PA00X+069550Y+039086X0200Y    R090 S0      
317CPU0_XTRIG_L5    VIA   -    MD0100PA00X+070455Y+065524X0200Y         S0      
317CPU0_XTRIG_L5    VIA   -    MD0100PA00X+111219Y+065196X0200Y    R270 S0      
327CPU0_XTRIG_L5    R478  -1          A01X+159088Y+024425X0198Y0197R180 S1      
317CPU0_XTRIG_L5    VIA   -    MD0100PA00X+159330Y+024425X0200Y    R090 S0      
317CPU0_XTRIG_L5    VIA   -    M      A01X+138372Y+024159X0200Y    R180 S2      
017CPU0_XTRIG_L5    VIA   -    M      A18X+138372Y+024159X0260Y    R180 S2      
017CPU0_XTRIG_L5          -    MD0100PA00X+138372Y+024159                       
327CPU0_XTRIG_L5    R483  -1          A01X+138129Y+024159X0198Y0197R180 S1      
327CPU0_XTRIG_L5    R157  -2          A18X+128668Y+080130X0198Y0197     S2      
327CPU0_XTRIG_L5    R414  -1   M      A18X+128668Y+079730X0198Y0197R090 S2      
317CPU0_XTRIG_L4    VIA   -    MD0100PA00X+143130Y+053880X0200Y         S0      
317CPU0_XTRIG_L4    VIA   -    M      A01X+138372Y+023659X0200Y    R180 S2      
017CPU0_XTRIG_L4    VIA   -    M      A18X+138372Y+023659X0260Y    R180 S2      
017CPU0_XTRIG_L4          -    MD0100PA00X+138372Y+023659                       
327CPU0_XTRIG_L4    R481  -1          A01X+138129Y+023659X0198Y0197R180 S1      
317CPU0_XTRIG_L4    VIA   -    MD0100PA00X+159366Y+025201X0200Y         S0      
317CPU0_XTRIG_L4    J212  -1    D0440PA00X+139126Y+017421X0640Y0640R270 S3      
317CPU0_XTRIG_L4    VIA   -    MD0100PA00X+123308Y+077258X0200Y    R180 S0      
327CPU0_XTRIG_L4    R236  -1          A01X+069950Y+039329X0198Y0197R090 S1      
317CPU0_XTRIG_L4    VIA   -    MD0100PA00X+069950Y+039086X0200Y    R090 S0      
317CPU0_XTRIG_L4    VIA   -    MD0100PA00X+070783Y+065532X0200Y         S0      
317CPU0_XTRIG_L4    VIA   -    MD0100PA00X+130770Y+066460X0200Y         S0      
317CPU0_XTRIG_L4    VIA   -    MD0100PA00X+111654Y+065107X0200Y    R270 S0      
327CPU0_XTRIG_L4    R156  -2          A18X+128268Y+080125X0198Y0197R090 S2      
327CPU0_XTRIG_L4    R413  -1   M      A18X+128268Y+079730X0198Y0197R090 S2      
327m9235            R1533 -1          A18X+071944Y+038391X0198Y0197R090 S2      
327m9235            R489  -2          A18X+071470Y+038395X0198Y0197R270 S2      
327m9235            VIA   -    M      A18X+071750Y+040196X0260Y    R090 S2      
317m9235            VIA   -    MD0100PA00X+071784Y+042151X0180Y    R090 S0      
327m9235            U18   -H2         A01X+071938Y+042304X0160Y    R090 S1      
327m9236            VIA   -    M      A18X+072957Y+036303X0260Y         S2      
317m9236            VIA   -    MD0100PA00X+153859Y+124506X0200Y    R180 S0      
327m9236            R417  -1          A01X+156016Y+126279X0198Y0197R090 S1      
327m9236            U25   -DJ9        A01X+152287Y+116413X0177Y    R180 S1      
317m9236            VIA   -    MD0100PA00X+087746Y+080236X0200Y         S0      
327m9236            R489  -1          A18X+071470Y+038080X0198Y0197R270 S2      
317m9236            VIA   -    MD0100PA00X+088592Y+065391X0200Y         S0      
317m9236            VIA   -    MD0100PA00X+073417Y+036078X0200Y    R270 S0      
317m9236            VIA   -    MD0100PA00X+083322Y+037599X0200Y         S0      
327m9237            VIA   -    M      A18X+074999Y+049278X0260Y    R090 S2      
327m9237            U18   -R18        A01X+074143Y+047344X0160Y    R090 S1      
317m9237            VIA   -    MD0100PA00X+074296Y+047497X0180Y    R090 S0      
327m9237            R251  -1          A18X+075197Y+049788X0198Y0197R270 S2      
317m9238            VIA   -    MD0080PA00X+142478Y+115242X0160Y         S0      
327m9238            R251  -2          A18X+075197Y+050103X0198Y0197R270 S2      
327m9238            U25   -DE36       A01X+142294Y+115138X0177Y    R180 S1      
317m9238            VIA   -    M      A01X+159092Y+130928X0200Y    R180 S2      
017m9238            VIA   -    M      A18X+159092Y+130928X0260Y    R180 S2      
017m9238                  -    MD0100PA00X+159092Y+130928                       
327m9238            R451  -1          A18X+159285Y+130413X0198Y0197R090 S2      
317m9238            VIA   -    MD0100PA00X+074866Y+051706X0200Y    R180 S0      
317m9238            VIA   -    MD0100PA00X+084744Y+055550X0200Y         S0      
327CPU0_SP5R4       U25   -DH10       A01X+152102Y+116094X0177Y    R180 S1      
317CPU0_SP5R4       VIA   -    MD0100PA00X+075950Y+039079X0200Y    R090 S0      
327CPU0_SP5R4       R223  -2          A01X+076350Y+039329X0198Y0197R270 S1      
317CPU0_SP5R4       VIA   -    MD0100PA00X+104752Y+044440X0200Y         S0      
317CPU0_SP5R4       VIA   -    MD0100PA00X+113234Y+047170X0200Y         S0      
317CPU0_SP5R4       VIA   -    MD0100PA00X+154398Y+125831X0200Y    R180 S0      
327CPU0_SP5R4       VIA   -    M      A01X+154284Y+126593X0300Y    R180 S1      
327CPU0_SP5R4       R389  -2          A01X+154710Y+127019X0198Y0197R180 S1      
317CPU0_SP5R3       VIA   -    MD0100PA00X+131172Y+122104X0200Y         S0      
327CPU0_SP5R3       U25   -DH73       A01X+128787Y+116094X0177Y    R180 S1      
317CPU0_SP5R3       VIA   -    MD0100PA00X+103019Y+073502X0200Y         S0      
327CPU0_SP5R3       R222  -1          A01X+075950Y+039329X0198Y0197R090 S1      
317CPU0_SP5R3       VIA   -    MD0100PA00X+075950Y+038686X0200Y    R090 S0      
327CPU0_SP5R3       VIA   -    M      A01X+075480Y+037992X0300Y    R090 S1      
327CPU0_SP5R3       R391  -2   M      A01X+075950Y+037994X0198Y0197R090 S1      
317CPU0_SP5R3       VIA   -    MD0100PA00X+103490Y+044440X0200Y         S0      
317CPU0_SP5R2       VIA   -    MD0080PA00X+130520Y+087962X0160Y    R180 S0      
327CPU0_SP5R2       U25   -C68        A01X+130704Y+088067X0177Y    R180 S1      
327CPU0_SP5R2       R396  -2          A18X+127318Y+080440X0198Y0197R270 S2      
317CPU0_SP5R2       VIA   -    MD0100PA00X+127518Y+080896X0200Y    R180 S0      
317CPU0_SP5R2       VIA   -    MD0100PA00X+065861Y+059953X0200Y         S0      
317CPU0_SP5R2       VIA   -    M      A01X+110808Y+064677X0200Y         S2      
017CPU0_SP5R2       VIA   -    M      A18X+110808Y+064677X0260Y         S2      
017CPU0_SP5R2             -    MD0100PA00X+110808Y+064677                       
317CPU0_SP5R2       VIA   -    MD0100PA00X+057784Y+043715X0200Y         S0      
327CPU0_SP5R2       R181  -1          A18X+073550Y+039329X0198Y0197R270 S2      
317CPU0_SP5R2       VIA   -    MD0100PA00X+073150Y+038686X0200Y    R090 S0      
317CPU0_SP5R1       VIA   -    MD0080PA00X+148652Y+087962X0160Y    R180 S0      
327CPU0_SP5R1       U25   -C19        A01X+148468Y+088067X0177Y    R180 S1      
317CPU0_SP5R1       VIA   -    MD0100PA00X+146995Y+081323X0200Y         S0      
327CPU0_SP5R1       R397  -2          A01X+073545Y+037195X0198Y0197R270 S1      
317CPU0_SP5R1       VIA   -    M      A01X+094560Y+066465X0200Y         S2      
017CPU0_SP5R1       VIA   -    M      A18X+094560Y+066465X0260Y         S2      
017CPU0_SP5R1             -    MD0100PA00X+094560Y+066465                       
317CPU0_SP5R1       VIA   -    MD0100PA00X+073550Y+036886X0200Y    R270 S0      
327CPU0_SP5R1       R180  -1          A18X+073546Y+038065X0198Y0197R270 S2      
317CPU0_SP5R1       VIA   -    MD0100PA00X+092310Y+036285X0200Y         S0      
317CPU0_SMERR_N     VIA   -    M      A01X+102451Y+050017X0200Y         S2      
017CPU0_SMERR_N     VIA   -    M      A18X+102451Y+050017X0260Y         S2      
017CPU0_SMERR_N           -    MD0100PA00X+102451Y+050017                       
317CPU0_SMERR_N     VIA   -    MD0100PA00X+154275Y+125360X0200Y    R180 S0      
327CPU0_SMERR_N     U25   -DJ11       A01X+151546Y+116413X0177Y    R180 S1      
317CPU0_SMERR_N     VIA   -    MD0100PA00X+073250Y+051336X0200Y    R180 S0      
327CPU0_SMERR_N     R250  -2          A01X+073250Y+051094X0198Y0197R090 S1      
317CPU0_SMERR_N     VIA   -    MD0100PA00X+113234Y+046820X0200Y         S0      
327CPU0_SMERR_N     R450  -1          A01X+154710Y+127819X0198Y0197     S1      
317CPU0_SLP_S5_N    VIA   -    MD0080PA00X+154321Y+115880X0160Y         S0      
327CPU0_SLP_S5_N    R248  -2          A01X+068850Y+054344X0198Y0197R090 S1      
317CPU0_SLP_S5_N    VIA   -    M      A01X+086850Y+077652X0300Y         S1      
017CPU0_SLP_S5_N    VIA   -    M      A18X+086850Y+077652X0200Y         S1      
017CPU0_SLP_S5_N          -    MD0100PA00X+086850Y+077652                       
327CPU0_SLP_S5_N    U25   -DG4        A01X+154137Y+115776X0177Y    R180 S1      
317CPU0_SLP_S5_N    VIA   -    MD0100PA00X+152931Y+117747X0200Y         S0      
317CPU0_SLP_S5_N    VIA   -    MD0100PA00X+155052Y+123290X0200Y    R180 S0      
327CPU0_SLP_S5_N    R448  -1          A01X+159118Y+126221X0198Y0197R090 S1      
327CPU0_SLP_S3_N    R249  -2          A01X+069250Y+051094X0198Y0197R090 S1      
317CPU0_SLP_S3_N    VIA   -    M      A01X+087059Y+078544X0200Y         S2      
017CPU0_SLP_S3_N    VIA   -    M      A18X+087059Y+078544X0260Y         S2      
017CPU0_SLP_S3_N          -    MD0100PA00X+087059Y+078544                       
327CPU0_SLP_S3_N    U25   -DJ5        A01X+153767Y+116413X0177Y    R180 S1      
327CPU0_SLP_S3_N    R449  -1          A01X+158718Y+126221X0198Y0197R090 S1      
317CPU0_SLP_S3_N    VIA   -    MD0100PA00X+154836Y+123475X0200Y    R180 S0      
327CPU0_SA1         R394  -1          A18X+132948Y+121580X0198Y0197R270 S2      
317CPU0_SA1         VIA   -    MD0100PA00X+132703Y+120679X0200Y         S0      
327CPU0_SA1         U25   -DJ56       A01X+135263Y+116413X0177Y    R180 S1      
317CPU0_SA1         VIA   -    MD0100PA00X+103274Y+073532X0200Y         S0      
317CPU0_SA1         VIA   -    M      A01X+103902Y+044440X0300Y         S1      
017CPU0_SA1         VIA   -    M      A18X+103902Y+044440X0200Y         S1      
017CPU0_SA1               -    MD0100PA00X+103902Y+044440                       
327CPU0_SA1         R221  -2          A18X+074750Y+039329X0198Y0197R090 S2      
317CPU0_SA1         VIA   -    MD0100PA00X+074750Y+039086X0200Y    R090 S0      
327CPU0_SA0         R392  -2   M      A18X+133398Y+121580X0198Y0197R090 S2      
327CPU0_SA0         R393  -1          A18X+133798Y+121580X0198Y0197R270 S2      
317CPU0_SA0         VIA   -    MD0100PA00X+132899Y+120979X0200Y         S0      
327CPU0_SA0         U25   -DJ55       A01X+135633Y+116413X0177Y    R180 S1      
317CPU0_SA0         VIA   -    M      A01X+104202Y+044440X0200Y         S2      
017CPU0_SA0         VIA   -    M      A18X+104202Y+044440X0260Y         S2      
017CPU0_SA0               -    MD0100PA00X+104202Y+044440                       
327CPU0_SA0         R220  -2          A18X+075950Y+039329X0198Y0197R090 S2      
317CPU0_SA0         VIA   -    MD0100PA00X+075550Y+038686X0200Y    R090 S0      
317CPU0_SA0         VIA   -    MD0100PA00X+103527Y+073547X0200Y         S0      
317m9239            VIA   -    MD0080PA00X+143959Y+115880X0160Y         S0      
327m9239            U25   -DG32       A01X+143775Y+115776X0177Y    R180 S1      
327m9239            VIA   -    M      A18X+143959Y+119358X0260Y    R180 S2      
327m9239            R748  -2   M      A18X+158890Y+129529X0198Y0197     S2      
327m9239            R737  -2          A18X+158890Y+129129X0198Y0197     S2      
327CPU0_PWR_GOOD    U25   -DJ8        A01X+152657Y+116413X0177Y    R180 S1      
327CPU0_PWR_GOOD    R287  -2   M      A01X+157918Y+126221X0198Y0197R270 S1      
327CPU0_PWR_GOOD    R276  -1          A01X+158318Y+126221X0198Y0197R090 S1      
317CPU0_PWR_GOOD    VIA   -    M      A01X+155111Y+123809X0200Y    R180 S2      
017CPU0_PWR_GOOD    VIA   -    M      A18X+155111Y+123809X0260Y    R180 S2      
017CPU0_PWR_GOOD          -    MD0100PA00X+155111Y+123809                       
317CPU0_PWR_GOOD    VIA   -    MD0100PA00X+079725Y+044334X0200Y         S0      
327CPU0_PWR_GOOD    R218  -1          A01X+079268Y+044334X0198Y0197R180 S1      
317CPU0_PWR_GOOD    VIA   -    MD0100PA00X+080520Y+062035X0200Y         S0      
317CPU0_PWR_GOOD    VIA   -    MD0100PA00X+086854Y+079088X0200Y         S0      
317m9240            VIA   -    MD0080PA00X+142663Y+116199X0160Y         S0      
327m9240            U25   -DH36       A01X+142480Y+116094X0177Y    R180 S1      
327m9240            VIA   -    M      A18X+158611Y+131294X0260Y    R180 S2      
327m9240            R288  -1   M      A18X+159960Y+129099X0198Y0197R180 S2      
327m9240            R434  -1          A18X+159960Y+128299X0198Y0197R180 S2      
327m9240            R440  -2   M      A18X+159960Y+128699X0198Y0197     S2      
317CPU0_PWR_BTN_N   VIA   -    MD0080PA00X+153396Y+116199X0160Y         S0      
327CPU0_PWR_BTN_N   U25   -DH7        A01X+153212Y+116094X0177Y    R180 S1      
317CPU0_PWR_BTN_N   VIA   -    MD0100PA00X+120659Y+048140X0200Y         S0      
317CPU0_PWR_BTN_N   VIA   -    MD0100PA00X+159847Y+126754X0200Y    R180 S0      
317CPU0_PWR_BTN_N   VIA   -    MD0100PA00X+115527Y+021234X0200Y    R180 S0      
327CPU0_PWR_BTN_N   R424  -2   M      A01X+115527Y+020984X0198Y0197     S1      
317CPU0_PWR_BTN_N   J6    -1    D0440PA00X+117386Y+020720X0640Y0640R090 S3      
317CPU0_PWR_BTN_N   VIA   -    M      A01X+112108Y+051150X0200Y         S2      
017CPU0_PWR_BTN_N   VIA   -    M      A18X+112108Y+051150X0260Y         S2      
017CPU0_PWR_BTN_N         -    MD0100PA00X+112108Y+051150                       
317CPU0_PWR_BTN_N   VIA   -    MD0100PA00X+072450Y+051336X0200Y    R180 S0      
327CPU0_PWR_BTN_N   R215  -1          A01X+072450Y+051094X0198Y0197R270 S1      
327CPU0_PROCHOT_N   U25   -A69        A01X+130334Y+087429X0177Y    R180 S1      
327CPU0_PROCHOT_N   R412  -1   M      A01X+127368Y+076506X0198Y0197R270 S1      
327CPU0_PROCHOT_N   R179  -2          A01X+071630Y+037679X0198Y0197R270 S1      
317CPU0_PROCHOT_N   VIA   -    M      A01X+098069Y+038778X0200Y         S2      
017CPU0_PROCHOT_N   VIA   -    M      A18X+098069Y+038778X0260Y         S2      
017CPU0_PROCHOT_N         -    MD0100PA00X+098069Y+038778                       
317CPU0_PROCHOT_N   VIA   -    MD0100PA00X+071550Y+037436X0200Y    R270 S0      
317CPU0_NV_SAVE_N   VIA   -    MD0080PA00X+131815Y+087643X0160Y    R180 S0      
327CPU0_NV_SAVE_N   U25   -B64        A01X+131999Y+087748X0177Y    R180 S1      
327CPU0_NV_SAVE_N   VIA   -    M      A18X+127935Y+078782X0260Y         S2      
327CPU0_NV_SAVE_N   R452  -1   M      A18X+127475Y+078732X0198Y0197     S2      
317CPU0_NV_SAVE_N   VIA   -    MD0100PA00X+124499Y+078758X0200Y    R180 S0      
327CPU0_NV_SAVE_N   R253  -1          A18X+071265Y+050092X0198Y0197R090 S2      
317CPU0_NV_SAVE_N   VIA   -    MD0100PA00X+071162Y+051353X0200Y    R180 S0      
317CPU0_NV_SAVE_N   VIA   -    MD0100PA00X+072425Y+062794X0200Y         S0      
317CPU0_NV_SAVE_N   VIA   -    MD0100PA00X+111447Y+064080X0200Y         S0      
317m9241            VIA   -    MD0080PA00X+144329Y+116518X0160Y         S0      
327m9241            R219  -1          A01X+073031Y+052736X0198Y0197R270 S1      
327m9241            R441  -1          A18X+157920Y+130614X0198Y0197R090 S2      
327m9241            U25   -DJ31       A01X+144145Y+116413X0177Y    R180 S1      
327m9241            VIA   -    M      A18X+144204Y+120060X0260Y    R180 S2      
317m9241            VIA   -    MD0100PA00X+157502Y+130637X0200Y    R180 S0      
317m9241            VIA   -    MD0100PA00X+072850Y+052986X0200Y         S0      
317m9241            VIA   -    MD0100PA00X+084366Y+055568X0200Y         S0      
317m9242            VIA   -    M      A01X+071650Y+052186X0200Y    R180 S2      
017m9242            VIA   -    M      A18X+071650Y+052186X0260Y    R180 S2      
017m9242                  -    MD0100PA00X+071650Y+052186                       
327m9242            U18   -H20        A01X+071938Y+047974X0160Y    R090 S1      
317m9242            VIA   -    MD0100PA00X+071784Y+048127X0180Y    R090 S0      
327m9242            R159  -2          A01X+071602Y+052435X0198Y0197R270 S1      
327m9243            R159  -1          A01X+071602Y+052750X0198Y0197R270 S1      
317m9243            VIA   -    MD0100PA00X+095476Y+059304X0200Y         S0      
327m9243            U150  -9          A01X+098667Y+037900X0140Y0630R180 S1      
317m9243            VIA   -    M      A01X+098567Y+038931X0200Y         S2      
017m9243            VIA   -    M      A18X+098567Y+038931X0260Y         S2      
017m9243                  -    MD0100PA00X+098567Y+038931                       
317m9243            VIA   -    MD0100PA00X+079172Y+057495X0200Y         S0      
327m9244            R258  -2          A01X+074450Y+051094X0198Y0197R090 S1      
317m9244            VIA   -    MD0100PA00X+074450Y+051336X0200Y    R180 S0      
317m9244            VIA   -    M      A01X+105823Y+052324X0200Y    R270 S2      
017m9244            VIA   -    M      A18X+105823Y+052324X0260Y    R270 S2      
017m9244                  -    MD0100PA00X+105823Y+052324                       
327m9244            R1632 -2          A01X+151894Y+025325X0198Y0197R180 S1      
327m9244            C551  -1   M      A01X+151335Y+025961X0198Y0197R270 S1      
317m9245            VIA   -    MD0100PA00X+091198Y+058528X0200Y         S0      
317m9245            VIA   -    M      A01X+092003Y+057785X0200Y         S2      
017m9245            VIA   -    M      A18X+092003Y+057785X0260Y         S2      
017m9245                  -    MD0100PA00X+092003Y+057785                       
327m9245            R1646 -2   M      A01X+092003Y+057071X0198Y0197     S1      
327m9245            Q63   -G          A01X+091997Y+056203X0400Y0560R270 S1      
327m9245            U13   -7          A01X+091689Y+059963X0140Y0520R090 S1      
327m9245            U153  -7   M      A01X+091689Y+058513X0140Y0520R090 S1      
327m9245            R158  -2          A18X+075665Y+050092X0198Y0197R270 S2      
317m9245            VIA   -    MD0100PA00X+075220Y+055476X0200Y         S0      
317m9246            VIA   -    MD0080PA00X+132186Y+087643X0160Y    R180 S0      
327m9246            R6502 -1   M      A18X+125237Y+078740X0198Y0197     S2      
327m9246            U25   -B63        A01X+132369Y+087748X0177Y    R180 S1      
327m9246            VIA   -    M      A18X+127935Y+078282X0260Y         S2      
327m9246            R438  -1   M      A18X+127475Y+078332X0198Y0197     S2      
317m9246            VIA   -    MD0100PA00X+125118Y+078449X0200Y    R180 S0      
317m9246            VIA   -    MD0100PA00X+113286Y+060937X0200Y         S0      
317m9246            VIA   -    MD0100PA00X+076450Y+052186X0200Y    R180 S0      
327m9246            R186  -2          A18X+076415Y+050092X0198Y0197R270 S2      
317m9246            VIA   -    MD0100PA00X+102750Y+048564X0200Y         S0      
317m9247            VIA   -    MD0080PA00X+145439Y+115880X0160Y         S0      
327m9247            R1592 -2          A18X+157118Y+127879X0180Y0200     S2      
327m9247            U25   -DG28       A01X+145255Y+115776X0177Y    R180 S1      
327m9247            VIA   -    M      A18X+145495Y+119343X0260Y    R180 S2      
317m9248            VIA   -    MD0080PA00X+147678Y+116578X0160Y         S0      
327m9248            R1593 -2          A18X+159258Y+127517X0180Y0200     S2      
327m9248            U25   -DJ22       A01X+147476Y+116413X0177Y    R180 S1      
327m9248            VIA   -    M      A18X+149382Y+120317X0260Y    R180 S2      
317CPU0_CORETYPE2   VIA   -    MD0080PA00X+130335Y+088281X0160Y    R180 S0      
327CPU0_CORETYPE2   U25   -D68        A01X+130519Y+088386X0177Y    R180 S1      
327CPU0_CORETYPE2   R387  -2          A18X+126418Y+080440X0198Y0197R270 S2      
317CPU0_CORETYPE2   VIA   -    MD0100PA00X+126657Y+080908X0200Y    R180 S0      
317CPU0_CORETYPE2   VIA   -    MD0100PA00X+086773Y+057552X0200Y         S0      
317CPU0_CORETYPE2   VIA   -    MD0100PA00X+074750Y+036886X0200Y         S0      
327CPU0_CORETYPE2   R185  -1          A18X+074750Y+038079X0198Y0197R270 S2      
317CPU0_CORETYPE2   VIA   -    M      A01X+113839Y+061566X0200Y         S2      
017CPU0_CORETYPE2   VIA   -    M      A18X+113839Y+061566X0260Y         S2      
017CPU0_CORETYPE2         -    MD0100PA00X+113839Y+061566                       
317CPU0_CORETYPE1   VIA   -    MD0080PA00X+129965Y+087643X0160Y    R180 S0      
327CPU0_CORETYPE1   U25   -B69        A01X+130149Y+087748X0177Y    R180 S1      
317CPU0_CORETYPE1   VIA   -    M      A01X+112939Y+061566X0200Y         S2      
017CPU0_CORETYPE1   VIA   -    M      A18X+112939Y+061566X0260Y         S2      
017CPU0_CORETYPE1         -    MD0100PA00X+112939Y+061566                       
317CPU0_CORETYPE1   VIA   -    MD0100PA00X+094426Y+058788X0200Y         S0      
317CPU0_CORETYPE1   VIA   -    MD0100PA00X+094426Y+042040X0200Y         S0      
327CPU0_CORETYPE1   R184  -1          A01X+074750Y+039329X0198Y0197R090 S1      
317CPU0_CORETYPE1   VIA   -    MD0100PA00X+074745Y+038682X0200Y    R090 S0      
317CPU0_CORETYPE1   VIA   -    MD0100PA00X+126043Y+080901X0200Y    R180 S0      
327CPU0_CORETYPE1   R388  -2          A18X+125718Y+080440X0198Y0197R270 S2      
317CPU0_CORETYPE0   VIA   -    MD0080PA00X+129780Y+087962X0160Y    R180 S0      
327CPU0_CORETYPE0   U25   -C70        A01X+129964Y+088067X0177Y    R180 S1      
327CPU0_CORETYPE0   R390  -2          A18X+125318Y+080440X0198Y0197R270 S2      
317CPU0_CORETYPE0   VIA   -    MD0100PA00X+125753Y+080894X0200Y    R180 S0      
317CPU0_CORETYPE0   VIA   -    MD0100PA00X+094176Y+058788X0200Y         S0      
317CPU0_CORETYPE0   VIA   -    MD0100PA00X+094176Y+042040X0200Y         S0      
327CPU0_CORETYPE0   R183  -1          A01X+074350Y+039329X0198Y0197R090 S1      
317CPU0_CORETYPE0   VIA   -    MD0100PA00X+074350Y+039086X0200Y    R090 S0      
317CPU0_CORETYPE0   VIA   -    M      A01X+112639Y+061566X0300Y         S1      
017CPU0_CORETYPE0   VIA   -    M      A18X+112639Y+061566X0200Y         S1      
017CPU0_CORETYPE0         -    MD0100PA00X+112639Y+061566                       
327CPU0_BP3         U25   -A62        A01X+132924Y+087429X0177Y    R180 S1      
317CPU0_BP3         VIA   -    MD0100PA00X+132924Y+087116X0200Y    R180 S0      
327CPU0_BP3         R411  -1   M      A18X+127275Y+077032X0198Y0197     S2      
317CPU0_BP3         VIA   -    MD0100PA00X+123610Y+077384X0200Y    R180 S0      
317CPU0_BP3         VIA   -    MD0100PA00X+119204Y+063849X0200Y         S0      
317CPU0_BP3         VIA   -    M      A01X+124906Y+023659X0200Y         S2      
017CPU0_BP3         VIA   -    M      A18X+124906Y+023659X0260Y         S2      
017CPU0_BP3               -    MD0100PA00X+124906Y+023659                       
327CPU0_BP3         J48   -7          A01X+125532Y+023659X0300Y0950R270 S1      
327CPU0_BP2         U25   -A63        A01X+132554Y+087429X0177Y    R180 S1      
317CPU0_BP2         VIA   -    MD0100PA00X+132554Y+087116X0200Y    R180 S0      
327CPU0_BP2         R410  -1   M      A18X+127275Y+077432X0198Y0197     S2      
317CPU0_BP2         VIA   -    MD0100PA00X+124106Y+078228X0200Y    R180 S0      
317CPU0_BP2         VIA   -    MD0100PA00X+119454Y+063849X0200Y         S0      
317CPU0_BP2         VIA   -    M      A01X+124906Y+024159X0200Y         S2      
017CPU0_BP2         VIA   -    M      A18X+124906Y+024159X0260Y         S2      
017CPU0_BP2               -    MD0100PA00X+124906Y+024159                       
327CPU0_BP2         J48   -5          A01X+125532Y+024159X0300Y0950R270 S1      
317CPU0_BP1         VIA   -    MD0080PA00X+132741Y+087962X0160Y    R180 S0      
327CPU0_BP1         U25   -C62        A01X+132924Y+088067X0177Y    R180 S1      
327CPU0_BP1         R409  -1   M      A18X+126475Y+077782X0198Y0197     S2      
317CPU0_BP1         VIA   -    MD0100PA00X+124321Y+077943X0200Y    R180 S0      
317CPU0_BP1         VIA   -    MD0100PA00X+119704Y+063849X0200Y         S0      
317CPU0_BP1         VIA   -    M      A01X+124906Y+024659X0200Y         S2      
017CPU0_BP1         VIA   -    M      A18X+124906Y+024659X0260Y         S2      
017CPU0_BP1               -    MD0100PA00X+124906Y+024659                       
327CPU0_BP1         J48   -3          A01X+125532Y+024659X0300Y0950R270 S1      
317CPU0_BP0         VIA   -    MD0080PA00X+132370Y+087962X0160Y    R180 S0      
327CPU0_BP0         U25   -C63        A01X+132554Y+088067X0177Y    R180 S1      
327CPU0_BP0         R408  -1   M      A18X+126475Y+078182X0198Y0197     S2      
317CPU0_BP0         VIA   -    MD0100PA00X+124813Y+078335X0200Y    R180 S0      
317CPU0_BP0         VIA   -    MD0100PA00X+119954Y+063849X0200Y         S0      
317CPU0_BP0         VIA   -    M      A01X+124906Y+025159X0200Y         S2      
017CPU0_BP0         VIA   -    M      A18X+124906Y+025159X0260Y         S2      
017CPU0_BP0               -    MD0100PA00X+124906Y+025159                       
327CPU0_BP0         J48   -1          A01X+125532Y+025159X0300Y0950R270 S1      
327CPLD_PROGRAMN    VIA   -    M      A01X+065958Y+047866X0300Y    R180 S1      
327CPLD_PROGRAMN    R639  -1          A01X+065958Y+047386X0198Y0197R180 S1      
327CPLD_PROGRAMN    U18   -E15        A01X+070993Y+046399X0160Y    R090 S1      
317CPLD_PROGRAMN    VIA   -    MD0100PA00X+070840Y+046552X0180Y    R090 S0      
317CPLD_PROGRAMN    VIA   -    MD0100PA00X+066200Y+047386X0200Y    R270 S0      
327CPLD_JTAG_EN     U18   -E14        A01X+070993Y+046084X0160Y    R090 S1      
317CPLD_JTAG_EN     VIA   -    MD0100PA00X+070840Y+046237X0180Y    R090 S0      
327CPLD_JTAG_EN     R638  -1          A01X+065958Y+046986X0198Y0197R180 S1      
327CPLD_JTAG_EN     VIA   -    M      A01X+066692Y+047185X0160Y0041     S1      
317CPLD_JTAG_EN     VIA   -    MD0100PA00X+067000Y+046982X0200Y    R270 S0      
327CLR_CMOS_N       R1779 -1          A01X+119549Y+008798X0198Y0197R090 S1      
327CLR_CMOS_N       VIA   -    M      A01X+119549Y+008318X0300Y    R270 S1      
327CLR_CMOS_N       Q8    -6          A01X+118847Y+007518X0170Y0200     S1      
317CLR_CMOS         VIA   -    M      A01X+118591Y+009363X0200Y    R090 S2      
017CLR_CMOS         VIA   -    M      A18X+118591Y+009363X0260Y    R090 S2      
017CLR_CMOS               -    MD0100PA00X+118591Y+009363                       
327CLR_CMOS         R1776 -1   M      A01X+118591Y+009112X0198Y0197     S1      
327CLR_CMOS         C1563 -1   M      A01X+118591Y+008712X0198Y0197     S1      
327CLR_CMOS         Q8    -5          A01X+118591Y+007518X0170Y0200     S1      
327CLR_CMOS         Q8    -2   M      A01X+118591Y+008266X0170Y0200     S1      
317CLR_CMOS         VIA   -    MD0100PA00X+094538Y+023396X0200Y         S0      
327CLR_CMOS         R275  -1          A18X+073965Y+039327X0198Y0197R270 S2      
317CLR_CMOS         VIA   -    MD0100PA00X+073965Y+039086X0200Y    R090 S0      
317CLR_CMOS         VIA   -    MD0100PA00X+093994Y+038642X0200Y         S0      
317m9249            VIA   -    MD0080PA00X+147289Y+115880X0160Y         S0      
327m9249            U25   -DG23       A01X+147106Y+115776X0177Y    R180 S1      
327m9249            VIA   -    M      A18X+148318Y+119300X0260Y    R180 S2      
327m9249            R473  -2          A18X+154010Y+126449X0198Y0197     S2      
327m9250            R1556 -1          A01X+077300Y+054029X0198Y0197R090 S1      
317m9250            VIA   -    M      A01X+077210Y+053270X0200Y         S2      
017m9250            VIA   -    M      A18X+077210Y+053270X0260Y         S2      
017m9250                  -    MD0100PA00X+077210Y+053270                       
327m9250            U18   -R21        A01X+074143Y+048288X0160Y    R090 S1      
317m9250            VIA   -    MD0100PA00X+074296Y+048442X0180Y    R090 S0      
327m9251            J41   -B1         A01X+070420Y+006516X0150Y0570R180 S1      
327m9251            R1556 -2          A01X+077300Y+054344X0198Y0197R090 S1      
327m9251            R750  -2   M      A18X+154818Y+126449X0198Y0197     S2      
327m9251            R739  -2          A18X+154818Y+126849X0198Y0197     S2      
327m9251            R473  -1   M      A18X+154325Y+126449X0198Y0197     S2      
317m9251            VIA   -    MD0100PA00X+154491Y+126065X0200Y    R180 S0      
317m9251            VIA   -    M      A01X+070420Y+007211X0200Y         S2      
017m9251            VIA   -    M      A18X+070420Y+007211X0260Y         S2      
017m9251                  -    MD0100PA00X+070420Y+007211                       
317m9251            VIA   -    MD0100PA00X+077200Y+054586X0200Y    R180 S0      
327m9252            U26   -DH9        A01X+054857Y+116095X0177Y    R180 S1      
327m9252            VIA   -    M      A18X+057560Y+125735X0260Y    R180 S2      
317m9252            VIA   -    MD0100PA00X+056713Y+124954X0200Y    R180 S0      
327m9252            R1502 -2          A18X+057642Y+126191X0198Y0197R180 S2      
327m9252            R1501 -2   M      A18X+057293Y+125279X0198Y0197R180 S2      
317m9253            VIA   -    MD0100PA00X+153290Y+123484X0200Y         S0      
327m9253            U25   -DH9        A01X+152472Y+116094X0177Y    R180 S1      
327m9253            R573  -1   M      A18X+153551Y+123536X0198Y0197R270 S2      
327m9253            R740  -2          A18X+154377Y+123533X0198Y0197R090 S2      
327m9253            R751  -2   M      A18X+153978Y+123536X0198Y0197R090 S2      
327CLK_50M_RMII_R   U90   -1          A01X+084772Y+008145X0140Y0590R180 S1      
327CLK_50M_RMII_R   R1139 -2          A01X+085002Y+009018X0198Y0197R270 S1      
317CLK_50M_RMII_R   VIA   -    M      A01X+085002Y+008734X0200Y         S2      
017CLK_50M_RMII_R   VIA   -    M      A18X+085002Y+008734X0260Y         S2      
017CLK_50M_RMII_R         -    MD0100PA00X+085002Y+008734                       
327m9254            J41   -B18        A01X+066404Y+006516X0150Y0570R180 S1      
327m9254            R1140 -2          A01X+083725Y+009045X0198Y0197R180 S1      
317m9254            VIA   -    MD0100PA00X+083725Y+009322X0200Y         S0      
317m9254            VIA   -    MD0100PA00X+067730Y+005795X0200Y         S0      
317m9254            VIA   -    M      A01X+066160Y+007556X0200Y         S2      
017m9254            VIA   -    M      A18X+066160Y+007556X0260Y         S2      
017m9254                  -    MD0100PA00X+066160Y+007556                       
327CLK_50M_RMII     OSC1  -3          A01X+085009Y+010595X0480Y0590R090 S1      
327CLK_50M_RMII     R1139 -1          A01X+085002Y+009333X0198Y0197R270 S1      
317CLK_50M_RMII     VIA   -    M      A01X+084747Y+009475X0200Y         S2      
017CLK_50M_RMII     VIA   -    M      A18X+084747Y+009475X0260Y         S2      
017CLK_50M_RMII           -    MD0100PA00X+084747Y+009475                       
327m9255            U321  -2          A01X+034767Y+012626X0180Y0520R270 S1      
327m9255            R4602 -2          A01X+033981Y+012625X0198Y0197R090 S1      
327m9255            VIA   -    M      A01X+033981Y+013105X0300Y    R180 S1      
327m9256            R4602 -1          A01X+033981Y+012310X0198Y0197R090 S1      
317m9256            VIA   -    MD0100PA00X+034044Y+012056X0200Y         S0      
327m9256            J35   -OA14       A01X+027662Y+003276X0150Y0570R180 S1      
317m9256            VIA   -    M      A01X+027512Y+002856X0200Y         S2      
017m9256            VIA   -    M      A18X+027512Y+002856X0260Y         S2      
017m9256                  -    MD0100PA00X+027512Y+002856                       
327m9257            U321  -1          A01X+034767Y+013000X0180Y0520R270 S1      
317m9257            VIA   -    M      A01X+034345Y+013117X0200Y         S2      
017m9257            VIA   -    M      A18X+034345Y+013117X0260Y         S2      
017m9257                  -    MD0100PA00X+034345Y+013117                       
327m9257            R3181 -2          A01X+085663Y+006292X0198Y0197R270 S1      
317m9257            VIA   -    MD0100PA00X+085863Y+006029X0200Y    R090 S0      
327m9258            U320  -2          A01X+150244Y+013082X0180Y0520R090 S1      
327m9258            VIA   -    M      A01X+150948Y+013082X0300Y    R090 S1      
327m9258            R4601 -2          A01X+151437Y+013081X0198Y0197R180 S1      
327m9259            R4601 -1          A01X+151752Y+013081X0198Y0197R180 S1      
317m9259            VIA   -    MD0100PA00X+151585Y+011981X0200Y    R090 S0      
327m9259            J38   -OA14       A01X+175103Y+003276X0150Y0570R180 S1      
317m9259            VIA   -    M      A01X+174871Y+002664X0200Y         S2      
017m9259            VIA   -    M      A18X+174871Y+002664X0260Y         S2      
017m9259                  -    MD0100PA00X+174871Y+002664                       
327m9260            U320  -1          A01X+150244Y+012708X0180Y0520R090 S1      
317m9260            VIA   -    MD0100PA00X+149489Y+012117X0200Y         S0      
327m9260            R1141 -2          A01X+083154Y+006277X0198Y0197R270 S1      
317m9260            VIA   -    M      A01X+083678Y+006801X0200Y    R090 S2      
017m9260            VIA   -    M      A18X+083678Y+006801X0260Y    R090 S2      
017m9260                  -    MD0100PA00X+083678Y+006801                       
327m9261            U90   -7          A01X+084516Y+005845X0140Y0590R180 S1      
327m9261            R3181 -1          A01X+085663Y+006607X0198Y0197R270 S1      
327m9261            VIA   -    M      A01X+085663Y+007079X0300Y    R090 S1      
327m9262            U90   -5          A01X+084004Y+005845X0140Y0590R180 S1      
327m9262            R1141 -1          A01X+083154Y+006592X0198Y0197R270 S1      
327m9262            VIA   -    M      A01X+083154Y+007064X0300Y    R090 S1      
327CLK_50M_EN       OSC1  -1          A01X+084174Y+009965X0480Y0590R090 S1      
327CLK_50M_EN       U90   -2          A01X+084516Y+008145X0140Y0590R180 S1      
327CLK_50M_EN       R1138 -2   M      A01X+084494Y+009333X0198Y0197R090 S1      
317CLK_50M_EN       VIA   -    M      A01X+084158Y+009418X0200Y         S2      
017CLK_50M_EN       VIA   -    M      A18X+084158Y+009418X0260Y         S2      
017CLK_50M_EN             -    MD0100PA00X+084158Y+009418                       
327m9263            U90   -3          A01X+084260Y+008145X0140Y0590R180 S1      
327m9263            R1140 -1          A01X+084040Y+009045X0198Y0197R180 S1      
317m9263            VIA   -    M      A01X+083990Y+008725X0200Y         S2      
017m9263            VIA   -    M      A18X+083990Y+008725X0260Y         S2      
017m9263                  -    MD0100PA00X+083990Y+008725                       
327m9264            U25   -A19        A01X+148468Y+087429X0177Y    R180 S1      
317m9264            VIA   -    MD0100PA00X+133681Y+085638X0200Y         S0      
327m9264            R435  -1          A18X+133688Y+084756X0198Y0197R090 S2      
327m9265            U25   -A20        A01X+148098Y+087429X0177Y    R180 S1      
317m9265            VIA   -    MD0100PA00X+133281Y+085638X0200Y         S0      
327m9265            R436  -1          A18X+133288Y+084756X0198Y0197R090 S2      
327m9266            U26   -A19        A01X+050854Y+087429X0177Y    R180 S1      
317m9266            VIA   -    MD0100PA00X+051357Y+086533X0200Y    R090 S0      
327m9266            R435  -2          A18X+133688Y+084441X0198Y0197R090 S2      
327m9267            U26   -A20        A01X+050483Y+087429X0177Y    R180 S1      
327m9267            R436  -2          A18X+133288Y+084441X0198Y0197R090 S2      
317m9267            VIA   -    MD0100PA00X+050957Y+086533X0200Y    R090 S0      
317m9268            VIA   -    MD0100PA01X+008032Y+053941X0200Y    R090 S0      
317m9268            VIA   -    MD0100P   X+019368Y+164005X0000Y0000     S0      
327m9268            R3337 -2          A01X+007521Y+053931X0198Y0197     S1      
317m9268            J112  -R2   D0142PA01X+023878Y+165311X0302Y    R180 S3      
317m9269            VIA   -    MD0100PA01X+008032Y+054331X0200Y    R090 S0      
317m9269            VIA   -    MD0100P   X+019368Y+164345X0000Y0000     S0      
327m9269            R3338 -2          A01X+007521Y+054321X0198Y0197     S1      
317m9269            J112  -Q2   D0142PA01X+023878Y+165783X0302Y    R180 S3      
327m9270            U26   -DJ41       A01X+043200Y+116414X0177Y    R180 S1      
327m9270            R3352 -1          A01X+049650Y+126479X0198Y0197R090 S1      
327m9271            U26   -DJ42       A01X+042830Y+116414X0177Y    R180 S1      
327m9271            R3353 -1          A01X+049250Y+126479X0198Y0197R090 S1      
317m9272            J112  -P3   D0142PA01X+024665Y+166335X0302Y    R180 S3      
317m9272            VIA   -    MD0100PA01X+065400Y+142336X0200Y         S0      
327m9272            VIA   -    M      A01X+063745Y+142176X0160Y0041R045 S1      
327m9272            R3352 -2          A01X+049650Y+126794X0198Y0197R090 S1      
317m9273            J112  -O3   D0142PA01X+024665Y+166807X0302Y    R180 S3      
317m9273            VIA   -    MD0100PA01X+065400Y+142676X0200Y         S0      
327m9273            VIA   -    M      A01X+062899Y+141509X0160Y0041R045 S1      
327m9273            R3353 -2          A01X+049250Y+126794X0198Y0197R090 S1      
327m9274            R2659 -1          A01X+144253Y+127518X0198Y0197R090 S1      
327m9274            U25   -DJ41       A01X+140814Y+116413X0177Y    R180 S1      
327m9275            U25   -DJ42       A01X+140444Y+116413X0177Y    R180 S1      
327m9275            R2660 -1          A01X+143853Y+127518X0198Y0197R090 S1      
317m9276            VIA   -    MD0100PA01X+069128Y+145511X0200Y         S0      
327m9276            VIA   -    M      A01X+081888Y+146765X0160Y0041R180 S1      
327m9276            R2659 -2          A01X+144253Y+127834X0198Y0197R090 S1      
317m9276            J112  -O4   D0142PA01X+025453Y+166728X0302Y    R180 S3      
317m9277            VIA   -    MD0100PA01X+069468Y+145511X0200Y         S0      
327m9277            VIA   -    M      A01X+082939Y+146638X0160Y0041R180 S1      
327m9277            R2660 -2          A01X+143853Y+127834X0198Y0197R090 S1      
317m9277            J112  -N4   D0142PA01X+025453Y+167201X0302Y    R180 S3      
327m9278            J41   -A68        A01X+051554Y+005354X0150Y0570R180 S1      
317m9278            VIA   -    MD0100PA00X+008095Y+052161X0200Y    R090 S2      
327m9278            R3335 -2          A01X+007521Y+052161X0198Y0197     S1      
317m9278            VIA   -    MD0100PA00X+051606Y+004661X0200Y         S0      
327m9279            J41   -A69        A01X+051318Y+005354X0150Y0570R180 S1      
317m9279            VIA   -    MD0100PA00X+008095Y+052551X0200Y    R090 S2      
327m9279            R3336 -2          A01X+007521Y+052551X0198Y0197     S1      
317m9279            VIA   -    MD0100PA00X+051266Y+004661X0200Y         S0      
327m9280            J41   -A14        A01X+067349Y+005354X0150Y0570R180 S1      
327m9280            R4535 -2          A18X+146556Y+084301X0198Y0197R090 S2      
317m9280            VIA   -    MD0100PA00X+067401Y+004246X0200Y         S0      
327m9281            J41   -A15        A01X+067113Y+005354X0150Y0570R180 S1      
327m9281            R4536 -2          A18X+146116Y+084301X0198Y0197R090 S2      
317m9281            VIA   -    MD0100PA00X+067061Y+004246X0200Y         S0      
327BOOT_RDY_R_H     R940  -1          A01X+158170Y+130228X0198Y0197     S1      
327BOOT_RDY_R_H     U25   -DH30       A01X+144700Y+116094X0177Y    R180 S1      
327BOOT_RDY_R_H     VIA   -    M      A01X+151808Y+129629X0300Y    R180 S1      
327BOOT_RDY_R1_N    VIA   -    M      A18X+157655Y+133877X0260Y         S2      
327BOOT_RDY_R1_N    R934  -2          A18X+156915Y+134162X0198Y0197R090 S2      
327BOOT_RDY_R1_N    R941  -2   M      A18X+157292Y+134162X0198Y0197R090 S2      
327BOOT_RDY_R1_N    U82   -2          A18X+159725Y+134103X0220Y0530R090 S2      
327BOOT_RDY_LED_N   D5    -C          A01X+133744Y+006456X0240Y0280R090 S1      
327BOOT_RDY_LED_N   Q2    -3          A01X+133984Y+008285X0170Y0200     S1      
327BOOT_RDY_LED_N   VIA   -    M      A01X+133744Y+007045X0300Y    R270 S1      
327BOOT_RDY_LED     R946  -2          A01X+134820Y+009251X0198Y0197R270 S1      
327BOOT_RDY_LED     Q2    -5          A01X+134240Y+007537X0170Y0200     S1      
327BOOT_RDY_LED     Q2    -6   M      A01X+134496Y+007537X0170Y0200     S1      
327BOOT_RDY_LED     VIA   -    M      A01X+134820Y+008771X0300Y         S1      
317BOOT_RDY_H       VIA   -    M      A01X+157233Y+134820X0200Y         S2      
017BOOT_RDY_H       VIA   -    M      A18X+157233Y+134820X0260Y         S2      
017BOOT_RDY_H             -    MD0100PA00X+157233Y+134820                       
327BOOT_RDY_H       R941  -1          A18X+157292Y+134477X0198Y0197R090 S2      
327BOOT_RDY_H       R938  -1          A01X+158485Y+129828X0198Y0197R180 S1      
327BOOT_RDY_H       R940  -2   M      A01X+158485Y+130228X0198Y0197     S1      
317m9282            VIA   -    M      A01X+133740Y+009808X0200Y         S2      
017m9282            VIA   -    M      A18X+133740Y+009808X0260Y         S2      
017m9282                  -    MD0100PA00X+133740Y+009808                       
317m9282            VIA   -    MD0100PA00X+123208Y+046058X0200Y         S0      
327m9282            R935  -1          A01X+133740Y+009566X0198Y0197R270 S1      
317m9282            VIA   -    MD0100PA00X+156476Y+136783X0200Y         S0      
327m9282            U82   -4          A18X+158760Y+133729X0220Y0530R090 S2      
317m9282            VIA   -    MD0100PA00X+154720Y+147816X0200Y         S0      
327m9283            R935  -2          A01X+133740Y+009251X0198Y0197R270 S1      
327m9283            R944  -2   M      A01X+134140Y+009251X0198Y0197R270 S1      
327m9283            Q2    -2          A01X+134240Y+008285X0170Y0200     S1      
327m9283            VIA   -    M      A01X+134140Y+008771X0300Y         S1      
327BMC_MONITER_R    VIA   -    M      A18X+079828Y+053137X0260Y         S2      
327BMC_MONITER_R    R2915 -1          A18X+068054Y+162904X0198Y0197     S2      
327BMC_MONITER_R    R2815 -2   M      A18X+068054Y+163304X0198Y0197R180 S2      
327BMC_MONITER_R    U195  -1          A18X+069088Y+162908X0160Y0200R270 S2      
317BMC_MONITER_R    VIA   -    MD0100PA00X+082279Y+076751X0200Y         S0      
317BMC_MONITER_R    VIA   -    MD0100PA00X+075323Y+067868X0200Y         S0      
327BMC_MONITER_R    R2845 -1          A01X+082399Y+043563X0198Y0197R180 S1      
317BMC_MONITER_R    VIA   -    MD0100PA00X+082647Y+043534X0200Y         S0      
317BMC_MONITER_R    VIA   -    MD0100PA00X+068699Y+162908X0200Y         S0      
327m9284            VIA   -    M      A18X+070241Y+162503X0260Y         S2      
327m9284            R2917 -1          A18X+071812Y+162891X0198Y0197R180 S2      
327m9284            R2820 -2   M      A18X+071332Y+162421X0198Y0197R090 S2      
327m9284            U195  -6          A18X+069836Y+162908X0160Y0200R270 S2      
327m9284            R2926 -1   M      A18X+070932Y+162421X0198Y0197R270 S2      
317m9285            VIA   -    M      A01X+071813Y+162433X0200Y         S2      
017m9285            VIA   -    M      A18X+071813Y+162433X0260Y         S2      
017m9285                  -    MD0100PA00X+071813Y+162433                       
327m9285            R2917 -2          A18X+072127Y+162891X0198Y0197R180 S2      
317m9285            VIA   -    MD0100PA00X+062981Y+166886X0200Y         S0      
317m9285            J109  -A1   D0142PA00X+056201Y+173421X0302Y0302R180 S3      
327BMC_JTAG_SEL_R   VIA   -    M      A01X+075250Y+050001X0300Y         S1      
327BMC_JTAG_SEL_R   R1359 -1          A01X+075250Y+050779X0198Y0197R090 S1      
327BMC_JTAG_SEL_R   U18   -U20        A01X+074772Y+047974X0160Y    R090 S1      
317BMC_JTAG_SEL_R   VIA   -    MD0100PA00X+074926Y+048127X0180Y    R090 S0      
317BMC_JTAG_SEL_R   VIA   -    MD0100PA00X+075325Y+049523X0200Y    R090 S0      
327BMC_JTAG_SEL     SW1   -13         A01X+169910Y+015676X0300Y0500R270 S1      
327BMC_JTAG_SEL     R1262 -2          A18X+169050Y+015776X0198Y0197R180 S2      
317BMC_JTAG_SEL     VIA   -    M      A01X+169510Y+015676X0200Y    R090 S2      
017BMC_JTAG_SEL     VIA   -    M      A18X+169510Y+015676X0260Y    R090 S2      
017BMC_JTAG_SEL           -    MD0100PA00X+169510Y+015676                       
317BMC_JTAG_SEL     VIA   -    MD0100PA00X+103586Y+048598X0200Y         S0      
327BMC_JTAG_SEL     R1359 -2          A01X+075250Y+051094X0198Y0197R090 S1      
317BMC_JTAG_SEL     VIA   -    MD0100PA00X+075250Y+051736X0200Y    R180 S0      
317BMC_JTAG_SEL     VIA   -    MD0100PA00X+104006Y+031353X0200Y         S0      
327m9286            VIA   -    M      A01X+129620Y+005654X0300Y         S1      
327m9286            D7    -A          A01X+130171Y+006074X0320Y0320R090 S1      
327m9286            R1194 -2          A01X+129620Y+006134X0198Y0197R270 S1      
327m9287            Q28   -3          A01X+130170Y+007775X0170Y0200R090 S1      
327m9287            D7    -C          A01X+130171Y+006665X0320Y0320R090 S1      
327m9287            VIA   -    M      A01X+130170Y+007234X0300Y    R270 S1      
317BMC_FPGA_LED2    VIA   -    M      A01X+130568Y+007475X0200Y    R270 S2      
017BMC_FPGA_LED2    VIA   -    M      A18X+130568Y+007475X0260Y    R270 S2      
017BMC_FPGA_LED2          -    MD0100PA00X+130568Y+007475                       
327BMC_FPGA_LED2    Q28   -5          A01X+130918Y+008031X0170Y0200R090 S1      
327BMC_FPGA_LED2    U18   -Y10        A01X+075717Y+044824X0160Y    R090 S1      
317BMC_FPGA_LED2    VIA   -    MD0100PA00X+075871Y+044670X0180Y    R090 S0      
317BMC_FPGA_LED2    VIA   -    MD0100PA00X+101676Y+035008X0200Y         S0      
327m9288            VIA   -    M      A01X+130811Y+005654X0300Y         S1      
327m9288            D8    -A          A01X+131362Y+006074X0320Y0320R090 S1      
327m9288            R1266 -2          A01X+130811Y+006134X0198Y0197R270 S1      
327m9289            Q28   -6          A01X+130918Y+008287X0170Y0200R090 S1      
327m9289            VIA   -    M      A01X+131362Y+007234X0300Y    R270 S1      
327m9289            D8    -C          A01X+131362Y+006665X0320Y0320R090 S1      
317BMC_FPGA_LED1    VIA   -    M      A01X+129920Y+007621X0200Y    R270 S2      
017BMC_FPGA_LED1    VIA   -    M      A18X+129920Y+007621X0260Y    R270 S2      
017BMC_FPGA_LED1          -    MD0100PA00X+129920Y+007621                       
327BMC_FPGA_LED1    Q28   -2          A01X+130170Y+008031X0170Y0200R090 S1      
317BMC_FPGA_LED1    VIA   -    MD0100PA00X+093857Y+023315X0200Y         S0      
317BMC_FPGA_LED1    VIA   -    MD0100PA00X+077761Y+040350X0200Y         S0      
327BMC_FPGA_LED1    U18   -AB10       A01X+076347Y+044824X0160Y    R090 S1      
317BMC_FPGA_LED1    VIA   -    MD0100PA00X+076501Y+044670X0180Y    R090 S0      
317BMC_FPGA_LED1    VIA   -    MD0100PA00X+078271Y+026047X0200Y         S0      
327m9290            VIA   -    M      A01X+073650Y+050001X0300Y         S1      
327m9290            R1203 -1          A01X+073650Y+050779X0198Y0197R090 S1      
327m9290            U18   -N22        A01X+073513Y+048604X0160Y    R090 S1      
317m9291            VIA   -    MD0080PA00X+144699Y+115242X0160Y         S0      
327m9291            SW1   -16         A01X+169910Y+014176X0300Y0500R270 S1      
317m9291            VIA   -    M      A01X+132754Y+010523X0200Y    R180 S2      
017m9291            VIA   -    M      A18X+132754Y+010523X0260Y    R180 S2      
017m9291                  -    MD0100PA00X+132754Y+010523                       
317m9291            VIA   -    MD0100PA00X+156282Y+130936X0200Y         S0      
327m9291            U25   -DE30       A01X+144515Y+115138X0177Y    R180 S1      
327m9291            R1203 -2          A01X+073650Y+051094X0198Y0197R090 S1      
317m9291            VIA   -    MD0100PA00X+073666Y+048757X0180Y    R090 S0      
317m9291            VIA   -    MD0100PA00X+114466Y+050032X0200Y         S0      
327m9291            R6107 -2          A18X+169050Y+014576X0198Y0197R180 S2      
327m9291            R1264 -2   M      A18X+169050Y+014176X0198Y0197R180 S2      
317m9291            VIA   -    MD0100PA00X+169510Y+014176X0200Y    R090 S0      
327m9291            Q30   -G          A01X+132754Y+010133X0400Y0480R180 S1      
327BIC_MONITER_N    R2835 -2          A01X+067311Y+173284X0198Y0197R090 S1      
327BIC_MONITER_N    Q67   -5          A01X+066465Y+173028X0170Y0200R090 S1      
327BIC_MONITER_N    Q67   -6   M      A01X+066465Y+173284X0170Y0200R090 S1      
327BIC_MONITER_N    VIA   -    M      A01X+066951Y+173284X0300Y    R270 S1      
317m9292            VIA   -    M      A01X+064498Y+172524X0200Y         S2      
017m9292            VIA   -    M      A18X+064498Y+172524X0260Y         S2      
017m9292                  -    MD0100PA00X+064498Y+172524                       
327m9292            R2846 -2          A18X+078907Y+048752X0198Y0197R180 S2      
317m9292            VIA   -    MD0100PA00X+075576Y+066690X0200Y         S0      
317m9292            VIA   -    MD0100PA00X+082286Y+078326X0200Y         S0      
327m9292            R2920 -2   M      A01X+064498Y+172800X0198Y0197     S1      
327m9292            C1773 -1   M      A01X+064882Y+172800X0198Y0197     S1      
327m9292            Q67   -3          A01X+065717Y+172772X0170Y0200R090 S1      
317BIC_MONITER      VIA   -    M      A01X+066093Y+173028X0200Y         S2      
017BIC_MONITER      VIA   -    M      A18X+066093Y+173028X0260Y         S2      
017BIC_MONITER            -    MD0100PA00X+066093Y+173028                       
317BIC_MONITER      J109  -A3   D0142PA00X+057776Y+173421X0302Y    R180 S3      
327BIC_MONITER      R2830 -2          A01X+064498Y+173300X0198Y0197     S1      
327BIC_MONITER      R2831 -1   M      A01X+064882Y+173300X0198Y0197     S1      
327BIC_MONITER      Q67   -2   M      A01X+065717Y+173028X0170Y0200R090 S1      
327BAT_LDO_EN       U9    -3          A01X+119619Y+009832X0160Y0360R270 S1      
327BAT_LDO_EN       VIA   -    M      A01X+118078Y+009038X0300Y         S1      
327BAT_LDO_EN       R1777 -2   M      A01X+118277Y+009586X0198Y0197     S1      
327BAT_LDO_EN       Q8    -3   M      A01X+118335Y+008266X0170Y0200     S1      
327BAT_LDO_EN       U167  -4          A01X+117697Y+007601X0280Y0360R180 S1      
327m9293            VIA   -    M      A01X+059945Y+047013X0300Y         S1      
327m9293            R2222 -1          A01X+059358Y+047435X0198Y0197R180 S1      
327m9293            U206  -4          A01X+060689Y+046883X0250Y0480R270 S1      
327m9293            R2221 -2   M      A01X+059358Y+046889X0198Y0197     S1      
327m9294            U325  -G          A01X+061622Y+047587X0400Y0560R090 S1      
327m9294            VIA   -    M      A01X+059962Y+045838X0300Y         S1      
327m9294            U206  -6   M      A01X+060689Y+046135X0250Y0480R270 S1      
327m9294            R2230 -2          A01X+059370Y+045846X0198Y0197     S1      
327m9295            VIA   -    M      A01X+062461Y+046883X0300Y         S1      
327m9295            R2227 -1          A01X+062985Y+047402X0198Y0197     S1      
327m9295            U206  -3          A01X+061720Y+046883X0250Y0480R270 S1      
327m9295            R2219 -2   M      A01X+062983Y+046886X0198Y0197R180 S1      
327m9296            R497  -2          A18X+072962Y+052432X0198Y0197R090 S2      
327m9296            U18   -K16        A01X+072568Y+046714X0160Y    R090 S1      
317m9296            VIA   -    M      A01X+072894Y+051752X0300Y    R180 S1      
017m9296            VIA   -    M      A18X+072894Y+051752X0200Y    R180 S1      
017m9296                  -    MD0100PA00X+072894Y+051752                       
317m9296            VIA   -    MD0100PA00X+072414Y+046867X0180Y    R090 S0      
327m9297            R497  -1          A18X+072962Y+052747X0198Y0197R090 S2      
327m9297            U26   -A68        A01X+033090Y+087429X0177Y    R180 S1      
317m9297            VIA   -    MD0100PA00X+028404Y+079685X0200Y    R180 S0      
317m9297            VIA   -    M      A01X+044208Y+051187X0200Y    R090 S2      
017m9297            VIA   -    M      A18X+044208Y+051187X0260Y    R090 S2      
017m9297                  -    MD0100PA00X+044208Y+051187                       
317m9297            VIA   -    MD0100PA00X+072865Y+054586X0200Y    R180 S0      
327m9297            R535  -1          A18X+027785Y+079799X0198Y0197     S2      
327m9298            VIA   -    M      A01X+128168Y+075659X0300Y         S1      
327m9298            R247  -2          A01X+128168Y+076191X0198Y0197R270 S1      
317m9298            VIA   -    MD0100PA00X+119511Y+066815X0200Y         S0      
327m9298            U18   -L17        A01X+072883Y+047029X0160Y    R090 S1      
317m9298            VIA   -    MD0100PA00X+072729Y+047182X0180Y    R090 S0      
317m9298            VIA   -    MD0100PA00X+073636Y+063685X0200Y         S0      
317m9298            VIA   -    MD0100PA00X+129800Y+065750X0200Y         S0      
327m9299            U25   -A68        A01X+130704Y+087429X0177Y    R180 S1      
327m9299            VIA   -    M      A01X+127768Y+077039X0300Y    R180 S1      
327m9299            R247  -1          A01X+128168Y+076506X0198Y0197R270 S1      
327m9299            R418  -1   M      A01X+127768Y+076506X0198Y0197R270 S1      
327AGND_HSC         PR3991-2          A01X+088858Y+158263X0198Y0197R180 S1      
317AGND_HSC         VIA   -    MD0100PA00X+088615Y+158283X0200Y         S0      
327AGND_HSC         PR3990-2          A01X+084658Y+158263X0198Y0197R180 S1      
317AGND_HSC         VIA   -    MD0100PA00X+084415Y+158283X0200Y         S0      
317AGND_HSC         VIA   -    MD0100PA00X+069900Y+160450X0200Y         S0      
327AGND_HSC         R1117 -2          A01X+070192Y+160450X0198Y0197R180 S1      
327AGND_HSC         PC2191-2          A01X+069850Y+159408X0198Y0197R090 S1      
317AGND_HSC         VIA   -    MD0100PA00X+069950Y+159650X0200Y         S0      
327AGND_HSC         PR3932-2          A18X+071955Y+157428X0198Y0197     S2      
327AGND_HSC         PC2186-2          A18X+072195Y+158393X0198Y0197R270 S2      
327AGND_HSC         PC2184-2          A01X+076308Y+158773X0198Y0197R180 S1      
317AGND_HSC         VIA   -    MD0100PA00X+076065Y+158773X0200Y         S0      
327AGND_HSC         PR3937-2          A01X+075518Y+158902X0198Y0197     S1      
317AGND_HSC         VIA   -    MD0100PA00X+075761Y+158902X0200Y         S0      
317AGND_HSC         VIA   -    MD0100PA00X+088615Y+157063X0200Y         S0      
327AGND_HSC         PC2349-2          A01X+088858Y+157063X0198Y0197R180 S1      
317AGND_HSC         VIA   -    MD0100PA00X+084415Y+157063X0200Y         S0      
327AGND_HSC         PC2350-2          A01X+084658Y+157063X0198Y0197R180 S1      
317AGND_HSC         VIA   -    MD0100PA00X+071447Y+156633X0200Y         S0      
327AGND_HSC         PC2190-2          A01X+071718Y+156633X0198Y0197R180 S1      
327AGND_HSC         PR3982-1          A01X+089172Y+160263X0198Y0197R180 S1      
317AGND_HSC         VIA   -    M      A01X+089415Y+160263X0200Y         S2      
017AGND_HSC         VIA   -    M      A18X+089415Y+160263X0260Y         S2      
017AGND_HSC               -    MD0100PA00X+089415Y+160263                       
327AGND_HSC         PR3912-1          A01X+084972Y+160263X0198Y0197R180 S1      
317AGND_HSC         VIA   -    MD0100PA00X+085215Y+160263X0200Y         S0      
327AGND_HSC         PR1134-1          A01X+080772Y+160263X0198Y0197R180 S1      
317AGND_HSC         VIA   -    MD0100PA00X+081015Y+160263X0200Y         S0      
327AGND_HSC         PC2189-2          A01X+072305Y+160251X0198Y0197R090 S1      
317AGND_HSC         VIA   -    MD0100PA00X+072341Y+160874X0200Y         S0      
327AGND_HSC         PR3927-2          A18X+072189Y+160481X0198Y0197R270 S2      
327AGND_HSC         PR3984-1          A01X+093372Y+159023X0198Y0197R180 S1      
317AGND_HSC         VIA   -    MD0100PA00X+093615Y+159023X0200Y         S0      
327AGND_HSC         PU297 -20         A01X+090277Y+158335X0100Y0150R270 S1      
327AGND_HSC         PC2223-2   M      A01X+089675Y+158501X0198Y0197R090 S1      
317AGND_HSC         VIA   -    MD0100PA00X+089485Y+158773X0200Y         S0      
327AGND_HSC         PC2224-2          A01X+089172Y+159063X0198Y0197     S1      
317AGND_HSC         VIA   -    MD0100PA00X+089415Y+159063X0200Y         S0      
327AGND_HSC         PC2227-2          A01X+088858Y+159463X0198Y0197R180 S1      
317AGND_HSC         VIA   -    MD0100PA00X+088615Y+159463X0200Y         S0      
317AGND_HSC         VIA   -    MD0100PA00X+085215Y+159063X0200Y         S0      
327AGND_HSC         PC2183-2          A01X+084972Y+159063X0198Y0197     S1      
317AGND_HSC         VIA   -    MD0100PA00X+085285Y+158773X0200Y         S0      
327AGND_HSC         PU296 -20         A01X+086077Y+158335X0100Y0150R270 S1      
327AGND_HSC         PC3272-2   M      A01X+085475Y+158501X0198Y0197R090 S1      
327AGND_HSC         PC2226-2          A01X+084658Y+159463X0198Y0197R180 S1      
317AGND_HSC         VIA   -    MD0100PA00X+084415Y+159463X0200Y         S0      
317AGND_HSC         VIA   -    MD0100PA00X+081015Y+159063X0200Y         S0      
327AGND_HSC         PC2182-2          A01X+080772Y+159063X0198Y0197     S1      
317AGND_HSC         VIA   -    MD0100PA00X+081085Y+158773X0200Y         S0      
327AGND_HSC         PU288 -20         A01X+081877Y+158335X0100Y0150R270 S1      
327AGND_HSC         PC2181-2   M      A01X+081275Y+158501X0198Y0197R090 S1      
327AGND_HSC         PC2185-2          A01X+080458Y+159463X0198Y0197R180 S1      
317AGND_HSC         VIA   -    MD0100PA00X+080215Y+159463X0200Y         S0      
327AGND_HSC         PC1525-2   M      A01X+077045Y+158411X0198Y0197R090 S1      
327AGND_HSC         PU287 -20         A01X+077677Y+158335X0100Y0150R270 S1      
317AGND_HSC         VIA   -    MD0100PA00X+076775Y+158411X0200Y         S0      
327AGND_HSC         PU289 -44  M      A01X+072196Y+158679X0460Y0630R270 S1      
317AGND_HSC         VIA   -    MD0100PA00X+072396Y+158579X0200Y    R270 S0      
317AGND_HSC         VIA   -    MD0100PA00X+072196Y+158779X0200Y    R270 S0      
317AGND_HSC         VIA   -    MD0100PA00X+071996Y+158579X0200Y    R270 S0      
327AGND_HSC         PC2187-2          A01X+070204Y+158452X0198Y0197R180 S1      
317AGND_HSC         VIA   -    MD0100PA00X+069961Y+158452X0200Y         S0      
327AGND_HSC         PC2225-2          A01X+093372Y+158223X0198Y0197     S1      
317AGND_HSC         VIA   -    MD0100PA00X+093615Y+158223X0200Y         S0      
327AGND_HSC         PR1101-2          A01X+080458Y+158263X0198Y0197R180 S1      
317AGND_HSC         VIA   -    MD0100PA00X+080215Y+158283X0200Y         S0      
327AGND_HSC         PU289 -18         A01X+071670Y+158148X0090Y0150R270 S1      
327AGND_HSC         PR3002-2          A01X+070518Y+158052X0198Y0197     S1      
317AGND_HSC         VIA   -    MD0100PA00X+071411Y+158148X0200Y         S0      
327AGND_HSC         PC2103-2          A01X+070204Y+157652X0198Y0197R180 S1      
317AGND_HSC         VIA   -    MD0100PA00X+069961Y+157652X0200Y         S0      
327AGND_HSC         PR1131-2          A01X+070204Y+157252X0198Y0197R180 S1      
317AGND_HSC         VIA   -    MD0100PA00X+069961Y+157252X0200Y         S0      
327AGND_HSC         PC2193-2   M      A01X+070204Y+156452X0198Y0197R180 S1      
327AGND_HSC         PR3930-1          A01X+070206Y+156057X0198Y0197     S1      
327AGND_HSC         PR1133-2   M      A01X+070204Y+156852X0198Y0197R180 S1      
317AGND_HSC         VIA   -    MD0100PA00X+069961Y+156852X0200Y         S0      
317AGND_HSC         VIA   -    MD0100PA00X+088615Y+157863X0200Y         S0      
327AGND_HSC         PR3987-2          A01X+088858Y+157863X0198Y0197R180 S1      
317AGND_HSC         VIA   -    MD0100PA00X+084415Y+157863X0200Y         S0      
327AGND_HSC         PR3986-2          A01X+084658Y+157863X0198Y0197R180 S1      
317AGND_HSC         VIA   -    MD0100PA00X+080215Y+157863X0200Y         S0      
327AGND_HSC         PR3915-2          A01X+080458Y+157863X0198Y0197R180 S1      
317AGND_HSC         VIA   -    MD0100PA00X+076065Y+157473X0200Y         S0      
327AGND_HSC         PR3914-2          A01X+076308Y+157473X0198Y0197R180 S1      
317AGND_HSC         VIA   -    MD0100PA00X+076065Y+157873X0200Y         S0      
327AGND_HSC         PR3918-2          A01X+076308Y+157873X0198Y0197R180 S1      
317AGND_HSC         VIA   -    MD0100PA00X+080215Y+157063X0200Y         S0      
327AGND_HSC         PC2348-2          A01X+080458Y+157063X0198Y0197R180 S1      
317AGND_HSC         VIA   -    MD0100PA00X+076065Y+157063X0200Y         S0      
327AGND_HSC         PC2347-2          A01X+076306Y+157063X0198Y0197R180 S1      
327AGND_HSC         PC2192-2   M      A01X+070192Y+159650X0198Y0197R180 S1      
327AGND_HSC         PR3935-2          A01X+070204Y+159252X0198Y0197R180 S1      
C                                                                               
C  ****************************************                                     
C      DUMMY NET PINS & VIAS ON THE BOARD                                       
C  ****************************************                                     
C                                                                               
327_d_bc14eb10      U18   -U12        A01X+074772Y+045454X0160Y    R090 S1      
317_d_bc14eb10      VIA   -     D0100PA00X+074926Y+045607X0180Y    R090 S0      
317_d_c5b37868      VIA   -     D0080PA00X+132304Y+102806X0160Y         S0      
327_d_c5b37868      U25   -BF63       A01X+132487Y+102701X0177Y    R180 S1      
317_d_c5b37918      VIA   -     D0080PA00X+132118Y+103124X0160Y         S0      
327_d_c5b37918      U25   -BG64       A01X+132302Y+103020X0177Y    R180 S1      
317_d_c5b37b60      VIA   -     D0080PA00X+132000Y+098805X0160Y    R180 S0      
327_d_c5b37b60      U25   -AU64       A01X+132184Y+098910X0177Y    R180 S1      
317_d_c5b37c10      VIA   -     D0080PA00X+132556Y+099124X0160Y    R180 S0      
327_d_c5b37c10      U25   -AV62       A01X+132739Y+099228X0177Y    R180 S1      
317_d_c5b37cc0      VIA   -     D0080PA00X+132674Y+105357X0160Y         S0      
327_d_c5b37cc0      U25   -BP62       A01X+132858Y+105252X0177Y    R180 S1      
317_d_c5b3a490      VIA   -     D0080PA00X+132859Y+104400X0160Y         S0      
327_d_c5b3a490      U25   -BL62       A01X+133042Y+104295X0177Y    R180 S1      
317_d_c5b3a540      VIA   -     D0080PA00X+132304Y+104719X0160Y         S0      
327_d_c5b3a540      U25   -BM63       A01X+132487Y+104614X0177Y    R180 S1      
317_d_c5b3a5f0      VIA   -     D0080PA00X+132118Y+105676X0160Y         S0      
327_d_c5b3a5f0      U25   -BR64       A01X+132302Y+105571X0177Y    R180 S1      
317_d_c5b3d628      VIA   -     D0080PA00X+134894Y+102806X0160Y         S0      
327_d_c5b3d628      U25   -BF56       A01X+135078Y+102701X0177Y    R180 S1      
317_d_c5b3d6d8      VIA   -     D0080PA00X+134709Y+103124X0160Y         S0      
327_d_c5b3d6d8      U25   -BG57       A01X+134893Y+103020X0177Y    R180 S1      
317_d_c5b3d998      VIA   -     D0080PA00X+134591Y+098805X0160Y    R180 S0      
327_d_c5b3d998      U25   -AU57       A01X+134775Y+098910X0177Y    R180 S1      
317_d_c5b3da48      VIA   -     D0080PA00X+135146Y+099124X0160Y    R180 S0      
327_d_c5b3da48      U25   -AV55       A01X+135330Y+099228X0177Y    R180 S1      
317_d_c5b3daf8      VIA   -     D0080PA00X+135264Y+105357X0160Y         S0      
327_d_c5b3daf8      U25   -BP55       A01X+135448Y+105252X0177Y    R180 S1      
317_d_c5b40bd8      VIA   -     D0080PA00X+135449Y+104400X0160Y         S0      
327_d_c5b40bd8      U25   -BL55       A01X+135633Y+104295X0177Y    R180 S1      
317_d_c5b40c88      VIA   -     D0080PA00X+134894Y+104719X0160Y         S0      
327_d_c5b40c88      U25   -BM56       A01X+135078Y+104614X0177Y    R180 S1      
317_d_c5b40d38      VIA   -     D0080PA00X+134709Y+105676X0160Y         S0      
327_d_c5b40d38      U25   -BR57       A01X+134893Y+105571X0177Y    R180 S1      
317_d_c5b43b90      VIA   -     D0080PA00X+133414Y+102806X0160Y         S0      
327_d_c5b43b90      U25   -BF60       A01X+133598Y+102701X0177Y    R180 S1      
317_d_c5b43c40      VIA   -     D0080PA00X+133599Y+103124X0160Y         S0      
327_d_c5b43c40      U25   -BG60       A01X+133783Y+103020X0177Y    R180 S1      
317_d_c5b43ed8      VIA   -     D0080PA00X+133481Y+098805X0160Y    R180 S0      
327_d_c5b43ed8      U25   -AU60       A01X+133665Y+098910X0177Y    R180 S1      
317_d_c5b43f88      VIA   -     D0080PA00X+134036Y+099124X0160Y    R180 S0      
327_d_c5b43f88      U25   -AV58       A01X+134220Y+099228X0177Y    R180 S1      
317_d_c5b44038      VIA   -     D0080PA00X+134154Y+105357X0160Y         S0      
327_d_c5b44038      U25   -BP58       A01X+134338Y+105252X0177Y    R180 S1      
317_d_c5b47028      VIA   -     D0080PA00X+133969Y+104400X0160Y         S0      
327_d_c5b47028      U25   -BL59       A01X+134153Y+104295X0177Y    R180 S1      
317_d_c5b470d8      VIA   -     D0080PA00X+133414Y+104719X0160Y         S0      
327_d_c5b470d8      U25   -BM60       A01X+133598Y+104614X0177Y    R180 S1      
317_d_c5b47188      VIA   -     D0080PA00X+133599Y+105676X0160Y         S0      
327_d_c5b47188      U25   -BR60       A01X+133783Y+105571X0177Y    R180 S1      
317_d_c5b4a220      VIA   -     D0080PA00X+129713Y+102806X0160Y         S0      
327_d_c5b4a220      U25   -BF70       A01X+129897Y+102701X0177Y    R180 S1      
317_d_c5b4a2c8      VIA   -     D0080PA00X+129528Y+103124X0160Y         S0      
327_d_c5b4a2c8      U25   -BG71       A01X+129712Y+103020X0177Y    R180 S1      
317_d_c5b4a540      VIA   -     D0080PA00X+129410Y+098805X0160Y    R180 S0      
327_d_c5b4a540      U25   -AU71       A01X+129594Y+098910X0177Y    R180 S1      
317_d_c5b4a5e8      VIA   -     D0080PA00X+129965Y+099124X0160Y    R180 S0      
327_d_c5b4a5e8      U25   -AV69       A01X+130149Y+099228X0177Y    R180 S1      
317_d_c5b4a690      VIA   -     D0080PA00X+130083Y+105357X0160Y         S0      
327_d_c5b4a690      U25   -BP69       A01X+130267Y+105252X0177Y    R180 S1      
317_d_c5b4d418      VIA   -     D0080PA00X+130268Y+104400X0160Y         S0      
327_d_c5b4d418      U25   -BL69       A01X+130452Y+104295X0177Y    R180 S1      
317_d_c5b4d4c0      VIA   -     D0080PA00X+129713Y+104719X0160Y         S0      
327_d_c5b4d4c0      U25   -BM70       A01X+129897Y+104614X0177Y    R180 S1      
317_d_c5b4d568      VIA   -     D0080PA00X+129528Y+105676X0160Y         S0      
327_d_c5b4d568      U25   -BR71       A01X+129712Y+105571X0177Y    R180 S1      
317_d_c5b50508      VIA   -     D0080PA00X+130823Y+102806X0160Y         S0      
327_d_c5b50508      U25   -BF67       A01X+131007Y+102701X0177Y    R180 S1      
317_d_c5b505b0      VIA   -     D0080PA00X+131008Y+103124X0160Y         S0      
327_d_c5b505b0      U25   -BG67       A01X+131192Y+103020X0177Y    R180 S1      
317_d_c5b50840      VIA   -     D0080PA00X+130890Y+098805X0160Y    R180 S0      
327_d_c5b50840      U25   -AU67       A01X+131074Y+098910X0177Y    R180 S1      
317_d_c5b508f0      VIA   -     D0080PA00X+131445Y+099124X0160Y    R180 S0      
327_d_c5b508f0      U25   -AV65       A01X+131629Y+099228X0177Y    R180 S1      
317_d_c5b509a0      VIA   -     D0080PA00X+131563Y+105357X0160Y         S0      
327_d_c5b509a0      U25   -BP65       A01X+131747Y+105252X0177Y    R180 S1      
317_d_c5b53788      VIA   -     D0080PA00X+131378Y+104400X0160Y         S0      
327_d_c5b53788      U25   -BL66       A01X+131562Y+104295X0177Y    R180 S1      
317_d_c5b53838      VIA   -     D0080PA00X+130823Y+104719X0160Y         S0      
327_d_c5b53838      U25   -BM67       A01X+131007Y+104614X0177Y    R180 S1      
317_d_c5b538e8      VIA   -     D0080PA00X+131008Y+105676X0160Y         S0      
327_d_c5b538e8      U25   -BR67       A01X+131192Y+105571X0177Y    R180 S1      
317_d_bd0a48c0      VIA   -     D0080PA00X+151175Y+102806X0160Y         S0      
327_d_bd0a48c0      U25   -BF13       A01X+150991Y+102701X0177Y    R180 S1      
317_d_c5b60bf0      VIA   -     D0080PA00X+151360Y+103124X0160Y         S0      
327_d_c5b60bf0      U25   -BG12       A01X+151176Y+103020X0177Y    R180 S1      
317_d_bd0a5ab8      VIA   -     D0080PA00X+151057Y+099124X0160Y    R180 S0      
327_d_bd0a5ab8      U25   -AV13       A01X+150873Y+099228X0177Y    R180 S1      
317_d_c5b8f368      VIA   -     D0080PA00X+150502Y+099443X0160Y    R180 S0      
327_d_c5b8f368      U25   -AW14       A01X+150318Y+099547X0177Y    R180 S1      
317_d_c5b5d9c0      VIA   -     D0080PA00X+150805Y+105357X0160Y         S0      
327_d_c5b5d9c0      U25   -BP14       A01X+150621Y+105252X0177Y    R180 S1      
317_d_c5b67680      VIA   -     D0080PA00X+151360Y+104400X0160Y         S0      
327_d_c5b67680      U25   -BL12       A01X+151176Y+104295X0177Y    R180 S1      
317_d_c945c6a8      VIA   -     D0080PA00X+151175Y+104719X0160Y         S0      
327_d_c945c6a8      U25   -BM13       A01X+150991Y+104614X0177Y    R180 S1      
317_d_c5b60ca0      VIA   -     D0080PA00X+151360Y+105676X0160Y         S0      
327_d_c5b60ca0      U25   -BR12       A01X+151176Y+105571X0177Y    R180 S1      
317_d_bd0a4a00      VIA   -     D0080PA00X+148585Y+102806X0160Y         S0      
327_d_bd0a4a00      U25   -BF20       A01X+148401Y+102701X0177Y    R180 S1      
317_d_bd0a49b0      VIA   -     D0080PA00X+148770Y+103124X0160Y         S0      
327_d_bd0a49b0      U25   -BG19       A01X+148586Y+103020X0177Y    R180 S1      
317_d_c5b8f158      VIA   -     D0080PA00X+148466Y+099124X0160Y    R180 S0      
327_d_c5b8f158      U25   -AV20       A01X+148283Y+099228X0177Y    R180 S1      
317_d_c5b8f838      VIA   -     D0080PA00X+147911Y+099443X0160Y    R180 S0      
327_d_c5b8f838      U25   -AW21       A01X+147728Y+099547X0177Y    R180 S1      
317_d_c5b64450      VIA   -     D0080PA00X+148214Y+105357X0160Y         S0      
327_d_c5b64450      U25   -BP21       A01X+148031Y+105252X0177Y    R180 S1      
317_d_c836a418      VIA   -     D0080PA00X+148770Y+104400X0160Y         S0      
327_d_c836a418      U25   -BL19       A01X+148586Y+104295X0177Y    R180 S1      
317_d_c946f198      VIA   -     D0080PA00X+148585Y+104719X0160Y         S0      
327_d_c946f198      U25   -BM20       A01X+148401Y+104614X0177Y    R180 S1      
317_d_c5b67730      VIA   -     D0080PA00X+148770Y+105676X0160Y         S0      
327_d_c5b67730      U25   -BR19       A01X+148586Y+105571X0177Y    R180 S1      
317_d_bd0a4910      VIA   -     D0080PA00X+150065Y+102806X0160Y         S0      
327_d_bd0a4910      U25   -BF16       A01X+149881Y+102701X0177Y    R180 S1      
317_d_bd0a4960      VIA   -     D0080PA00X+149880Y+103124X0160Y         S0      
327_d_bd0a4960      U25   -BG16       A01X+149696Y+103020X0177Y    R180 S1      
317_d_c5b8f2b8      VIA   -     D0080PA00X+149947Y+099124X0160Y    R180 S0      
327_d_c5b8f2b8      U25   -AV16       A01X+149763Y+099228X0177Y    R180 S1      
317_d_c5b8f208      VIA   -     D0080PA00X+149392Y+099443X0160Y    R180 S0      
327_d_c5b8f208      U25   -AW17       A01X+149208Y+099547X0177Y    R180 S1      
317_d_c5b6ad00      VIA   -     D0080PA00X+149325Y+105357X0160Y         S0      
327_d_c5b6ad00      U25   -BP18       A01X+149141Y+105252X0177Y    R180 S1      
317_d_bd0abb20      VIA   -     D0080PA00X+149880Y+104400X0160Y         S0      
327_d_bd0abb20      U25   -BL16       A01X+149696Y+104295X0177Y    R180 S1      
317_d_c946b680      VIA   -     D0080PA00X+150065Y+104719X0160Y         S0      
327_d_c946b680      U25   -BM16       A01X+149881Y+104614X0177Y    R180 S1      
317_d_c5b6dd90      VIA   -     D0080PA00X+149880Y+105676X0160Y         S0      
327_d_c5b6dd90      U25   -BR16       A01X+149696Y+105571X0177Y    R180 S1      
317_d_c5b85750      VIA   -     D0080PA00X+140512Y+088600X0160Y    R180 S0      
327_d_c5b85750      U25   -E41        A01X+140696Y+088705X0177Y    R180 S1      
317_d_c5b858a0      VIA   -     D0080PA00X+140882Y+088600X0160Y    R180 S0      
327_d_c5b858a0      U25   -E40        A01X+141066Y+088705X0177Y    R180 S1      
317_d_c5b859f0      VIA   -     D0080PA00X+140142Y+087962X0160Y    R180 S0      
327_d_c5b859f0      U25   -C42        A01X+140326Y+088067X0177Y    R180 S1      
317_d_c946b6a8      VIA   -     D0080PA00X+140512Y+087962X0160Y    R180 S0      
327_d_c946b6a8      U25   -C41        A01X+140696Y+088067X0177Y    R180 S1      
317_d_c5b8da98      VIA   -     D0080PA00X+146801Y+088600X0160Y    R180 S0      
327_d_c5b8da98      U25   -E24        A01X+146617Y+088705X0177Y    R180 S1      
317_d_c5b8df18      VIA   -     D0080PA00X+141000Y+115880X0160Y         S0      
327_d_c5b8df18      U25   -DG40       A01X+141184Y+115776X0177Y    R180 S1      
317_d_c5b8dfc8      VIA   -     D0080PA00X+131563Y+116199X0160Y         S0      
327_d_c5b8dfc8      U25   -DH65       A01X+131747Y+116094X0177Y    R180 S1      
317_d_c5b8e078      VIA   -     D0080PA00X+131748Y+116518X0160Y         S0      
327_d_c5b8e078      U25   -DJ65       A01X+131932Y+116413X0177Y    R180 S1      
317_d_c5b8e128      VIA   -     D0080PA00X+130268Y+116518X0160Y         S0      
327_d_c5b8e128      U25   -DJ69       A01X+130452Y+116413X0177Y    R180 S1      
317_d_c5b8e1d8      VIA   -     D0080PA00X+130083Y+116199X0160Y         S0      
327_d_c5b8e1d8      U25   -DH69       A01X+130267Y+116094X0177Y    R180 S1      
317_d_c5b8e5a8      VIA   -     D0080PA00X+134154Y+116199X0160Y         S0      
327_d_c5b8e5a8      U25   -DH58       A01X+134338Y+116094X0177Y    R180 S1      
317_d_c5b8e658      VIA   -     D0080PA00X+134339Y+115880X0160Y         S0      
327_d_c5b8e658      U25   -DG58       A01X+134523Y+115776X0177Y    R180 S1      
317_d_bd0a4e60      VIA   -     D0080PA00X+151797Y+101037X0160Y    R180 S0      
327_d_bd0a4e60      U25   -BD11       A01X+151613Y+101142X0177Y    R180 S1      
317_d_c5beef50      VIA   -     D0080PA00X+150687Y+101037X0160Y    R180 S0      
327_d_c5beef50      U25   -BD14       A01X+150503Y+101142X0177Y    R180 S1      
317_d_c5beeea0      VIA   -     D0080PA00X+149207Y+101037X0160Y    R180 S0      
327_d_c5beeea0      U25   -BD18       A01X+149023Y+101142X0177Y    R180 S1      
317_d_c5be84c0      VIA   -     D0080PA00X+148096Y+101037X0160Y    R180 S0      
327_d_c5be84c0      U25   -BD21       A01X+147913Y+101142X0177Y    R180 S1      
317_d_bd0a4eb0      VIA   -     D0080PA00X+154388Y+101037X0160Y    R180 S0      
327_d_bd0a4eb0      U25   -BD4        A01X+154204Y+101142X0177Y    R180 S1      
317_d_c5b8f4c8      VIA   -     D0080PA00X+135146Y+101037X0160Y    R180 S0      
327_d_c5b8f4c8      U25   -BD55       A01X+135330Y+101142X0177Y    R180 S1      
317_d_c5b8f578      VIA   -     D0080PA00X+134036Y+101037X0160Y    R180 S0      
327_d_c5b8f578      U25   -BD58       A01X+134220Y+101142X0177Y    R180 S1      
317_d_c5b8f628      VIA   -     D0080PA00X+132556Y+101037X0160Y    R180 S0      
327_d_c5b8f628      U25   -BD62       A01X+132739Y+101142X0177Y    R180 S1      
317_d_c5b8f6d8      VIA   -     D0080PA00X+131445Y+101037X0160Y    R180 S0      
327_d_c5b8f6d8      U25   -BD65       A01X+131629Y+101142X0177Y    R180 S1      
317_d_c5b8f788      VIA   -     D0080PA00X+129965Y+101037X0160Y    R180 S0      
327_d_c5b8f788      U25   -BD69       A01X+130149Y+101142X0177Y    R180 S1      
317_d_bd0a4dc0      VIA   -     D0080PA00X+153278Y+101037X0160Y    R180 S0      
327_d_bd0a4dc0      U25   -BD7        A01X+153094Y+101142X0177Y    R180 S1      
317_d_c5b8f8e8      VIA   -     D0080PA00X+128855Y+101037X0160Y    R180 S0      
327_d_c5b8f8e8      U25   -BD72       A01X+129039Y+101142X0177Y    R180 S1      
317_d_c5b60b40      VIA   -     D0080PA00X+152655Y+102806X0160Y         S0      
327_d_c5b60b40      U25   -BF9        A01X+152472Y+102701X0177Y    R180 S1      
317_d_c5bebb10      VIA   -     D0080PA00X+152470Y+103124X0160Y         S0      
327_d_c5bebb10      U25   -BG9        A01X+152287Y+103020X0177Y    R180 S1      
317_d_bd0a5a68      VIA   -     D0080PA00X+152537Y+099124X0160Y    R180 S0      
327_d_bd0a5a68      U25   -AV9        A01X+152354Y+099228X0177Y    R180 S1      
317_d_bd0a5a18      VIA   -     D0080PA00X+151982Y+099443X0160Y    R180 S0      
327_d_bd0a5a18      U25   -AW10       A01X+151798Y+099547X0177Y    R180 S1      
317_d_c5be88e0      VIA   -     D0080PA00X+151915Y+105357X0160Y         S0      
327_d_c5be88e0      U25   -BP11       A01X+151732Y+105252X0177Y    R180 S1      
317_d_bd0a3ec0      VIA   -     D0080PA00X+152470Y+104400X0160Y         S0      
327_d_bd0a3ec0      U25   -BL9        A01X+152287Y+104295X0177Y    R180 S1      
317_d_bd0a4050      VIA   -     D0080PA00X+152655Y+104719X0160Y         S0      
327_d_bd0a4050      U25   -BM9        A01X+152472Y+104614X0177Y    R180 S1      
317_d_c5bebbc0      VIA   -     D0080PA00X+152470Y+105676X0160Y         S0      
327_d_c5bebbc0      U25   -BR9        A01X+152287Y+105571X0177Y    R180 S1      
317_d_c5beba60      VIA   -     D0080PA00X+153766Y+102806X0160Y         S0      
327_d_c5beba60      U25   -BF6        A01X+153582Y+102701X0177Y    R180 S1      
317_d_c5bf25a0      VIA   -     D0080PA00X+153951Y+103124X0160Y         S0      
327_d_c5bf25a0      U25   -BG5        A01X+153767Y+103020X0177Y    R180 S1      
317_d_bd0a5b58      VIA   -     D0080PA00X+153648Y+099124X0160Y    R180 S0      
327_d_bd0a5b58      U25   -AV6        A01X+153464Y+099228X0177Y    R180 S1      
317_d_bd0a5b08      VIA   -     D0080PA00X+153092Y+099443X0160Y    R180 S0      
327_d_bd0a5b08      U25   -AW7        A01X+152909Y+099547X0177Y    R180 S1      
317_d_c5bef370      VIA   -     D0080PA00X+153396Y+105357X0160Y         S0      
327_d_c5bef370      U25   -BP7        A01X+153212Y+105252X0177Y    R180 S1      
317_d_bd0a3f10      VIA   -     D0080PA00X+153951Y+104400X0160Y         S0      
327_d_bd0a3f10      U25   -BL5        A01X+153767Y+104295X0177Y    R180 S1      
317_d_bd0a40a0      VIA   -     D0080PA00X+153766Y+104719X0160Y         S0      
327_d_bd0a40a0      U25   -BM6        A01X+153582Y+104614X0177Y    R180 S1      
317_d_c5bf2650      VIA   -     D0080PA00X+153951Y+105676X0160Y         S0      
327_d_c5bf2650      U25   -BR5        A01X+153767Y+105571X0177Y    R180 S1      
317_d_c8db9360      VIA   -     D0080PA00X+034689Y+102806X0160Y         S0      
327_d_c8db9360      U26   -BF63       A01X+034873Y+102701X0177Y    R180 S1      
317_d_c8db92a8      VIA   -     D0080PA00X+034504Y+103124X0160Y         S0      
327_d_c8db92a8      U26   -BG64       A01X+034688Y+103020X0177Y    R180 S1      
317_d_c8dacbc0      VIA   -     D0080PA00X+034386Y+098805X0160Y         S0      
327_d_c8dacbc0      U26   -AU64       A01X+034570Y+098910X0177Y    R180 S1      
317_d_c8dac920      VIA   -     D0080PA00X+034941Y+099124X0160Y         S0      
327_d_c8dac920      U26   -AV62       A01X+035125Y+099228X0177Y    R180 S1      
317_d_c8dbbbd8      VIA   -     D0080PA00X+035060Y+105357X0160Y         S0      
327_d_c8dbbbd8      U26   -BP62       A01X+035243Y+105252X0177Y    R180 S1      
317_d_c8dcbd68      VIA   -     D0080PA00X+035244Y+104400X0160Y         S0      
327_d_c8dcbd68      U26   -BL62       A01X+035428Y+104295X0177Y    R180 S1      
317_d_c8dcc090      VIA   -     D0080PA00X+034689Y+104719X0160Y         S0      
327_d_c8dcc090      U26   -BM63       A01X+034873Y+104614X0177Y    R180 S1      
317_d_c8dbb238      VIA   -     D0080PA00X+034504Y+105676X0160Y         S0      
327_d_c8dbb238      U26   -BR64       A01X+034688Y+105571X0177Y    R180 S1      
317_d_c8dbac08      VIA   -     D0080PA00X+037280Y+102806X0160Y         S0      
327_d_c8dbac08      U26   -BF56       A01X+037464Y+102701X0177Y    R180 S1      
317_d_c8dba5f8      VIA   -     D0080PA00X+037095Y+103124X0160Y         S0      
327_d_c8dba5f8      U26   -BG57       A01X+037279Y+103020X0177Y    R180 S1      
317_d_c8dac410      VIA   -     D0080PA00X+036977Y+098805X0160Y         S0      
327_d_c8dac410      U26   -AU57       A01X+037161Y+098910X0177Y    R180 S1      
317_d_c8dac3e8      VIA   -     D0080PA00X+037532Y+099124X0160Y         S0      
327_d_c8dac3e8      U26   -AV55       A01X+037716Y+099228X0177Y    R180 S1      
317_d_c8dbb0f0      VIA   -     D0080PA00X+037650Y+105357X0160Y         S0      
327_d_c8dbb0f0      U26   -BP55       A01X+037834Y+105252X0177Y    R180 S1      
317_d_c8dbacf0      VIA   -     D0080PA00X+037835Y+104400X0160Y         S0      
327_d_c8dbacf0      U26   -BL55       A01X+038019Y+104295X0177Y    R180 S1      
317_d_c8dbaec0      VIA   -     D0080PA00X+037280Y+104719X0160Y         S0      
327_d_c8dbaec0      U26   -BM56       A01X+037464Y+104614X0177Y    R180 S1      
317_d_c8dbb1e0      VIA   -     D0080PA00X+037095Y+105676X0160Y         S0      
327_d_c8dbb1e0      U26   -BR57       A01X+037279Y+105571X0177Y    R180 S1      
317_d_c8db9788      VIA   -     D0080PA00X+035800Y+102806X0160Y         S0      
327_d_c8db9788      U26   -BF60       A01X+035983Y+102701X0177Y    R180 S1      
317_d_c8db9aa0      VIA   -     D0080PA00X+035985Y+103124X0160Y         S0      
327_d_c8db9aa0      U26   -BG60       A01X+036168Y+103020X0177Y    R180 S1      
317_d_c8dac6a0      VIA   -     D0080PA00X+035867Y+098805X0160Y         S0      
327_d_c8dac6a0      U26   -AU60       A01X+036050Y+098910X0177Y    R180 S1      
317_d_c8dac4c8      VIA   -     D0080PA00X+036422Y+099124X0160Y         S0      
327_d_c8dac4c8      U26   -AV58       A01X+036606Y+099228X0177Y    R180 S1      
317_d_c8dbc210      VIA   -     D0080PA00X+036540Y+105357X0160Y         S0      
327_d_c8dbc210      U26   -BP58       A01X+036724Y+105252X0177Y    R180 S1      
317_d_c8dcb0c8      VIA   -     D0080PA00X+036355Y+104400X0160Y         S0      
327_d_c8dcb0c8      U26   -BL59       A01X+036538Y+104295X0177Y    R180 S1      
317_d_c8dcbbf0      VIA   -     D0080PA00X+035800Y+104719X0160Y         S0      
327_d_c8dcbbf0      U26   -BM60       A01X+035983Y+104614X0177Y    R180 S1      
317_d_c8dbbff0      VIA   -     D0080PA00X+035985Y+105676X0160Y         S0      
327_d_c8dbbff0      U26   -BR60       A01X+036168Y+105571X0177Y    R180 S1      
317_d_c8db8958      VIA   -     D0080PA00X+032099Y+102806X0160Y         S0      
327_d_c8db8958      U26   -BF70       A01X+032283Y+102701X0177Y    R180 S1      
317_d_c8db8780      VIA   -     D0080PA00X+031914Y+103124X0160Y         S0      
327_d_c8db8780      U26   -BG71       A01X+032098Y+103020X0177Y    R180 S1      
317_d_c8db8678      VIA   -     D0080PA00X+031796Y+098805X0160Y         S0      
327_d_c8db8678      U26   -AU71       A01X+031980Y+098910X0177Y    R180 S1      
317_d_c8dad520      VIA   -     D0080PA00X+032351Y+099124X0160Y         S0      
327_d_c8dad520      U26   -AV69       A01X+032535Y+099228X0177Y    R180 S1      
317_d_bd87e340      VIA   -     D0080PA00X+032469Y+105357X0160Y         S0      
327_d_bd87e340      U26   -BP69       A01X+032653Y+105252X0177Y    R180 S1      
317_d_c8dcd5b0      VIA   -     D0080PA00X+032654Y+104400X0160Y         S0      
327_d_c8dcd5b0      U26   -BL69       A01X+032838Y+104295X0177Y    R180 S1      
317_d_c8dcd800      VIA   -     D0080PA00X+032099Y+104719X0160Y         S0      
327_d_c8dcd800      U26   -BM70       A01X+032283Y+104614X0177Y    R180 S1      
317_d_c2a33a20      VIA   -     D0080PA00X+031914Y+105676X0160Y         S0      
327_d_c2a33a20      U26   -BR71       A01X+032098Y+105571X0177Y    R180 S1      
317_d_c8db8c30      VIA   -     D0080PA00X+033209Y+102806X0160Y         S0      
327_d_c8db8c30      U26   -BF67       A01X+033393Y+102701X0177Y    R180 S1      
317_d_c8db8f88      VIA   -     D0080PA00X+033394Y+103124X0160Y         S0      
327_d_c8db8f88      U26   -BG67       A01X+033578Y+103020X0177Y    R180 S1      
317_d_c8dad160      VIA   -     D0080PA00X+033276Y+098805X0160Y         S0      
327_d_c8dad160      U26   -AU67       A01X+033460Y+098910X0177Y    R180 S1      
317_d_c8dace98      VIA   -     D0080PA00X+033831Y+099124X0160Y         S0      
327_d_c8dace98      U26   -AV65       A01X+034015Y+099228X0177Y    R180 S1      
317_d_c8dcd828      VIA   -     D0080PA00X+033949Y+105357X0160Y         S0      
327_d_c8dcd828      U26   -BP65       A01X+034133Y+105252X0177Y    R180 S1      
317_d_c8dcc298      VIA   -     D0080PA00X+033764Y+104400X0160Y         S0      
327_d_c8dcc298      U26   -BL66       A01X+033948Y+104295X0177Y    R180 S1      
317_d_c8dcc6c0      VIA   -     D0080PA00X+033209Y+104719X0160Y         S0      
327_d_c8dcc6c0      U26   -BM67       A01X+033393Y+104614X0177Y    R180 S1      
317_d_b9fe2388      VIA   -     D0080PA00X+033394Y+105676X0160Y         S0      
327_d_b9fe2388      U26   -BR67       A01X+033578Y+105571X0177Y    R180 S1      
317_d_c8d7c828      VIA   -     D0080PA00X+053561Y+102806X0160Y         S0      
327_d_c8d7c828      U26   -BF13       A01X+053377Y+102701X0177Y    R180 S1      
317_d_c8d7d3a8      VIA   -     D0080PA00X+053746Y+103124X0160Y         S0      
327_d_c8d7d3a8      U26   -BG12       A01X+053562Y+103020X0177Y    R180 S1      
317_d_c8d68b90      VIA   -     D0080PA00X+053443Y+099124X0160Y         S0      
327_d_c8d68b90      U26   -AV13       A01X+053259Y+099228X0177Y    R180 S1      
317_d_c8d68e88      VIA   -     D0080PA00X+052888Y+099443X0160Y         S0      
327_d_c8d68e88      U26   -AW14       A01X+052704Y+099547X0177Y    R180 S1      
317_d_c8d82bb0      VIA   -     D0080PA00X+053191Y+105357X0160Y         S0      
327_d_c8d82bb0      U26   -BP14       A01X+053007Y+105252X0177Y    R180 S1      
317_d_c8d861a0      VIA   -     D0080PA00X+053746Y+104400X0160Y         S0      
327_d_c8d861a0      U26   -BL12       A01X+053562Y+104295X0177Y    R180 S1      
317_d_c8d85b70      VIA   -     D0080PA00X+053561Y+104719X0160Y         S0      
327_d_c8d85b70      U26   -BM13       A01X+053377Y+104614X0177Y    R180 S1      
317_d_c8d83bb8      VIA   -     D0080PA00X+053746Y+105676X0160Y         S0      
327_d_c8d83bb8      U26   -BR12       A01X+053562Y+105571X0177Y    R180 S1      
317_d_c8d7b2d8      VIA   -     D0080PA00X+050970Y+102806X0160Y         S0      
327_d_c8d7b2d8      U26   -BF20       A01X+050787Y+102701X0177Y    R180 S1      
317_d_c8d7b8c0      VIA   -     D0080PA00X+051155Y+103124X0160Y         S0      
327_d_c8d7b8c0      U26   -BG19       A01X+050972Y+103020X0177Y    R180 S1      
317_d_c8d68110      VIA   -     D0080PA00X+050852Y+099124X0160Y         S0      
327_d_c8d68110      U26   -AV20       A01X+050668Y+099228X0177Y    R180 S1      
317_d_c8d67db0      VIA   -     D0080PA00X+050297Y+099443X0160Y         S0      
327_d_c8d67db0      U26   -AW21       A01X+050113Y+099547X0177Y    R180 S1      
317_d_c8d8d5c8      VIA   -     D0080PA00X+050600Y+105357X0160Y         S0      
327_d_c8d8d5c8      U26   -BP21       A01X+050416Y+105252X0177Y    R180 S1      
317_d_c8d884b8      VIA   -     D0080PA00X+051155Y+104400X0160Y         S0      
327_d_c8d884b8      U26   -BL19       A01X+050972Y+104295X0177Y    R180 S1      
317_d_c8d89688      VIA   -     D0080PA00X+050970Y+104719X0160Y         S0      
327_d_c8d89688      U26   -BM20       A01X+050787Y+104614X0177Y    R180 S1      
317_d_c8d8caa8      VIA   -     D0080PA00X+051155Y+105676X0160Y         S0      
327_d_c8d8caa8      U26   -BR19       A01X+050972Y+105571X0177Y    R180 S1      
317_d_c8d7c688      VIA   -     D0080PA00X+052451Y+102806X0160Y         S0      
327_d_c8d7c688      U26   -BF16       A01X+052267Y+102701X0177Y    R180 S1      
317_d_c8d7bcd0      VIA   -     D0080PA00X+052266Y+103124X0160Y         S0      
327_d_c8d7bcd0      U26   -BG16       A01X+052082Y+103020X0177Y    R180 S1      
317_d_c8d69170      VIA   -     D0080PA00X+052333Y+099124X0160Y         S0      
327_d_c8d69170      U26   -AV16       A01X+052149Y+099228X0177Y    R180 S1      
317_d_c8d682e0      VIA   -     D0080PA00X+051778Y+099443X0160Y         S0      
327_d_c8d682e0      U26   -AW17       A01X+051594Y+099547X0177Y    R180 S1      
317_d_c8d8a0e8      VIA   -     D0080PA00X+051710Y+105357X0160Y         S0      
327_d_c8d8a0e8      U26   -BP18       A01X+051527Y+105252X0177Y    R180 S1      
317_d_c8d86c70      VIA   -     D0080PA00X+052266Y+104400X0160Y         S0      
327_d_c8d86c70      U26   -BL16       A01X+052082Y+104295X0177Y    R180 S1      
317_d_c8d87be8      VIA   -     D0080PA00X+052451Y+104719X0160Y         S0      
327_d_c8d87be8      U26   -BM16       A01X+052267Y+104614X0177Y    R180 S1      
317_d_c8d8c0d8      VIA   -     D0080PA00X+052266Y+105676X0160Y         S0      
327_d_c8d8c0d8      U26   -BR16       A01X+052082Y+105571X0177Y    R180 S1      
317_d_c8da1eb8      VIA   -     D0080PA00X+039567Y+088600X0160Y         S0      
327_d_c8da1eb8      U26   -E50        A01X+039751Y+088705X0177Y    R180 S1      
317_d_c8da1710      VIA   -     D0080PA00X+039937Y+088600X0160Y         S0      
327_d_c8da1710      U26   -E49        A01X+040121Y+088705X0177Y    R180 S1      
317_d_c8da35b0      VIA   -     D0080PA00X+039197Y+087962X0160Y         S0      
327_d_c8da35b0      U26   -C51        A01X+039381Y+088067X0177Y    R180 S1      
317_d_c8da30e0      VIA   -     D0080PA00X+039567Y+087962X0160Y         S0      
327_d_c8da30e0      U26   -C50        A01X+039751Y+088067X0177Y    R180 S1      
317_d_c598b608      VIA   -     D0080PA00X+046344Y+116518X0160Y         S0      
327_d_c598b608      U26   -DJ32       A01X+046161Y+116414X0177Y    R180 S1      
317_d_c8dd10e0      VIA   -     D0080PA00X+047270Y+116199X0160Y         S0      
327_d_c8dd10e0      U26   -DH30       A01X+047086Y+116095X0177Y    R180 S1      
317_d_c7efa9a8      VIA   -     D0080PA00X+047084Y+115243X0160Y         S0      
327_d_c7efa9a8      U26   -DE30       A01X+046901Y+115138X0177Y    R180 S1      
317_d_c8dd0350      VIA   -     D0080PA00X+046900Y+115562X0160Y         S0      
327_d_c8dd0350      U26   -DF31       A01X+046716Y+115457X0177Y    R180 S1      
317_d_c8dd10b8      VIA   -     D0080PA00X+046714Y+115880X0160Y         S0      
327_d_c8dd10b8      U26   -DG31       A01X+046531Y+115776X0177Y    R180 S1      
317_d_c8dd0b08      VIA   -     D0080PA00X+046344Y+115880X0160Y         S0      
327_d_c8dd0b08      U26   -DG32       A01X+046161Y+115776X0177Y    R180 S1      
317_d_bd0bd950      VIA   -     D0080PA00X+052888Y+087962X0160Y         S0      
327_d_bd0bd950      U26   -C14        A01X+052704Y+088067X0177Y    R180 S1      
317_d_bd0bdba8      VIA   -     D0080PA00X+053258Y+087325X0160Y         S0      
327_d_bd0bdba8      U26   -A13        A01X+053074Y+087429X0177Y    R180 S1      
317_d_bd0af0d0      VIA   -     D0080PA00X+045049Y+115562X0160Y         S0      
327_d_bd0af0d0      U26   -DF36       A01X+044865Y+115457X0177Y    R180 S1      
317_d_c598ca08      VIA   -     D0080PA00X+056892Y+116199X0160Y         S0      
327_d_c598ca08      U26   -DH4        A01X+056708Y+116095X0177Y    R180 S1      
317_d_c6b7c9b0      VIA   -     D0080PA00X+054116Y+115880X0160Y         S0      
327_d_c6b7c9b0      U26   -DG11       A01X+053932Y+115776X0177Y    R180 S1      
317_d_c8db7190      VIA   -     D0080PA00X+047455Y+116518X0160Y         S0      
327_d_c8db7190      U26   -DJ29       A01X+047271Y+116414X0177Y    R180 S1      
317_d_c5f78670      VIA   -     D0080PA00X+053746Y+115880X0160Y         S0      
327_d_c5f78670      U26   -DG12       A01X+053562Y+115776X0177Y    R180 S1      
317_d_c6f6d0b8      VIA   -     D0080PA00X+053931Y+116199X0160Y         S0      
327_d_c6f6d0b8      U26   -DH12       A01X+053747Y+116095X0177Y    R180 S1      
317_d_bd0aecc0      VIA   -     D0080PA00X+050415Y+116518X0160Y         S0      
327_d_bd0aecc0      U26   -DJ21       A01X+050232Y+116414X0177Y    R180 S1      
317_d_c8db0fc0      VIA   -     D0080PA00X+050785Y+116518X0160Y         S0      
327_d_c8db0fc0      U26   -DJ20       A01X+050602Y+116414X0177Y    R180 S1      
317_d_bd0bd6d0      VIA   -     D0080PA00X+052703Y+088281X0160Y         S0      
327_d_bd0bd6d0      U26   -D15        A01X+052519Y+088386X0177Y    R180 S1      
317_d_bd0bd9c8      VIA   -     D0080PA00X+052703Y+087644X0160Y         S0      
327_d_bd0bd9c8      U26   -B15        A01X+052519Y+087748X0177Y    R180 S1      
317_d_c5989cb8      VIA   -     D0080PA00X+048935Y+116518X0160Y         S0      
327_d_c5989cb8      U26   -DJ25       A01X+048751Y+116414X0177Y    R180 S1      
317_d_c5989bf0      VIA   -     D0080PA00X+050045Y+116518X0160Y         S0      
327_d_c5989bf0      U26   -DJ22       A01X+049861Y+116414X0177Y    R180 S1      
317_d_c8dca5c0      VIA   -     D0080PA00X+048010Y+115562X0160Y         S0      
327_d_c8dca5c0      U26   -DF28       A01X+047826Y+115457X0177Y    R180 S1      
317_d_c8dafe80      VIA   -     D0080PA00X+050045Y+115880X0160Y         S0      
327_d_c8dafe80      U26   -DG22       A01X+049861Y+115776X0177Y    R180 S1      
317_d_c8e03b78      VIA   -     D0080PA00X+047825Y+116518X0160Y         S0      
327_d_c8e03b78      U26   -DJ28       A01X+047641Y+116414X0177Y    R180 S1      
317_d_c8dce930      VIA   -     D0080PA00X+047455Y+115880X0160Y         S0      
327_d_c8dce930      U26   -DG29       A01X+047271Y+115776X0177Y    R180 S1      
317_d_c8d81798      VIA   -     D0080PA00X+049490Y+115562X0160Y         S0      
327_d_c8d81798      U26   -DF24       A01X+049306Y+115457X0177Y    R180 S1      
317_d_c8db0590      VIA   -     D0080PA00X+049490Y+116199X0160Y         S0      
327_d_c8db0590      U26   -DH24       A01X+049306Y+116095X0177Y    R180 S1      
317_d_c5e90728      VIA   -     D0080PA00X+049305Y+115243X0160Y         S0      
327_d_c5e90728      U26   -DE24       A01X+049121Y+115138X0177Y    R180 S1      
317_d_c89304c8      VIA   -     D0080PA00X+049120Y+115562X0160Y         S0      
327_d_c89304c8      U26   -DF25       A01X+048936Y+115457X0177Y    R180 S1      
317_d_c8c9bf78      VIA   -     D0080PA00X+048935Y+115880X0160Y         S0      
327_d_c8c9bf78      U26   -DG25       A01X+048751Y+115776X0177Y    R180 S1      
317_d_c8db0240      VIA   -     D0080PA00X+049675Y+115880X0160Y         S0      
327_d_c8db0240      U26   -DG23       A01X+049491Y+115776X0177Y    R180 S1      
317_d_c8dce618      VIA   -     D0080PA00X+047825Y+115880X0160Y         S0      
327_d_c8dce618      U26   -DG28       A01X+047641Y+115776X0177Y    R180 S1      
317_d_c59892e0      VIA   -     D0080PA00X+049675Y+116518X0160Y         S0      
327_d_c59892e0      U26   -DJ23       A01X+049491Y+116414X0177Y    R180 S1      
317_d_c8db1208      VIA   -     D0080PA00X+048565Y+116518X0160Y         S0      
327_d_c8db1208      U26   -DJ26       A01X+048381Y+116414X0177Y    R180 S1      
317_d_c5995c70      VIA   -     D0080PA00X+048195Y+115243X0160Y         S0      
327_d_c5995c70      U26   -DE27       A01X+048011Y+115138X0177Y    R180 S1      
317_d_c8dd0328      VIA   -     D0080PA00X+047270Y+115562X0160Y         S0      
327_d_c8dd0328      U26   -DF30       A01X+047086Y+115457X0177Y    R180 S1      
317_d_c8db3eb0      VIA   -     D0080PA00X+048565Y+115880X0160Y         S0      
327_d_c8db3eb0      U26   -DG26       A01X+048381Y+115776X0177Y    R180 S1      
317_d_c8db17f8      VIA   -     D0080PA00X+048380Y+116199X0160Y         S0      
327_d_c8db17f8      U26   -DH27       A01X+048196Y+116095X0177Y    R180 S1      
317_d_c8d94448      VIA   -     D0080PA00X+046596Y+087325X0160Y         S0      
327_d_c8d94448      U26   -A31        A01X+046413Y+087429X0177Y    R180 S1      
317_d_c8da15f8      VIA   -     D0080PA00X+045116Y+087325X0160Y         S0      
327_d_c8da15f8      U26   -A35        A01X+044932Y+087429X0177Y    R180 S1      
317_d_bd0bda40      VIA   -     D0080PA00X+041418Y+087325X0160Y         S0      
327_d_bd0bda40      U26   -A45        A01X+041602Y+087429X0177Y    R180 S1      
317_d_c8da26f0      VIA   -     D0080PA00X+040308Y+087325X0160Y         S0      
327_d_c8da26f0      U26   -A48        A01X+040491Y+087429X0177Y    R180 S1      
317_d_c8da2bd8      VIA   -     D0080PA00X+039567Y+087325X0160Y         S0      
327_d_c8da2bd8      U26   -A50        A01X+039751Y+087429X0177Y    R180 S1      
317_d_c8da2ad0      VIA   -     D0080PA00X+039197Y+087325X0160Y         S0      
327_d_c8da2ad0      U26   -A51        A01X+039381Y+087429X0177Y    R180 S1      
317_d_c8da4830      VIA   -     D0080PA00X+038087Y+087325X0160Y         S0      
327_d_c8da4830      U26   -A54        A01X+038271Y+087429X0177Y    R180 S1      
317_d_c8da6b38      VIA   -     D0080PA00X+037717Y+087325X0160Y         S0      
327_d_c8da6b38      U26   -A55        A01X+037901Y+087429X0177Y    R180 S1      
317_d_c8dab820      VIA   -     D0080PA00X+037347Y+087325X0160Y         S0      
327_d_c8dab820      U26   -A56        A01X+037531Y+087429X0177Y    R180 S1      
317_d_c8dabe88      VIA   -     D0080PA00X+036977Y+087325X0160Y         S0      
327_d_c8dabe88      U26   -A57        A01X+037161Y+087429X0177Y    R180 S1      
317_d_c8d70790      VIA   -     D0080PA00X+054183Y+101037X0160Y         S0      
327_d_c8d70790      U26   -BD11       A01X+053999Y+101142X0177Y    R180 S1      
317_d_c8d70d90      VIA   -     D0080PA00X+053073Y+101037X0160Y         S0      
327_d_c8d70d90      U26   -BD14       A01X+052889Y+101142X0177Y    R180 S1      
317_d_c8d722b0      VIA   -     D0080PA00X+051592Y+101037X0160Y         S0      
327_d_c8d722b0      U26   -BD18       A01X+051409Y+101142X0177Y    R180 S1      
317_d_c8d72e48      VIA   -     D0080PA00X+050482Y+101037X0160Y         S0      
327_d_c8d72e48      U26   -BD21       A01X+050298Y+101142X0177Y    R180 S1      
317_d_c8d6ffc8      VIA   -     D0080PA00X+056774Y+101037X0160Y         S0      
327_d_c8d6ffc8      U26   -BD4        A01X+056590Y+101142X0177Y    R180 S1      
317_d_c8dabee0      VIA   -     D0080PA00X+037532Y+101037X0160Y         S0      
327_d_c8dabee0      U26   -BD55       A01X+037716Y+101142X0177Y    R180 S1      
317_d_c8dabf30      VIA   -     D0080PA00X+036422Y+101037X0160Y         S0      
327_d_c8dabf30      U26   -BD58       A01X+036606Y+101142X0177Y    R180 S1      
317_d_c8dabfa8      VIA   -     D0080PA00X+034941Y+101037X0160Y         S0      
327_d_c8dabfa8      U26   -BD62       A01X+035125Y+101142X0177Y    R180 S1      
317_d_c8dac060      VIA   -     D0080PA00X+033831Y+101037X0160Y         S0      
327_d_c8dac060      U26   -BD65       A01X+034015Y+101142X0177Y    R180 S1      
317_d_c8dac220      VIA   -     D0080PA00X+032351Y+101037X0160Y         S0      
327_d_c8dac220      U26   -BD69       A01X+032535Y+101142X0177Y    R180 S1      
317_d_c8d701b0      VIA   -     D0080PA00X+055663Y+101037X0160Y         S0      
327_d_c8d701b0      U26   -BD7        A01X+055480Y+101142X0177Y    R180 S1      
317_d_c8d99ba8      VIA   -     D0080PA00X+046596Y+087962X0160Y         S0      
327_d_c8d99ba8      U26   -C31        A01X+046413Y+088067X0177Y    R180 S1      
317_d_c8d9fae8      VIA   -     D0080PA00X+045486Y+087962X0160Y         S0      
327_d_c8d9fae8      U26   -C34        A01X+045302Y+088067X0177Y    R180 S1      
317_d_c8da09c8      VIA   -     D0080PA00X+045116Y+087962X0160Y         S0      
327_d_c8da09c8      U26   -C35        A01X+044932Y+088067X0177Y    R180 S1      
317_d_c8da38c8      VIA   -     D0080PA00X+038457Y+087962X0160Y         S0      
327_d_c8da38c8      U26   -C53        A01X+038641Y+088067X0177Y    R180 S1      
317_d_c8da3b08      VIA   -     D0080PA00X+038087Y+087962X0160Y         S0      
327_d_c8da3b08      U26   -C54        A01X+038271Y+088067X0177Y    R180 S1      
317_d_bd0bd6f8      VIA   -     D0080PA00X+054183Y+088281X0160Y         S0      
327_d_bd0bd6f8      U26   -D11        A01X+053999Y+088386X0177Y    R180 S1      
317_d_c8d902d0      VIA   -     D0080PA00X+050112Y+088281X0160Y         S0      
327_d_c8d902d0      U26   -D22        A01X+049928Y+088386X0177Y    R180 S1      
317_d_c8d9a908      VIA   -     D0080PA00X+045671Y+088281X0160Y         S0      
327_d_c8d9a908      U26   -D34        A01X+045487Y+088386X0177Y    R180 S1      
317_d_c8d9f288      VIA   -     D0080PA00X+044931Y+088281X0160Y         S0      
327_d_c8d9f288      U26   -D36        A01X+044747Y+088386X0177Y    R180 S1      
317_d_c8d8fb78      VIA   -     D0080PA00X+056774Y+088281X0160Y         S0      
327_d_c8d8fb78      U26   -D4         A01X+056590Y+088386X0177Y    R180 S1      
317_d_c8d8e840      VIA   -     D0080PA00X+055293Y+088281X0160Y         S0      
327_d_c8d8e840      U26   -D8         A01X+055109Y+088386X0177Y    R180 S1      
317_d_c892c108      VIA   -     D0080PA00X+051896Y+115880X0160Y         S0      
327_d_c892c108      U26   -DG17       A01X+051712Y+115776X0177Y    R180 S1      
317_d_c8897708      VIA   -     D0080PA00X+052081Y+116199X0160Y         S0      
327_d_c8897708      U26   -DH17       A01X+051897Y+116095X0177Y    R180 S1      
317_d_c8db0cf0      VIA   -     D0080PA00X+050600Y+116199X0160Y         S0      
327_d_c8db0cf0      U26   -DH21       A01X+050416Y+116095X0177Y    R180 S1      
317_d_c598c6c0      VIA   -     D0080PA00X+056707Y+116518X0160Y         S0      
327_d_c598c6c0      U26   -DJ4        A01X+056523Y+116414X0177Y    R180 S1      
317_d_c8d9d7d0      VIA   -     D0080PA00X+045856Y+088600X0160Y         S0      
327_d_c8d9d7d0      U26   -E33        A01X+045672Y+088705X0177Y    R180 S1      
317_d_c8d9e758      VIA   -     D0080PA00X+044746Y+088600X0160Y         S0      
327_d_c8d9e758      U26   -E36        A01X+044562Y+088705X0177Y    R180 S1      
317_d_c5e911d0      VIA   -     D0080PA00X+053561Y+116199X0160Y         S0      
327_d_c5e911d0      U26   -DH13       A01X+053377Y+116095X0177Y    R180 S1      
317_d_c598a488      VIA   -     D0080PA00X+042831Y+115562X0160Y         S0      
327_d_c598a488      U26   -DF41       A01X+043015Y+115457X0177Y    R180 S1      
317_d_c8d93088      VIA   -     D0080PA00X+049557Y+087962X0160Y         S0      
327_d_c8d93088      U26   -C23        A01X+049373Y+088067X0177Y    R180 S1      
317_d_c598dd90      VIA   -     D0080PA00X+053191Y+116199X0160Y         S0      
327_d_c598dd90      U26   -DH14       A01X+053007Y+116095X0177Y    R180 S1      
317_d_c2a33a48      VIA   -     D0080PA00X+042646Y+115880X0160Y         S0      
327_d_c2a33a48      U26   -DG42       A01X+042830Y+115776X0177Y    R180 S1      
317_d_c8d90c78      VIA   -     D0080PA00X+049742Y+088281X0160Y         S0      
327_d_c8d90c78      U26   -D23        A01X+049558Y+088386X0177Y    R180 S1      
317_d_c8da0f80      VIA   -     D0080PA00X+044931Y+087644X0160Y         S0      
327_d_c8da0f80      U26   -B36        A01X+044747Y+087748X0177Y    R180 S1      
317_d_c8d7eeb8      VIA   -     D0080PA00X+055041Y+102806X0160Y         S0      
327_d_c8d7eeb8      U26   -BF9        A01X+054857Y+102701X0177Y    R180 S1      
317_d_c8d80650      VIA   -     D0080PA00X+054856Y+103124X0160Y         S0      
327_d_c8d80650      U26   -BG9        A01X+054672Y+103020X0177Y    R180 S1      
317_d_c8d69ee0      VIA   -     D0080PA00X+054923Y+099124X0160Y         S0      
327_d_c8d69ee0      U26   -AV9        A01X+054739Y+099228X0177Y    R180 S1      
317_d_c8d69548      VIA   -     D0080PA00X+054368Y+099443X0160Y         S0      
327_d_c8d69548      U26   -AW10       A01X+054184Y+099547X0177Y    R180 S1      
317_d_c8d85138      VIA   -     D0080PA00X+054301Y+105357X0160Y         S0      
327_d_c8d85138      U26   -BP11       A01X+054117Y+105252X0177Y    R180 S1      
317_d_c8d812c0      VIA   -     D0080PA00X+054856Y+104400X0160Y         S0      
327_d_c8d812c0      U26   -BL9        A01X+054672Y+104295X0177Y    R180 S1      
317_d_c8d81bd0      VIA   -     D0080PA00X+055041Y+104719X0160Y         S0      
327_d_c8d81bd0      U26   -BM9        A01X+054857Y+104614X0177Y    R180 S1      
317_d_c8d825b8      VIA   -     D0080PA00X+054856Y+105676X0160Y         S0      
327_d_c8d825b8      U26   -BR9        A01X+054672Y+105571X0177Y    R180 S1      
317_d_c8d7ac08      VIA   -     D0080PA00X+056152Y+102806X0160Y         S0      
327_d_c8d7ac08      U26   -BF6        A01X+055968Y+102701X0177Y    R180 S1      
317_d_c8d7a570      VIA   -     D0080PA00X+056336Y+103124X0160Y         S0      
327_d_c8d7a570      U26   -BG5        A01X+056153Y+103020X0177Y    R180 S1      
317_d_c8d6a178      VIA   -     D0080PA00X+056033Y+099124X0160Y         S0      
327_d_c8d6a178      U26   -AV6        A01X+055850Y+099228X0177Y    R180 S1      
317_d_c8d6aa60      VIA   -     D0080PA00X+055478Y+099443X0160Y         S0      
327_d_c8d6aa60      U26   -AW7        A01X+055294Y+099547X0177Y    R180 S1      
317_d_c8d73308      VIA   -     D0080PA00X+055781Y+105357X0160Y         S0      
327_d_c8d73308      U26   -BP7        A01X+055598Y+105252X0177Y    R180 S1      
317_d_c8d79648      VIA   -     D0080PA00X+056336Y+104400X0160Y         S0      
327_d_c8d79648      U26   -BL5        A01X+056153Y+104295X0177Y    R180 S1      
317_d_c8d79270      VIA   -     D0080PA00X+056152Y+104719X0160Y         S0      
327_d_c8d79270      U26   -BM6        A01X+055968Y+104614X0177Y    R180 S1      
317_d_c8d72f70      VIA   -     D0080PA00X+056336Y+105676X0160Y         S0      
327_d_c8d72f70      U26   -BR5        A01X+056153Y+105571X0177Y    R180 S1      
317_d_b9adb328      VIA   -     D0100PA00X+116427Y+106470X0190Y         S0      
327_d_b9adb328      J15   -231        A01X+116427Y+106470X0205Y0590R090 S1      
317_d_b9a4df98      VIA   -     D0100PA00X+116427Y+106805X0190Y         S0      
327_d_b9a4df98      J15   -232        A01X+116427Y+106805X0205Y0590R090 S1      
317_d_b9a4ded0      VIA   -     D0100PA00X+018813Y+106471X0190Y         S0      
327_d_b9a4ded0      J26   -231        A01X+018813Y+106471X0205Y0590R090 S1      
317_d_b9abb2b8      VIA   -     D0100PA00X+018813Y+106805X0190Y         S0      
327_d_b9abb2b8      J26   -232        A01X+018813Y+106805X0205Y0590R090 S1      
317_d_b9abb1f0      VIA   -     D0100PA00X+113457Y+106470X0190Y         S0      
327_d_b9abb1f0      J17   -231        A01X+113457Y+106470X0205Y0590R090 S1      
317_d_b9a2f2e8      VIA   -     D0100PA00X+113457Y+106805X0190Y         S0      
327_d_b9a2f2e8      J17   -232        A01X+113457Y+106805X0205Y0590R090 S1      
317_d_b9a2f220      VIA   -     D0100PA00X+015842Y+106471X0190Y         S0      
327_d_b9a2f220      J28   -231        A01X+015842Y+106471X0205Y0590R090 S1      
317_d_b9a9c5f8      VIA   -     D0100PA00X+015842Y+106805X0190Y         S0      
327_d_b9a9c5f8      J28   -232        A01X+015842Y+106805X0205Y0590R090 S1      
317_d_b9a9c530      VIA   -     D0100PA00X+110487Y+106470X0190Y         S0      
327_d_b9a9c530      J19   -231        A01X+110487Y+106470X0205Y0590R090 S1      
317_d_b9a10638      VIA   -     D0100PA00X+110487Y+106805X0190Y         S0      
327_d_b9a10638      J19   -232        A01X+110487Y+106805X0205Y0590R090 S1      
317_d_b9a10570      VIA   -     D0100PA00X+012872Y+106471X0190Y         S0      
327_d_b9a10570      J30   -231        A01X+012872Y+106471X0205Y0590R090 S1      
317_d_b9a7d948      VIA   -     D0100PA00X+012872Y+106805X0190Y         S0      
327_d_b9a7d948      J30   -232        A01X+012872Y+106805X0205Y0590R090 S1      
317_d_b9a7d880      VIA   -     D0100PA00X+107517Y+106470X0190Y         S0      
327_d_b9a7d880      J21   -231        A01X+107517Y+106470X0205Y0590R090 S1      
317_d_b9a00fe0      VIA   -     D0100PA00X+107517Y+106805X0190Y         S0      
327_d_b9a00fe0      J21   -232        A01X+107517Y+106805X0205Y0590R090 S1      
317_d_b9a00f18      VIA   -     D0100PA00X+009902Y+106471X0190Y         S0      
327_d_b9a00f18      J32   -231        A01X+009902Y+106471X0205Y0590R090 S1      
317_d_b9a6e2f0      VIA   -     D0100PA00X+009902Y+106805X0190Y         S0      
327_d_b9a6e2f0      J32   -232        A01X+009902Y+106805X0205Y0590R090 S1      
317_d_b9a6e228      VIA   -     D0100PA00X+104546Y+106470X0190Y         S0      
327_d_b9a6e228      J23   -231        A01X+104546Y+106470X0205Y0590R090 S1      
317_d_b99f19b0      VIA   -     D0100PA00X+104546Y+106805X0190Y         S0      
327_d_b99f19b0      J23   -232        A01X+104546Y+106805X0205Y0590R090 S1      
317_d_bcfd34a0      VIA   -     D0100PA00X+006932Y+106471X0190Y         S0      
327_d_bcfd34a0      J33   -231        A01X+006932Y+106471X0205Y0590R090 S1      
317_d_bcfd05b0      VIA   -     D0100PA00X+006932Y+106805X0190Y         S0      
327_d_bcfd05b0      J33   -232        A01X+006932Y+106805X0205Y0590R090 S1      
317_d_b99b40a8      VIA   -     D0100PA00X+165320Y+106470X0190Y         S0      
327_d_b99b40a8      J69   -231        A01X+165320Y+106470X0205Y0590R090 S1      
317_d_b9a3e940      VIA   -     D0100PA00X+165320Y+106805X0190Y         S0      
327_d_b9a3e940      J69   -232        A01X+165320Y+106805X0205Y0590R090 S1      
317_d_b9a3e878      VIA   -     D0100PA00X+067706Y+106471X0190Y         S0      
327_d_b9a3e878      J27   -231        A01X+067706Y+106471X0205Y0590R090 S1      
317_d_b9aabc30      VIA   -     D0100PA00X+067706Y+106805X0190Y         S0      
327_d_b9aabc30      J27   -232        A01X+067706Y+106805X0205Y0590R090 S1      
317_d_b9aabb68      VIA   -     D0100PA00X+168290Y+106470X0190Y         S0      
327_d_b9aabb68      J18   -231        A01X+168290Y+106470X0205Y0590R090 S1      
317_d_b9995510      VIA   -     D0100PA00X+168290Y+106805X0190Y         S0      
327_d_b9995510      J18   -232        A01X+168290Y+106805X0205Y0590R090 S1      
317_d_b9995448      VIA   -     D0100PA00X+070676Y+106471X0190Y         S0      
327_d_b9995448      J100  -231        A01X+070676Y+106471X0205Y0590R090 S1      
317_d_b99c3778      VIA   -     D0100PA00X+070676Y+106805X0190Y         S0      
327_d_b99c3778      J100  -232        A01X+070676Y+106805X0205Y0590R090 S1      
317_d_b99c36b0      VIA   -     D0100PA00X+171260Y+106470X0190Y         S0      
327_d_b99c36b0      J68   -231        A01X+171260Y+106470X0205Y0590R090 S1      
317_d_b9a1fc90      VIA   -     D0100PA00X+171260Y+106805X0190Y         S0      
327_d_b9a1fc90      J68   -232        A01X+171260Y+106805X0205Y0590R090 S1      
317_d_b9a1fbc8      VIA   -     D0100PA00X+073646Y+106471X0190Y         S0      
327_d_b9a1fbc8      J29   -231        A01X+073646Y+106471X0205Y0590R090 S1      
317_d_b9a8cfa0      VIA   -     D0100PA00X+073646Y+106805X0190Y         S0      
327_d_b9a8cfa0      J29   -232        A01X+073646Y+106805X0205Y0590R090 S1      
317_d_b9a8ced8      VIA   -     D0100PA00X+174230Y+106470X0190Y         S0      
327_d_b9a8ced8      J20   -231        A01X+174230Y+106470X0205Y0590R090 S1      
317_d_b99a4b40      VIA   -     D0100PA00X+174230Y+106805X0190Y         S0      
327_d_b99a4b40      J20   -232        A01X+174230Y+106805X0205Y0590R090 S1      
317_d_b99a4a78      VIA   -     D0100PA00X+076616Y+106471X0190Y         S0      
327_d_b99a4a78      J99   -231        A01X+076616Y+106471X0205Y0590R090 S1      
317_d_b99d2da8      VIA   -     D0100PA00X+076616Y+106805X0190Y         S0      
327_d_b99d2da8      J99   -232        A01X+076616Y+106805X0205Y0590R090 S1      
317_d_b99d2ce0      VIA   -     D0100PA00X+177200Y+106470X0190Y         S0      
327_d_b99d2ce0      J67   -231        A01X+177200Y+106470X0205Y0590R090 S1      
317_d_bcfd06a8      VIA   -     D0100PA00X+177200Y+106805X0190Y         S0      
327_d_bcfd06a8      J67   -232        A01X+177200Y+106805X0205Y0590R090 S1      
317_d_bcfd3030      VIA   -     D0100PA00X+079586Y+106471X0190Y         S0      
327_d_bcfd3030      J37   -231        A01X+079586Y+106471X0205Y0590R090 S1      
317_d_ba2f2cf8      VIA   -     D0100PA00X+079586Y+106805X0190Y         S0      
327_d_ba2f2cf8      J37   -232        A01X+079586Y+106805X0205Y0590R090 S1      
327N/C                    -           A01X+108866Y+029965X0390Y    R180 S1      
327N/C                    -           A18X+040926Y+041211X0390Y    R180 S2      
327N/C                    -           A18X+092501Y+101460X0390Y    R180 S2      
327N/C                    -           A01X+148996Y+140300X0390Y    R180 S1      
327N/C                    -           A01X+086462Y+136852X0390Y    R180 S1      
327N/C                    -           A01X+092501Y+101460X0390Y    R180 S1      
327N/C              U6010 -FJ31       A01X+118733Y+154808X0100Y0130R090 S1      
327N/C              U6011 -FJ31       A01X+131539Y+154808X0100Y0130R090 S1      
327N/C              U6012 -FJ31       A01X+157957Y+154808X0100Y0130R090 S1      
327N/C              U6013 -FJ31       A01X+145150Y+154808X0100Y0130R090 S1      
327N/C              U6014 -FJ31       A01X+017946Y+151508X0100Y0130R090 S1      
327N/C              U6015 -FJ31       A01X+030752Y+151508X0100Y0130R090 S1      
327N/C              U6016 -FJ31       A01X+057169Y+151508X0100Y0130R090 S1      
327N/C              U6017 -FJ31       A01X+044363Y+151508X0100Y0130R090 S1      
327N/C              U6014 -FJ6        A01X+017946Y+153398X0100Y0130R090 S1      
327N/C              U6014 -FJ23       A01X+017946Y+152217X0100Y0130R090 S1      
327N/C                    -           A18X+170493Y+164938X0390Y    R180 S2      
317N/C              J212  -10   D0440PA00X+135126Y+016421X0640Y    R270 S3      
317N/C              J212  -9    D0440PA00X+135126Y+017421X0640Y    R270 S3      
317N/C              J45   -SCR_ D1200UA00X+079128Y+170489X2910Y2910R270 S3      
317N/C              J45   -SCR_ D1200UA00X+106628Y+170489X2910Y2910R270 S3      
317N/C              U25   -MH6  D1580UA00X+158255Y+101921X1580Y    R180 S3      
317N/C              U25   -MH5  D1580UA00X+153728Y+119992X1580Y    R180 S3      
317N/C              U25   -MH4  D1580UA00X+129633Y+119992X1580Y    R180 S3      
317N/C              U25   -MH3  D1580UA00X+125106Y+101921X1580Y    R180 S3      
317N/C              U25   -MH2  D1580UA00X+129633Y+083850X1580Y    R180 S3      
317N/C              U25   -MH1  D1580UA00X+153728Y+083850X1580Y    R180 S3      
327N/C              U25   -BF74       A01X+128416Y+102701X0177Y    R180 S1      
327N/C              U25   -BG74       A01X+128602Y+103020X0177Y    R180 S1      
327N/C              U25   -AU74       A01X+128484Y+098910X0177Y    R180 S1      
327N/C              U25   -AV72       A01X+129039Y+099228X0177Y    R180 S1      
327N/C              U25   -BP72       A01X+129157Y+105252X0177Y    R180 S1      
327N/C              U25   -BL73       A01X+128972Y+104295X0177Y    R180 S1      
327N/C              U25   -BM74       A01X+128416Y+104614X0177Y    R180 S1      
327N/C              U25   -BR74       A01X+128602Y+105571X0177Y    R180 S1      
327N/C              U25   -BF2        A01X+155062Y+102701X0177Y    R180 S1      
327N/C              U25   -BG2        A01X+154877Y+103020X0177Y    R180 S1      
327N/C              U25   -AV2        A01X+154944Y+099228X0177Y    R180 S1      
327N/C              U25   -AW3        A01X+154389Y+099547X0177Y    R180 S1      
327N/C              U25   -BP4        A01X+154322Y+105252X0177Y    R180 S1      
327N/C              U25   -BL2        A01X+154877Y+104295X0177Y    R180 S1      
327N/C              U25   -BM2        A01X+155062Y+104614X0177Y    R180 S1      
327N/C              U25   -BR2        A01X+154877Y+105571X0177Y    R180 S1      
327N/C              U25   -E47        A01X+138476Y+088705X0177Y    R180 S1      
327N/C              U25   -E46        A01X+138846Y+088705X0177Y    R180 S1      
327N/C              U25   -C48        A01X+138106Y+088067X0177Y    R180 S1      
327N/C              U25   -C47        A01X+138476Y+088067X0177Y    R180 S1      
327N/C              U25   -B16        A01X+149763Y+087748X0177Y    R180 S1      
327N/C              U25   -DG11       A01X+151546Y+115776X0177Y    R180 S1      
327N/C              U25   -DJ47       A01X+138594Y+116413X0177Y    R180 S1      
327N/C              U25   -DJ48       A01X+138224Y+116413X0177Y    R180 S1      
327N/C              U25   -DJ50       A01X+137484Y+116413X0177Y    R180 S1      
327N/C              U25   -DJ51       A01X+137113Y+116413X0177Y    R180 S1      
327N/C              U25   -D15        A01X+150133Y+088386X0177Y    R180 S1      
327N/C              U25   -B15        A01X+150133Y+087748X0177Y    R180 S1      
327N/C              U25   -C28        A01X+145137Y+088067X0177Y    R180 S1      
327N/C              U25   -C29        A01X+144767Y+088067X0177Y    R180 S1      
327N/C              U25   -E29        A01X+144767Y+088705X0177Y    R180 S1      
327N/C              U25   -E30        A01X+144397Y+088705X0177Y    R180 S1      
327N/C              U25   -DH40       A01X+140999Y+116094X0177Y    R180 S1      
327N/C              U25   -DH62       A01X+132858Y+116094X0177Y    R180 S1      
327N/C              U25   -DJ62       A01X+133042Y+116413X0177Y    R180 S1      
327N/C              U25   -A31        A01X+144027Y+087429X0177Y    R180 S1      
327N/C              U25   -A35        A01X+142546Y+087429X0177Y    R180 S1      
327N/C              U25   -A41        A01X+140696Y+087429X0177Y    R180 S1      
327N/C              U25   -A42        A01X+140326Y+087429X0177Y    R180 S1      
327N/C              U25   -A45        A01X+139216Y+087429X0177Y    R180 S1      
327N/C              U25   -A48        A01X+138106Y+087429X0177Y    R180 S1      
327N/C              U25   -A50        A01X+137365Y+087429X0177Y    R180 S1      
327N/C              U25   -A51        A01X+136995Y+087429X0177Y    R180 S1      
327N/C              U25   -A54        A01X+135885Y+087429X0177Y    R180 S1      
327N/C              U25   -A55        A01X+135515Y+087429X0177Y    R180 S1      
327N/C              U25   -A56        A01X+135145Y+087429X0177Y    R180 S1      
327N/C              U25   -A57        A01X+134775Y+087429X0177Y    R180 S1      
327N/C              U25   -A59        A01X+134035Y+087429X0177Y    R180 S1      
327N/C              U25   -A60        A01X+133665Y+087429X0177Y    R180 S1      
327N/C              U25   -B40        A01X+140881Y+087748X0177Y    R180 S1      
327N/C              U25   -C31        A01X+144027Y+088067X0177Y    R180 S1      
327N/C              U25   -C34        A01X+142916Y+088067X0177Y    R180 S1      
327N/C              U25   -C35        A01X+142546Y+088067X0177Y    R180 S1      
327N/C              U25   -C53        A01X+136255Y+088067X0177Y    R180 S1      
327N/C              U25   -C54        A01X+135885Y+088067X0177Y    R180 S1      
327N/C              U25   -D11        A01X+151613Y+088386X0177Y    R180 S1      
327N/C              U25   -D22        A01X+147542Y+088386X0177Y    R180 S1      
327N/C              U25   -D34        A01X+143102Y+088386X0177Y    R180 S1      
327N/C              U25   -D36        A01X+142361Y+088386X0177Y    R180 S1      
327N/C              U25   -D4         A01X+154204Y+088386X0177Y    R180 S1      
327N/C              U25   -D58        A01X+134220Y+088386X0177Y    R180 S1      
327N/C              U25   -D62        A01X+132739Y+088386X0177Y    R180 S1      
327N/C              U25   -D65        A01X+131629Y+088386X0177Y    R180 S1      
327N/C              U25   -D72        A01X+129039Y+088386X0177Y    R180 S1      
327N/C              U25   -D8         A01X+152724Y+088386X0177Y    R180 S1      
327N/C              U25   -DG17       A01X+149326Y+115776X0177Y    R180 S1      
327N/C              U25   -DH17       A01X+149511Y+116094X0177Y    R180 S1      
327N/C              U25   -DH21       A01X+148031Y+116094X0177Y    R180 S1      
327N/C              U25   -DJ4        A01X+154137Y+116413X0177Y    R180 S1      
327N/C              U25   -E33        A01X+143287Y+088705X0177Y    R180 S1      
327N/C              U25   -E36        A01X+142176Y+088705X0177Y    R180 S1      
327N/C              U25   -C58        A01X+134405Y+088067X0177Y    R180 S1      
327N/C              U25   -DH13       A01X+150991Y+116094X0177Y    R180 S1      
327N/C              U25   -DF41       A01X+140629Y+115457X0177Y    R180 S1      
327N/C              U25   -C23        A01X+146987Y+088067X0177Y    R180 S1      
327N/C              U25   -C59        A01X+134035Y+088067X0177Y    R180 S1      
327N/C              U25   -DH14       A01X+150621Y+116094X0177Y    R180 S1      
327N/C              U25   -DG42       A01X+140444Y+115776X0177Y    R180 S1      
327N/C              U25   -D23        A01X+147172Y+088386X0177Y    R180 S1      
327N/C              U25   -B36        A01X+142361Y+087748X0177Y    R180 S1      
327N/C              U25   -DJ57       A01X+134893Y+116413X0177Y    R180 S1      
317N/C              U26   -MH6  D1580UA00X+060641Y+101921X1580Y    R180 S3      
317N/C              U26   -MH5  D1580UA00X+056113Y+119992X1580Y    R180 S3      
317N/C              U26   -MH4  D1580UA00X+032019Y+119992X1580Y    R180 S3      
317N/C              U26   -MH3  D1580UA00X+027491Y+101921X1580Y    R180 S3      
317N/C              U26   -MH2  D1580UA00X+032019Y+083850X1580Y    R180 S3      
317N/C              U26   -MH1  D1580UA00X+056113Y+083850X1580Y    R180 S3      
327N/C              U26   -BF74       A01X+030802Y+102701X0177Y    R180 S1      
327N/C              U26   -BG74       A01X+030987Y+103020X0177Y    R180 S1      
327N/C              U26   -AU74       A01X+030869Y+098910X0177Y    R180 S1      
327N/C              U26   -AV72       A01X+031424Y+099228X0177Y    R180 S1      
327N/C              U26   -BP72       A01X+031542Y+105252X0177Y    R180 S1      
327N/C              U26   -BL73       A01X+031357Y+104295X0177Y    R180 S1      
327N/C              U26   -BM74       A01X+030802Y+104614X0177Y    R180 S1      
327N/C              U26   -BR74       A01X+030987Y+105571X0177Y    R180 S1      
327N/C              U26   -BF2        A01X+057448Y+102701X0177Y    R180 S1      
327N/C              U26   -BG2        A01X+057263Y+103020X0177Y    R180 S1      
327N/C              U26   -AV2        A01X+057330Y+099228X0177Y    R180 S1      
327N/C              U26   -AW3        A01X+056775Y+099547X0177Y    R180 S1      
327N/C              U26   -BP4        A01X+056708Y+105252X0177Y    R180 S1      
327N/C              U26   -BL2        A01X+057263Y+104295X0177Y    R180 S1      
327N/C              U26   -BM2        A01X+057448Y+104614X0177Y    R180 S1      
327N/C              U26   -BR2        A01X+057263Y+105571X0177Y    R180 S1      
327N/C              U26   -A14        A01X+052704Y+087429X0177Y    R180 S1      
327N/C              U26   -B16        A01X+052149Y+087748X0177Y    R180 S1      
327N/C              U26   -DJ47       A01X+040980Y+116414X0177Y    R180 S1      
327N/C              U26   -DJ48       A01X+040609Y+116414X0177Y    R180 S1      
327N/C              U26   -DJ50       A01X+039869Y+116414X0177Y    R180 S1      
327N/C              U26   -DJ51       A01X+039499Y+116414X0177Y    R180 S1      
327N/C              U26   -C72        A01X+031609Y+088067X0177Y    R180 S1      
327N/C              U26   -B72        A01X+031424Y+087748X0177Y    R180 S1      
327N/C              U26   -A4         A01X+056405Y+087429X0177Y    R180 S1      
327N/C              U26   -B4         A01X+056590Y+087748X0177Y    R180 S1      
327N/C              U26   -A41        A01X+043082Y+087429X0177Y    R180 S1      
327N/C              U26   -A42        A01X+042712Y+087429X0177Y    R180 S1      
327N/C              U26   -A59        A01X+036420Y+087429X0177Y    R180 S1      
327N/C              U26   -A60        A01X+036050Y+087429X0177Y    R180 S1      
327N/C              U26   -B40        A01X+043267Y+087748X0177Y    R180 S1      
327N/C              U26   -BD72       A01X+031424Y+101142X0177Y    R180 S1      
327N/C              U26   -D58        A01X+036606Y+088386X0177Y    R180 S1      
327N/C              U26   -D62        A01X+035125Y+088386X0177Y    R180 S1      
327N/C              U26   -D65        A01X+034015Y+088386X0177Y    R180 S1      
327N/C              U26   -D72        A01X+031424Y+088386X0177Y    R180 S1      
327N/C              U26   -C58        A01X+036790Y+088067X0177Y    R180 S1      
327N/C              U26   -C59        A01X+036420Y+088067X0177Y    R180 S1      
327N/C              U26   -DJ57       A01X+037279Y+116414X0177Y    R180 S1      
317N/C              H111  -1    D1580UA00X+084124Y+142033X1580Y         S3      
317N/C              H112  -1    D1580UA00X+101624Y+142033X1580Y         S3      
317N/C              H90   -1    D1220UA00X+176693Y+171496X1220Y         S3      
327N/C              U6010 -FJ6        A01X+118733Y+156698X0100Y0130R090 S1      
327N/C              U6010 -FJ23       A01X+118733Y+155517X0100Y0130R090 S1      
327N/C              U6010 -E18        A01X+127100Y+155871X0120Y         S1      
327N/C              U6010 -B16        A01X+127305Y+155989X0100Y0130R090 S1      
327N/C              U6011 -FJ6        A01X+131539Y+156698X0100Y0130R090 S1      
327N/C              U6011 -FJ23       A01X+131539Y+155517X0100Y0130R090 S1      
327N/C              U6011 -E18        A01X+139906Y+155871X0120Y         S1      
327N/C              U6011 -B16        A01X+140111Y+155989X0100Y0130R090 S1      
327N/C              U6012 -FJ6        A01X+157957Y+156698X0100Y0130R090 S1      
327N/C              U6012 -FJ23       A01X+157957Y+155517X0100Y0130R090 S1      
327N/C              U6012 -E18        A01X+166324Y+155871X0120Y         S1      
327N/C              U6012 -B16        A01X+166528Y+155989X0100Y0130R090 S1      
327N/C              U6013 -FJ6        A01X+145150Y+156698X0100Y0130R090 S1      
327N/C              U6013 -FJ23       A01X+145150Y+155517X0100Y0130R090 S1      
327N/C              U6013 -E18        A01X+153518Y+155871X0120Y         S1      
327N/C              U6013 -B16        A01X+153722Y+155989X0100Y0130R090 S1      
327N/C              U6014 -E18        A01X+026313Y+152571X0120Y         S1      
327N/C              U6014 -B16        A01X+026517Y+152689X0100Y0130R090 S1      
327N/C              U6015 -FJ6        A01X+030752Y+153398X0100Y0130R090 S1      
327N/C              U6015 -FJ23       A01X+030752Y+152217X0100Y0130R090 S1      
327N/C              U6015 -E18        A01X+039119Y+152571X0120Y         S1      
327N/C              U6015 -B16        A01X+039324Y+152689X0100Y0130R090 S1      
327N/C              U6016 -FJ6        A01X+057169Y+153398X0100Y0130R090 S1      
327N/C              U6016 -FJ23       A01X+057169Y+152217X0100Y0130R090 S1      
327N/C              U6016 -E18        A01X+065536Y+152571X0120Y         S1      
327N/C              U6016 -B16        A01X+065741Y+152689X0100Y0130R090 S1      
327N/C              U6017 -FJ6        A01X+044363Y+153398X0100Y0130R090 S1      
327N/C              U6017 -FJ23       A01X+044363Y+152217X0100Y0130R090 S1      
327N/C              U6017 -E18        A01X+052730Y+152571X0120Y         S1      
327N/C              U6017 -B16        A01X+052935Y+152689X0100Y0130R090 S1      
327N/C              BIOS_L-1          A01X+000611Y+167306X0300Y         S1      
327N/C                    -           A18X+002356Y+159034X0390Y    R180 S2      
327N/C                    -           A18X+086462Y+136852X0390Y    R180 S2      
327N/C                    -           A18X+148996Y+140300X0390Y    R180 S2      
327N/C                    -           A18X+156879Y+017824X0390Y    R180 S2      
327N/C                    -           A18X+108866Y+029965X0390Y    R180 S2      
327N/C                    -           A18X+002071Y+013975X0390Y    R180 S2      
327N/C                    -           A01X+114824Y+055422X0390Y    R180 S1      
327N/C                    -           A01X+040926Y+041211X0390Y    R180 S1      
327N/C                    -           A01X+156879Y+017824X0390Y    R180 S1      
327N/C                    -           A01X+002356Y+159034X0390Y    R180 S1      
327N/C                    -           A01X+170493Y+164938X0390Y    R180 S1      
327N/C              J1    -2          A01X+121011Y+076018X0205Y0590R090 S1      
327N/C              J1    -144        A01X+121011Y+125545X0205Y0590R090 S1      
327N/C              J1    -149        A01X+119397Y+077022X0205Y0590R090 S1      
327N/C              J1    -150        A01X+119397Y+077356X0205Y0590R090 S1      
327N/C              J1    -220        A01X+119397Y+102789X0205Y0590R090 S1      
327N/C              J1    -231        A01X+119397Y+106470X0205Y0590R090 S1      
327N/C              J1    -232        A01X+119397Y+106805X0205Y0590R090 S1      
327N/C              J24   -2          A01X+023397Y+076018X0205Y0590R090 S1      
327N/C              J24   -144        A01X+023397Y+125545X0205Y0590R090 S1      
327N/C              J24   -149        A01X+021783Y+077022X0205Y0590R090 S1      
327N/C              J24   -150        A01X+021783Y+077356X0205Y0590R090 S1      
327N/C              J24   -220        A01X+021783Y+102790X0205Y0590R090 S1      
327N/C              J24   -231        A01X+021783Y+106471X0205Y0590R090 S1      
327N/C              J24   -232        A01X+021783Y+106805X0205Y0590R090 S1      
327N/C              J15   -2          A01X+118041Y+076018X0205Y0590R090 S1      
327N/C              J15   -144        A01X+118041Y+125545X0205Y0590R090 S1      
327N/C              J15   -149        A01X+116427Y+077022X0205Y0590R090 S1      
327N/C              J15   -150        A01X+116427Y+077356X0205Y0590R090 S1      
327N/C              J15   -220        A01X+116427Y+102789X0205Y0590R090 S1      
327N/C              J26   -2          A01X+020427Y+076018X0205Y0590R090 S1      
327N/C              J26   -144        A01X+020427Y+125545X0205Y0590R090 S1      
327N/C              J26   -149        A01X+018813Y+077022X0205Y0590R090 S1      
327N/C              J26   -150        A01X+018813Y+077356X0205Y0590R090 S1      
327N/C              J26   -220        A01X+018813Y+102790X0205Y0590R090 S1      
327N/C              J17   -2          A01X+115071Y+076018X0205Y0590R090 S1      
327N/C              J17   -144        A01X+115071Y+125545X0205Y0590R090 S1      
327N/C              J17   -149        A01X+113457Y+077022X0205Y0590R090 S1      
327N/C              J17   -150        A01X+113457Y+077356X0205Y0590R090 S1      
327N/C              J17   -220        A01X+113457Y+102789X0205Y0590R090 S1      
327N/C              J28   -2          A01X+017457Y+076018X0205Y0590R090 S1      
327N/C              J28   -144        A01X+017457Y+125545X0205Y0590R090 S1      
327N/C              J28   -149        A01X+015842Y+077022X0205Y0590R090 S1      
327N/C              J28   -150        A01X+015842Y+077356X0205Y0590R090 S1      
327N/C              J28   -220        A01X+015842Y+102790X0205Y0590R090 S1      
327N/C              J19   -2          A01X+112101Y+076018X0205Y0590R090 S1      
327N/C              J19   -144        A01X+112101Y+125545X0205Y0590R090 S1      
327N/C              J19   -149        A01X+110487Y+077022X0205Y0590R090 S1      
327N/C              J19   -150        A01X+110487Y+077356X0205Y0590R090 S1      
327N/C              J19   -220        A01X+110487Y+102789X0205Y0590R090 S1      
327N/C              J30   -2          A01X+014487Y+076018X0205Y0590R090 S1      
327N/C              J30   -144        A01X+014487Y+125545X0205Y0590R090 S1      
327N/C              J30   -149        A01X+012872Y+077022X0205Y0590R090 S1      
327N/C              J30   -150        A01X+012872Y+077356X0205Y0590R090 S1      
327N/C              J30   -220        A01X+012872Y+102790X0205Y0590R090 S1      
327N/C              J21   -2          A01X+109131Y+076018X0205Y0590R090 S1      
327N/C              J21   -144        A01X+109131Y+125545X0205Y0590R090 S1      
327N/C              J21   -149        A01X+107517Y+077022X0205Y0590R090 S1      
327N/C              J21   -150        A01X+107517Y+077356X0205Y0590R090 S1      
327N/C              J21   -220        A01X+107517Y+102789X0205Y0590R090 S1      
327N/C              J32   -2          A01X+011517Y+076018X0205Y0590R090 S1      
327N/C              J32   -144        A01X+011517Y+125545X0205Y0590R090 S1      
327N/C              J32   -149        A01X+009902Y+077022X0205Y0590R090 S1      
327N/C              J32   -150        A01X+009902Y+077356X0205Y0590R090 S1      
327N/C              J32   -220        A01X+009902Y+102790X0205Y0590R090 S1      
327N/C              J23   -2          A01X+106161Y+076018X0205Y0590R090 S1      
327N/C              J23   -144        A01X+106161Y+125545X0205Y0590R090 S1      
327N/C              J23   -149        A01X+104546Y+077022X0205Y0590R090 S1      
327N/C              J23   -150        A01X+104546Y+077356X0205Y0590R090 S1      
327N/C              J23   -220        A01X+104546Y+102789X0205Y0590R090 S1      
327N/C              J33   -2          A01X+008546Y+076018X0205Y0590R090 S1      
327N/C              J33   -144        A01X+008546Y+125545X0205Y0590R090 S1      
327N/C              J33   -149        A01X+006932Y+077022X0205Y0590R090 S1      
327N/C              J33   -150        A01X+006932Y+077356X0205Y0590R090 S1      
327N/C              J33   -220        A01X+006932Y+102790X0205Y0590R090 S1      
327N/C              J16   -2          A01X+163964Y+076018X0205Y0590R090 S1      
327N/C              J16   -144        A01X+163964Y+125545X0205Y0590R090 S1      
327N/C              J16   -149        A01X+162350Y+077022X0205Y0590R090 S1      
327N/C              J16   -150        A01X+162350Y+077356X0205Y0590R090 S1      
327N/C              J16   -220        A01X+162350Y+102789X0205Y0590R090 S1      
327N/C              J16   -231        A01X+162350Y+106470X0205Y0590R090 S1      
327N/C              J16   -232        A01X+162350Y+106805X0205Y0590R090 S1      
327N/C              J102  -2          A01X+066350Y+076018X0205Y0590R090 S1      
327N/C              J102  -144        A01X+066350Y+125545X0205Y0590R090 S1      
327N/C              J102  -149        A01X+064735Y+077022X0205Y0590R090 S1      
327N/C              J102  -150        A01X+064735Y+077356X0205Y0590R090 S1      
327N/C              J102  -220        A01X+064735Y+102790X0205Y0590R090 S1      
327N/C              J102  -231        A01X+064735Y+106471X0205Y0590R090 S1      
327N/C              J102  -232        A01X+064735Y+106805X0205Y0590R090 S1      
327N/C              J69   -2          A01X+166934Y+076018X0205Y0590R090 S1      
327N/C              J69   -144        A01X+166934Y+125545X0205Y0590R090 S1      
327N/C              J69   -149        A01X+165320Y+077022X0205Y0590R090 S1      
327N/C              J69   -150        A01X+165320Y+077356X0205Y0590R090 S1      
327N/C              J69   -220        A01X+165320Y+102789X0205Y0590R090 S1      
327N/C              J27   -2          A01X+069320Y+076018X0205Y0590R090 S1      
327N/C              J27   -144        A01X+069320Y+125545X0205Y0590R090 S1      
327N/C              J27   -149        A01X+067706Y+077022X0205Y0590R090 S1      
327N/C              J27   -150        A01X+067706Y+077356X0205Y0590R090 S1      
327N/C              J27   -220        A01X+067706Y+102790X0205Y0590R090 S1      
327N/C              J18   -2          A01X+169904Y+076018X0205Y0590R090 S1      
327N/C              J18   -144        A01X+169904Y+125545X0205Y0590R090 S1      
327N/C              J18   -149        A01X+168290Y+077022X0205Y0590R090 S1      
327N/C              J18   -150        A01X+168290Y+077356X0205Y0590R090 S1      
327N/C              J18   -220        A01X+168290Y+102789X0205Y0590R090 S1      
327N/C              J100  -2          A01X+072290Y+076018X0205Y0590R090 S1      
327N/C              J100  -144        A01X+072290Y+125545X0205Y0590R090 S1      
327N/C              J100  -149        A01X+070676Y+077022X0205Y0590R090 S1      
327N/C              J100  -150        A01X+070676Y+077356X0205Y0590R090 S1      
327N/C              J100  -220        A01X+070676Y+102790X0205Y0590R090 S1      
327N/C              J68   -2          A01X+172874Y+076018X0205Y0590R090 S1      
327N/C              J68   -144        A01X+172874Y+125545X0205Y0590R090 S1      
327N/C              J68   -149        A01X+171260Y+077022X0205Y0590R090 S1      
327N/C              J68   -150        A01X+171260Y+077356X0205Y0590R090 S1      
327N/C              J68   -220        A01X+171260Y+102789X0205Y0590R090 S1      
327N/C              J29   -2          A01X+075260Y+076018X0205Y0590R090 S1      
327N/C              J29   -144        A01X+075260Y+125545X0205Y0590R090 S1      
327N/C              J29   -149        A01X+073646Y+077022X0205Y0590R090 S1      
327N/C              J29   -150        A01X+073646Y+077356X0205Y0590R090 S1      
327N/C              J29   -220        A01X+073646Y+102790X0205Y0590R090 S1      
327N/C              J20   -2          A01X+175844Y+076018X0205Y0590R090 S1      
327N/C              J20   -144        A01X+175844Y+125545X0205Y0590R090 S1      
327N/C              J20   -149        A01X+174230Y+077022X0205Y0590R090 S1      
327N/C              J20   -150        A01X+174230Y+077356X0205Y0590R090 S1      
327N/C              J20   -220        A01X+174230Y+102789X0205Y0590R090 S1      
327N/C              J99   -2          A01X+078230Y+076018X0205Y0590R090 S1      
327N/C              J99   -144        A01X+078230Y+125545X0205Y0590R090 S1      
327N/C              J99   -149        A01X+076616Y+077022X0205Y0590R090 S1      
327N/C              J99   -150        A01X+076616Y+077356X0205Y0590R090 S1      
327N/C              J99   -220        A01X+076616Y+102790X0205Y0590R090 S1      
327N/C              J67   -2          A01X+178814Y+076018X0205Y0590R090 S1      
327N/C              J67   -144        A01X+178814Y+125545X0205Y0590R090 S1      
327N/C              J67   -149        A01X+177200Y+077022X0205Y0590R090 S1      
327N/C              J67   -150        A01X+177200Y+077356X0205Y0590R090 S1      
327N/C              J67   -220        A01X+177200Y+102789X0205Y0590R090 S1      
327N/C              J37   -2          A01X+081200Y+076018X0205Y0590R090 S1      
327N/C              J37   -144        A01X+081200Y+125545X0205Y0590R090 S1      
327N/C              J37   -149        A01X+079586Y+077022X0205Y0590R090 S1      
327N/C              J37   -150        A01X+079586Y+077356X0205Y0590R090 S1      
327N/C              J37   -220        A01X+079586Y+102790X0205Y0590R090 S1      
317N/C              PJ38  -H2   D0300UA00X+076689Y+153026X0300Y    R090 S3      
317N/C              PJ38  -H1   D0300UA00X+076689Y+148676X0300Y    R090 S3      
327N/C              BATTER-1          A01X+010094Y-007655X0300Y    R270 S1      
327N/C              J90_CO-1          A01X+021494Y-007655X0300Y    R270 S1      
327N/C                    -           A01X+002071Y+013975X0390Y    R180 S1      
327N/C              U99   -1          A01X+123691Y+009795X0220Y0530R270 S1      
327N/C              U124  -1          A01X+166861Y+022834X0220Y0530R270 S1      
327N/C              U101  -1          A18X+159725Y+135925X0220Y0530R090 S2      
327N/C              U92   -1          A01X+059485Y+043969X0220Y0530R270 S1      
327N/C              U86   -1          A01X+136811Y+011620X0220Y0530R180 S1      
327N/C              U82   -1          A18X+159725Y+134477X0220Y0530R090 S2      
327N/C              U3    -1          A18X+158918Y+080099X0220Y0530R090 S2      
317N/C              J59   -H1   D0460UA00X+067651Y+022461X0460Y    R270 S3      
317N/C              J59   -H2   D0650UA00X+067651Y+014587X0650Y    R270 S3      
317N/C              J90   -H1   D0440UA00X+092933Y+016041X0440Y    R090 S3      
317N/C              J90   -H2   D0440UA00X+092244Y+023770X0440Y    R090 S3      
327N/C              J54   -20         A01X+154562Y+025425X0340Y0960R090 S1      
327N/C              J54   -14         A01X+154562Y+023925X0340Y0960R090 S1      
317N/C              J41   -H1   D0440UA00X+075780Y+004508X0440Y    R180 S3      
317N/C              J41   -H2   D0440UA00X+050518Y+004114X0440Y    R180 S3      
317N/C              J38   -H1   D0440UA00X+178733Y+002429X0440Y    R180 S3      
317N/C              J38   -H2   D0440UA00X+153471Y+002035X0440Y    R180 S3      
317N/C              J35   -H1   D0440UA00X+031292Y+002429X0440Y    R180 S3      
317N/C              J35   -H2   D0440UA00X+006030Y+002035X0440Y    R180 S3      
317N/C              J57   -5    D0460PA00X+056902Y+027427X0660Y    R180 S3      
317N/C              J57   -4    D0460PA00X+057902Y+027427X0660Y    R180 S3      
317N/C              J6    -5    D0440PA00X+119386Y+020720X0640Y    R090 S3      
317N/C              J13   -H1   D0450UA00X+145480Y+008034X0450Y    R180 S3      
317N/C              JP4003-1    D0410PA00X+108097Y+166096X0610Y0610     S3      
327N/C              U192  -5          A18X+069319Y+164341X0140Y0560R090 S2      
327N/C              D1    -2          A01X+167551Y+021393X0320Y0360R090 S1      
327N/C              U308  -4          A01X+109293Y+170376X0170Y0240R180 S1      
327N/C              U308  -3          A01X+109293Y+171124X0170Y0240R180 S1      
327N/C              U39   -19         A01X+105108Y+047060X0120Y0630R270 S1      
327N/C              U39   -20         A01X+105108Y+047316X0120Y0630R270 S1      
327N/C              U36   -19         A01X+114066Y+047060X0120Y0630R270 S1      
327N/C              U36   -20         A01X+114066Y+047316X0120Y0630R270 S1      
327N/C              U200  -5          A01X+010258Y+172612X0140Y0560R090 S1      
327N/C              U194  -5          A01X+012011Y+169883X0140Y0560R270 S1      
327N/C              U175  -5          A01X+064656Y+170973X0140Y0560     S1      
327N/C              U176  -5          A01X+114647Y+167473X0140Y0560R270 S1      
317N/C              J8    -H1   D0450UA00X+122553Y+006747X0450Y         S3      
327N/C              U44   -1          A01X+093879Y+026722X0140Y0490R270 S1      
317N/C              H127  -1    D3940UA00X+011793Y+060538X3940Y         S3      
317N/C              H126  -1    D3940UA00X+076360Y+060541X3940Y         S3      
317N/C              H125  -1    D3940UA00X+109408Y+060538X3940Y         S3      
317N/C              H124  -1    D3940UA00X+173974Y+060541X3940Y         S3      
317N/C              H75   -1    D1260UA00X+036844Y+018524X2520Y3150R090 S3      
317N/C              H74   -1    D1260UA00X+025033Y+018524X2520Y3150R090 S3      
317N/C              H30   -1    D1250UA00X+003182Y+142426X1250Y         S3      
317N/C              H29   -1    D1250UA00X+180045Y+012619X1250Y         S3      
317N/C              H28   -1    D1250UA00X+004400Y+015420X1250Y         S3      
317N/C              H27   -1    D1250UA00X+180465Y+166729X1250Y         S3      
317N/C              H115  -1    D2000UA00X+092874Y+032165X2000Y2550R090 S3      
317N/C              H114  -1    D2170UA00X+105766Y+020472X2170Y         S3      
317N/C              H113  -1    D2170UA00X+080569Y+020472X2170Y         S3      
317N/C              J123  -SCR_ D1250UA00X+044104Y+169827X2560Y2560R180 S3      
317N/C              J123  -H1   D1250UA00X+044104Y+171846X1250Y    R180 S3      
317N/C              J123  -H2   D1250UA00X+044104Y+167220X1250Y    R180 S3      
317N/C              J122  -SCR_ D1250UA00X+141644Y+169827X2560Y2560R180 S3      
317N/C              J122  -H1   D1250UA00X+141644Y+171846X1250Y    R180 S3      
317N/C              J122  -H2   D1250UA00X+141644Y+167220X1250Y    R180 S3      
327N/C              U207  -1          A01X+033434Y+017861X0140Y0490     S1      
327N/C              U75   -1          A01X+082159Y+049161X0140Y0490R090 S1      
327N/C              U26_SR-1          A01X+012374Y-007655X0300Y    R270 S1      
327N/C              U26_BP-1          A01X+013514Y-007655X0300Y    R270 S1      
327N/C              U25_SR-1          A01X+014654Y-007655X0300Y    R270 S1      
327N/C              U25_BP-1          A01X+015794Y-007655X0300Y    R270 S1      
327N/C              PJ38_N-1          A01X+016934Y-007655X0300Y    R270 S1      
327N/C              JP6001-1          A01X+019214Y-007655X0300Y    R270 S1      
327N/C              JP6000-1          A01X+018074Y-007655X0300Y    R270 S1      
327N/C              JP4003-1          A01X+020354Y-007655X0300Y    R270 S1      
327N/C              JP12_1-1          A01X+008954Y-007655X0300Y    R270 S1      
327N/C              Q6000 -4          A18X+120918Y+028695X0170Y0200R270 S2      
327N/C              Q6000 -5          A18X+120918Y+028951X0170Y0200R270 S2      
327N/C              Q6000 -3          A18X+121666Y+028695X0170Y0200R270 S2      
327N/C              U6001 -25         A01X+052399Y+016033X0070Y0520R180 S1      
327N/C              U6001 -11         A01X+053758Y+014832X0070Y0520R270 S1      
327N/C              U6001 -12         A01X+053758Y+014990X0070Y0520R270 S1      
327N/C              U6001 -15         A01X+053758Y+015462X0070Y0520R270 S1      
327N/C              U6001 -14         A01X+053758Y+015304X0070Y0520R270 S1      
327N/C              U6001 -67         A01X+053344Y+013001X0070Y0520R180 S1      
327N/C              U6001 -68         A01X+053502Y+012942X0070Y0400R180 S1      
327N/C              U6001 -38         A01X+050726Y+015304X0070Y0520R270 S1      
327N/C              U6001 -39         A01X+050726Y+015147X0070Y0520R270 S1      
327N/C              U6001 -35         A01X+050667Y+015777X0070Y0400R270 S1      
327N/C              U6001 -36         A01X+050726Y+015620X0070Y0520R270 S1      
327N/C              U6001 -65         A01X+053029Y+013001X0070Y0520R180 S1      
327N/C              U6001 -64         A01X+052872Y+013001X0070Y0520R180 S1      
327N/C              U6001 -41         A01X+050726Y+014832X0070Y0520R270 S1      
327N/C              U6001 -42         A01X+050726Y+014675X0070Y0520R270 S1      
327N/C              U6001 -45         A01X+050726Y+014202X0070Y0520R270 S1      
327N/C              U6001 -44         A01X+050726Y+014360X0070Y0520R270 S1      
327N/C              U6001 -62         A01X+052557Y+013001X0070Y0520R180 S1      
327N/C              U6001 -63         A01X+052714Y+013001X0070Y0520R180 S1      
327N/C              LBL_1 -1          A01X+011234Y-007655X0300Y    R270 S1      
327N/C              U6002 -26         A01X+046141Y+012696X0094Y0236R090 S1      
327N/C              U6002 -19         A01X+046141Y+011318X0094Y0236R090 S1      
327N/C              U6002 -3          A01X+043326Y+010668X0094Y0236     S1      
327N/C              U6002 -27         A01X+046141Y+012893X0094Y0236R090 S1      
327N/C              U6002 -20         A01X+046141Y+011515X0094Y0236R090 S1      
327N/C              U6002 -4          A01X+043523Y+010668X0094Y0236     S1      
327N/C              U6002 -29         A01X+046141Y+013286X0094Y0236R090 S1      
327N/C              U6002 -22         A01X+046141Y+011909X0094Y0236R090 S1      
327N/C              U6002 -7          A01X+044114Y+010668X0094Y0236     S1      
327N/C              U6002 -24         A01X+046141Y+012302X0094Y0236R090 S1      
327N/C              U6002 -25         A01X+046141Y+012499X0094Y0236R090 S1      
327N/C              U6002 -2          A01X+043130Y+010668X0094Y0236     S1      
327N/C              U6002 -32         A01X+046141Y+013877X0094Y0236R090 S1      
327N/C              U6002 -36         A01X+045295Y+014133X0094Y0236     S1      
327N/C              U21   -2          A01X+067297Y+167902X0350Y0500R180 S1      
327N/C              U21   -1          A01X+067797Y+167902X0350Y0500R180 S1      
327N/C              U20   -2          A01X+064928Y+167880X0350Y0500R180 S1      
327N/C              U20   -1          A01X+065428Y+167880X0350Y0500R180 S1      
327N/C              U19   -2          A01X+043537Y+159028X0350Y0500R180 S1      
327N/C              U19   -1          A01X+044037Y+159028X0350Y0500R180 S1      
327N/C              U17   -2          A18X+148258Y+167385X0350Y0500R090 S2      
327N/C              U17   -1          A18X+148258Y+167885X0350Y0500R090 S2      
327N/C              U16   -2          A01X+166110Y+169640X0350Y0500R180 S1      
327N/C              U16   -1          A01X+166610Y+169640X0350Y0500R180 S1      
327N/C              U15   -2          A01X+113307Y+158945X0350Y0500R270 S1      
327N/C              U15   -1          A01X+113307Y+159445X0350Y0500R270 S1      
327N/C              U12   -2          A01X+041038Y+159028X0350Y0500R180 S1      
327N/C              U12   -1          A01X+041538Y+159028X0350Y0500R180 S1      
327N/C              U11   -2          A01X+117919Y+168263X0350Y0500R180 S1      
327N/C              U11   -1          A01X+118419Y+168263X0350Y0500R180 S1      
327N/C              U8005 -3          A18X+074000Y+164434X0240Y0420R180 S2      
327N/C              U8009 -3          A01X+055200Y+043484X0240Y0420R180 S1      
327N/C              U8007 -3          A01X+049200Y+041334X0240Y0420R180 S1      
327N/C              LBL_2 -1          A18X+166590Y+194982X0300Y         S2      
327N/C              U34   -1          A01X+032618Y+027774X0220Y0530R270 S1      
327N/C              U33   -1          A01X+037268Y+031124X0220Y0530R270 S1      
327N/C              U30   -1          A01X+065526Y+037068X0220Y0530     S1      
327N/C              U28   -1          A01X+078790Y+038493X0220Y0530R270 S1      
327N/C              U60   -2          A01X+018427Y+040006X0240Y0320     S1      
327N/C              U57   -2          A01X+015749Y+040060X0240Y0320     S1      
C                                                                               
C  ****************************************                                     
C      TOOLING HOLE PINS ON THE BOARD                                           
C  ****************************************                                     
C                                                                               
367                       -     D0410UA00X+172172Y-002921X0410Y    R090 S3      
367                       -     D0410UA00X+172172Y-003921X0410Y    R090 S3      
367                       -     D0410UA00X+174672Y-002921X0410Y    R090 S3      
367                       -     D0410UA00X+174672Y-003921X0410Y    R090 S3      
367                       -     D0410UA00X+172172Y-002921X0410Y    R090 S3      
367                       -     D0410UA00X+172172Y-001921X0410Y    R090 S3      
367                       -     D0410UA00X+174672Y-002921X0410Y    R090 S3      
367                       -     D0410UA00X+174672Y-001921X0410Y    R090 S3      
367                       -     D0410UA00X+154697Y-003921X0410Y    R270 S3      
367                       -     D0410UA00X+154697Y-002921X0410Y    R270 S3      
367                       -     D0410UA00X+152197Y-003921X0410Y    R270 S3      
367                       -     D0410UA00X+152197Y-002921X0410Y    R270 S3      
367                       -     D0410UA00X+154697Y-001921X0410Y    R270 S3      
367                       -     D0410UA00X+154697Y-002921X0410Y    R270 S3      
367                       -     D0410UA00X+152197Y-001921X0410Y    R270 S3      
367                       -     D0410UA00X+152197Y-002921X0410Y    R270 S3      
367                       -     D0410UA00X+142843Y+001499X0410Y    R090 S3      
367                       -     D0410UA00X+142843Y+000499X0410Y    R090 S3      
367                       -     D0410UA00X+145343Y+001499X0410Y    R090 S3      
367                       -     D0410UA00X+145343Y+000499X0410Y    R090 S3      
367                       -     D0410UA00X+142843Y+001499X0410Y    R090 S3      
367                       -     D0410UA00X+142843Y+002499X0410Y    R090 S3      
367                       -     D0410UA00X+145343Y+001499X0410Y    R090 S3      
367                       -     D0410UA00X+145343Y+002499X0410Y    R090 S3      
367                       -     D0410UA00X+142843Y-000501X0410Y    R090 S3      
367                       -     D0410UA00X+142843Y+000499X0410Y    R090 S3      
367                       -     D0410UA00X+145343Y-000501X0410Y    R090 S3      
367                       -     D0410UA00X+145343Y+000499X0410Y    R090 S3      
367                       -     D0410UA00X+142843Y-000501X0410Y    R090 S3      
367                       -     D0410UA00X+142843Y-001501X0410Y    R090 S3      
367                       -     D0410UA00X+145343Y-000501X0410Y    R090 S3      
367                       -     D0410UA00X+145343Y-001501X0410Y    R090 S3      
367                       -     D0410UA00X+142843Y-002501X0410Y    R090 S3      
367                       -     D0410UA00X+142843Y-003501X0410Y    R090 S3      
367                       -     D0410UA00X+145343Y-002501X0410Y    R090 S3      
367                       -     D0410UA00X+145343Y-003501X0410Y    R090 S3      
367                       -     D0410UA00X+142843Y-002501X0410Y    R090 S3      
367                       -     D0410UA00X+142843Y-001501X0410Y    R090 S3      
367                       -     D0410UA00X+145343Y-002501X0410Y    R090 S3      
367                       -     D0410UA00X+145343Y-001501X0410Y    R090 S3      
367                       -     D0410UA00X+125367Y+000499X0410Y    R270 S3      
367                       -     D0410UA00X+125367Y+001499X0410Y    R270 S3      
367                       -     D0410UA00X+122867Y+000499X0410Y    R270 S3      
367                       -     D0410UA00X+122867Y+001499X0410Y    R270 S3      
367                       -     D0410UA00X+125367Y+002499X0410Y    R270 S3      
367                       -     D0410UA00X+125367Y+001499X0410Y    R270 S3      
367                       -     D0410UA00X+122867Y+002499X0410Y    R270 S3      
367                       -     D0410UA00X+122867Y+001499X0410Y    R270 S3      
367                       -     D0410UA00X+125367Y+000499X0410Y    R270 S3      
367                       -     D0410UA00X+125367Y-000501X0410Y    R270 S3      
367                       -     D0410UA00X+122867Y+000499X0410Y    R270 S3      
367                       -     D0410UA00X+122867Y-000501X0410Y    R270 S3      
367                       -     D0410UA00X+125367Y-001501X0410Y    R270 S3      
367                       -     D0410UA00X+125367Y-000501X0410Y    R270 S3      
367                       -     D0410UA00X+122867Y-001501X0410Y    R270 S3      
367                       -     D0410UA00X+122867Y-000501X0410Y    R270 S3      
367                       -     D0410UA00X+125367Y-003501X0410Y    R270 S3      
367                       -     D0410UA00X+125367Y-002501X0410Y    R270 S3      
367                       -     D0410UA00X+122867Y-003501X0410Y    R270 S3      
367                       -     D0410UA00X+122867Y-002501X0410Y    R270 S3      
367                       -     D0410UA00X+125367Y-001501X0410Y    R270 S3      
367                       -     D0410UA00X+125367Y-002501X0410Y    R270 S3      
367                       -     D0410UA00X+122867Y-001501X0410Y    R270 S3      
367                       -     D0410UA00X+122867Y-002501X0410Y    R270 S3      
367                       -     D0410UA00X+116957Y+001499X0410Y    R090 S3      
367                       -     D0410UA00X+116957Y+000499X0410Y    R090 S3      
367                       -     D0410UA00X+119457Y+001499X0410Y    R090 S3      
367                       -     D0410UA00X+119457Y+000499X0410Y    R090 S3      
367                       -     D0410UA00X+116957Y+001499X0410Y    R090 S3      
367                       -     D0410UA00X+116957Y+002499X0410Y    R090 S3      
367                       -     D0410UA00X+119457Y+001499X0410Y    R090 S3      
367                       -     D0410UA00X+119457Y+002499X0410Y    R090 S3      
367                       -     D0410UA00X+116957Y-000501X0410Y    R090 S3      
367                       -     D0410UA00X+116957Y+000499X0410Y    R090 S3      
367                       -     D0410UA00X+119457Y-000501X0410Y    R090 S3      
367                       -     D0410UA00X+119457Y+000499X0410Y    R090 S3      
367                       -     D0410UA00X+116957Y-000501X0410Y    R090 S3      
367                       -     D0410UA00X+116957Y-001501X0410Y    R090 S3      
367                       -     D0410UA00X+119457Y-000501X0410Y    R090 S3      
367                       -     D0410UA00X+119457Y-001501X0410Y    R090 S3      
367                       -     D0410UA00X+116957Y-002501X0410Y    R090 S3      
367                       -     D0410UA00X+116957Y-003501X0410Y    R090 S3      
367                       -     D0410UA00X+119457Y-002501X0410Y    R090 S3      
367                       -     D0410UA00X+119457Y-003501X0410Y    R090 S3      
367                       -     D0410UA00X+116957Y-002501X0410Y    R090 S3      
367                       -     D0410UA00X+116957Y-001501X0410Y    R090 S3      
367                       -     D0410UA00X+119457Y-002501X0410Y    R090 S3      
367                       -     D0410UA00X+119457Y-001501X0410Y    R090 S3      
367                       -     D0410UA00X+085015Y+000499X0410Y    R270 S3      
367                       -     D0410UA00X+085015Y+001499X0410Y    R270 S3      
367                       -     D0410UA00X+082515Y+000499X0410Y    R270 S3      
367                       -     D0410UA00X+082515Y+001499X0410Y    R270 S3      
367                       -     D0410UA00X+085015Y+002499X0410Y    R270 S3      
367                       -     D0410UA00X+085015Y+001499X0410Y    R270 S3      
367                       -     D0410UA00X+082515Y+002499X0410Y    R270 S3      
367                       -     D0410UA00X+082515Y+001499X0410Y    R270 S3      
367                       -     D0410UA00X+085015Y+000499X0410Y    R270 S3      
367                       -     D0410UA00X+085015Y-000501X0410Y    R270 S3      
367                       -     D0410UA00X+082515Y+000499X0410Y    R270 S3      
367                       -     D0410UA00X+082515Y-000501X0410Y    R270 S3      
367                       -     D0410UA00X+085015Y-001501X0410Y    R270 S3      
367                       -     D0410UA00X+085015Y-000501X0410Y    R270 S3      
367                       -     D0410UA00X+082515Y-001501X0410Y    R270 S3      
367                       -     D0410UA00X+082515Y-000501X0410Y    R270 S3      
367                       -     D0410UA00X+085015Y-003501X0410Y    R270 S3      
367                       -     D0410UA00X+085015Y-002501X0410Y    R270 S3      
367                       -     D0410UA00X+082515Y-003501X0410Y    R270 S3      
367                       -     D0410UA00X+082515Y-002501X0410Y    R270 S3      
367                       -     D0410UA00X+085015Y-001501X0410Y    R270 S3      
367                       -     D0410UA00X+085015Y-002501X0410Y    R270 S3      
367                       -     D0410UA00X+082515Y-001501X0410Y    R270 S3      
367                       -     D0410UA00X+082515Y-002501X0410Y    R270 S3      
367                       -     D0410UA00X+071809Y-000887X0410Y    R090 S3      
367                       -     D0410UA00X+071809Y-001887X0410Y    R090 S3      
367                       -     D0410UA00X+074309Y-000887X0410Y    R090 S3      
367                       -     D0410UA00X+074309Y-001887X0410Y    R090 S3      
367                       -     D0410UA00X+071809Y-002887X0410Y    R090 S3      
367                       -     D0410UA00X+071809Y-001887X0410Y    R090 S3      
367                       -     D0410UA00X+074309Y-002887X0410Y    R090 S3      
367                       -     D0410UA00X+074309Y-001887X0410Y    R090 S3      
367                       -     D0410UA00X+039867Y-001887X0410Y    R270 S3      
367                       -     D0410UA00X+039867Y-000887X0410Y    R270 S3      
367                       -     D0410UA00X+037367Y-001887X0410Y    R270 S3      
367                       -     D0410UA00X+037367Y-000887X0410Y    R270 S3      
367                       -     D0410UA00X+039867Y-001887X0410Y    R270 S3      
367                       -     D0410UA00X+039867Y-002887X0410Y    R270 S3      
367                       -     D0410UA00X+037367Y-001887X0410Y    R270 S3      
367                       -     D0410UA00X+037367Y-002887X0410Y    R270 S3      
C                                                                               
C  End-of-Job                                                                   
C                                                                               
999                                                                             
